(kicad_pcb
	(version 20260206)
	(generator "pcbnew")
	(generator_version "10.0")
	(general
		(thickness 1.21888)
		(legacy_teardrops no)
	)
	(paper "A4")
	(layers
		(0 "F.Cu" signal "TOP")
		(4 "In1.Cu" signal "SGND")
		(6 "In2.Cu" signal "IN1")
		(8 "In3.Cu" signal "IN2")
		(10 "In4.Cu" signal "SGND1")
		(2 "B.Cu" signal "BOTTOM")
		(9 "F.Adhes" user "F.Adhesive")
		(11 "B.Adhes" user "B.Adhesive")
		(13 "F.Paste" user "Top Paste")
		(15 "B.Paste" user "Bottom Paste")
		(5 "F.SilkS" user "Top Overlay")
		(7 "B.SilkS" user "Bottom Overlay")
		(1 "F.Mask" user "Top Solder")
		(3 "B.Mask" user "Bottom Solder")
		(17 "Dwgs.User" user "User.Drawings")
		(19 "Cmts.User" user "User.Comments")
		(21 "Eco1.User" user "User.Eco1")
		(23 "Eco2.User" user "User.Eco2")
		(25 "Edge.Cuts" user)
		(27 "Margin" user)
		(31 "F.CrtYd" user "Top Courtyard")
		(29 "B.CrtYd" user "Bottom Courtyard")
		(35 "F.Fab" user "Top Component Center")
		(33 "B.Fab" user "Bottom Component Center")
	)
	(setup
		(pad_to_mask_clearance 0.1016)
		(allow_soldermask_bridges_in_footprints no)
		(tenting
			(front yes)
			(back yes)
		)
		(covering
			(front no)
			(back no)
		)
		(plugging
			(front no)
			(back no)
		)
		(capping no)
		(filling no)
		(aux_axis_origin -68.261405 262.2786)
		(grid_origin -68.261405 262.2786)
		(pcbplotparams
			(layerselection 0x00000000_00000000_55555555_5755f5ff)
			(plot_on_all_layers_selection 0x00000000_00000000_00000000_00000000)
			(disableapertmacros no)
			(usegerberextensions no)
			(usegerberattributes yes)
			(usegerberadvancedattributes yes)
			(creategerberjobfile yes)
			(dashed_line_dash_ratio 12)
			(dashed_line_gap_ratio 3)
			(svgprecision 4)
			(plotframeref no)
			(mode 1)
			(useauxorigin no)
			(pdf_front_fp_property_popups yes)
			(pdf_back_fp_property_popups yes)
			(pdf_metadata yes)
			(pdf_single_document no)
			(dxfpolygonmode yes)
			(dxfimperialunits yes)
			(dxfusepcbnewfont yes)
			(psnegative no)
			(psa4output no)
			(plot_black_and_white yes)
			(sketchpadsonfab no)
			(plotpadnumbers no)
			(hidednponfab no)
			(sketchdnponfab yes)
			(crossoutdnponfab yes)
			(subtractmaskfromsilk no)
			(outputformat 1)
			(mirror no)
			(drillshape 1)
			(scaleselection 1)
			(outputdirectory "")
		)
	)
	(footprint "Resistors:RESC1608X50N"
		(layer "F.Cu")
		(at 163.640595 66.5716 180)
		(property "Reference" "R27"
			(at -1.948 -0.400345 0)
			(unlocked yes)
			(layer "F.SilkS")
			(effects
				(font
					(size 0.762 0.762)
					(thickness 0.2286)
				)
				(justify left bottom)
			)
		)
		(property "Value" "ERJ-3EKF1002V"
			(at 0.4445 -3.72999 0)
			(unlocked yes)
			(layer "F.SilkS")
			(hide yes)
			(effects
				(font
					(size 1.524 1.524)
					(thickness 0.254)
				)
				(justify left bottom)
			)
		)
		(sheetname "UART")
		(sheetfile "UART.kicad_sch")
		(duplicate_pad_numbers_are_jumpers no)
		(fp_line
			(start 0 -0.5)
			(end 0 0.5)
			(stroke
				(width 0.1524)
				(type solid)
			)
			(layer "F.SilkS")
		)
		(pad "1" smd rect
			(at -0.69 0 270)
			(size 1 0.72)
			(layers "F.Cu" "F.Mask" "F.Paste")
			(net "NetC54_2")
		)
		(pad "2" smd rect
			(at 0.69 0 270)
			(size 1 0.72)
			(layers "F.Cu" "F.Mask" "F.Paste")
			(net "NetR27_2")
		)
	)
	(footprint "Vault:CAPC1608X87X45ML20T05"
		(layer "F.Cu")
		(at 227.648595 119.6576)
		(property "Reference" "C15"
			(at 1.74 0.414345 0)
			(unlocked yes)
			(layer "F.SilkS")
			(effects
				(font
					(size 0.762 0.762)
					(thickness 0.2286)
				)
				(justify left bottom)
			)
		)
		(property "Value" "0.1uF"
			(at -1.1811 5.63499 0)
			(unlocked yes)
			(layer "F.SilkS")
			(hide yes)
			(effects
				(font
					(size 1.524 1.524)
					(thickness 0.254)
				)
				(justify left bottom)
			)
		)
		(sheetname "POWER")
		(sheetfile "POWER.kicad_sch")
		(duplicate_pad_numbers_are_jumpers no)
		(pad "1" smd rect
			(at -0.7 0 90)
			(size 1.1 1.05)
			(layers "F.Cu" "F.Mask" "F.Paste")
			(net "GND")
		)
		(pad "2" smd rect
			(at 0.7 0 90)
			(size 1.1 1.05)
			(layers "F.Cu" "F.Mask" "F.Paste")
			(net "+5.0V")
		)
	)
	(footprint "Vault:TECO-1909763-1_V"
		(layer "F.Cu")
		(at 75.088595 110.9786 90)
		(property "Reference" "J5"
			(at -2.926921 2.028605 0)
			(unlocked yes)
			(layer "F.SilkS")
			(effects
				(font
					(size 0.762 0.762)
					(thickness 0.2286)
				)
			)
		)
		(property "Value" "1909763-1"
			(at 4.608085 3.749802 90)
			(unlocked yes)
			(layer "F.SilkS")
			(hide yes)
			(effects
				(font
					(size 1.524 1.524)
					(thickness 0.254)
				)
			)
		)
		(sheetname "USER_IO")
		(sheetfile "USER_IO.kicad_sch")
		(duplicate_pad_numbers_are_jumpers no)
		(fp_line
			(start -0.55 -1.3)
			(end 0.55 -1.3)
			(stroke
				(width 0.2)
				(type solid)
			)
			(layer "F.SilkS")
		)
		(fp_circle
			(center -1.778 1.65)
			(end -1.653 1.65)
			(stroke
				(width 0.25)
				(type solid)
			)
			(fill no)
			(layer "F.SilkS")
		)
		(pad "1" smd rect
			(at -1.475 0 90)
			(size 1.05 2.2)
			(layers "F.Cu" "F.Mask" "F.Paste")
			(net "GND")
		)
		(pad "2" smd rect
			(at 0 1.525 90)
			(size 1 1.05)
			(layers "F.Cu" "F.Mask" "F.Paste")
			(net "ANT2")
		)
		(pad "3" smd rect
			(at 1.475 0 90)
			(size 1.05 2.2)
			(layers "F.Cu" "F.Mask" "F.Paste")
			(net "GND")
		)
	)
	(footprint "Vault:CAPC1608X87X45ML20T05"
		(layer "F.Cu")
		(at 168.593595 82.8276 -90)
		(property "Reference" "C81"
			(at -3.799 -2.113345 90)
			(unlocked yes)
			(layer "F.SilkS")
			(effects
				(font
					(size 0.762 0.762)
					(thickness 0.2286)
				)
				(justify left bottom)
			)
		)
		(property "Value" "0.1uF"
			(at 3.47599 0.2921 0)
			(unlocked yes)
			(layer "F.SilkS")
			(hide yes)
			(effects
				(font
					(size 1.524 1.524)
					(thickness 0.254)
				)
				(justify left bottom)
			)
		)
		(sheetname "MAC")
		(sheetfile "MAC.kicad_sch")
		(duplicate_pad_numbers_are_jumpers no)
		(pad "1" smd rect
			(at -0.7 0)
			(size 1.1 1.05)
			(layers "F.Cu" "F.Mask" "F.Paste")
			(net "GND")
		)
		(pad "2" smd rect
			(at 0.7 0)
			(size 1.1 1.05)
			(layers "F.Cu" "F.Mask" "F.Paste")
			(net "+3.3V_CLEAN")
		)
	)
	(footprint "Vault:CAPC1608X87X45ML20T05"
		(layer "F.Cu")
		(at 170.117595 82.8276 -90)
		(property "Reference" "C82"
			(at -3.674 -1.839345 90)
			(unlocked yes)
			(layer "F.SilkS")
			(effects
				(font
					(size 0.762 0.762)
					(thickness 0.2286)
				)
				(justify left bottom)
			)
		)
		(property "Value" "0.1uF"
			(at 3.47599 0.2921 0)
			(unlocked yes)
			(layer "F.SilkS")
			(hide yes)
			(effects
				(font
					(size 1.524 1.524)
					(thickness 0.254)
				)
				(justify left bottom)
			)
		)
		(sheetname "MAC")
		(sheetfile "MAC.kicad_sch")
		(duplicate_pad_numbers_are_jumpers no)
		(pad "1" smd rect
			(at -0.7 0)
			(size 1.1 1.05)
			(layers "F.Cu" "F.Mask" "F.Paste")
			(net "GND")
		)
		(pad "2" smd rect
			(at 0.7 0)
			(size 1.1 1.05)
			(layers "F.Cu" "F.Mask" "F.Paste")
			(net "+3.3V_CLEAN")
		)
	)
	(footprint "IntegratedCircuits:SOP64P600X170-16N"
		(layer "F.Cu")
		(at 157.036595 64.7936)
		(property "Reference" "U6"
			(at -0.97759 4.347655 0)
			(unlocked yes)
			(layer "F.SilkS")
			(effects
				(font
					(size 0.762 0.762)
					(thickness 0.2286)
				)
				(justify left bottom)
			)
		)
		(property "Value" "FT230XS-R"
			(at -3.4671 5.25399 0)
			(unlocked yes)
			(layer "F.SilkS")
			(hide yes)
			(effects
				(font
					(size 1.524 1.524)
					(thickness 0.254)
				)
				(justify left bottom)
			)
		)
		(sheetname "UART")
		(sheetfile "UART.kicad_sch")
		(duplicate_pad_numbers_are_jumpers no)
		(fp_line
			(start -1.6 -2.5)
			(end 1.6 -2.5)
			(stroke
				(width 0.2)
				(type solid)
			)
			(layer "F.SilkS")
		)
		(fp_line
			(start -1.6 2.5)
			(end -1.6 -2.5)
			(stroke
				(width 0.2)
				(type solid)
			)
			(layer "F.SilkS")
		)
		(fp_line
			(start -1.6 2.5)
			(end 1.6 2.5)
			(stroke
				(width 0.2)
				(type solid)
			)
			(layer "F.SilkS")
		)
		(fp_line
			(start 1.6 2.5)
			(end 1.6 -2.5)
			(stroke
				(width 0.2)
				(type solid)
			)
			(layer "F.SilkS")
		)
		(fp_circle
			(center -2.725 -2.9975)
			(end -2.725 -3.1225)
			(stroke
				(width 0.25)
				(type solid)
			)
			(fill no)
			(layer "F.SilkS")
		)
		(fp_circle
			(center -0.6 -1.5)
			(end -0.6 -1.8)
			(stroke
				(width 0.6)
				(type solid)
			)
			(fill no)
			(layer "F.SilkS")
		)
		(pad "1" smd oval
			(at -2.725 -2.2225 90)
			(size 0.45 1.45)
			(layers "F.Cu" "F.Mask" "F.Paste")
			(net "UART1_RXD")
		)
		(pad "2" smd oval
			(at -2.725 -1.5875 90)
			(size 0.45 1.45)
			(layers "F.Cu" "F.Mask" "F.Paste")
		)
		(pad "3" smd oval
			(at -2.725 -0.9525 90)
			(size 0.45 1.45)
			(layers "F.Cu" "F.Mask" "F.Paste")
			(net "NetU6_3")
		)
		(pad "4" smd oval
			(at -2.725 -0.3175 90)
			(size 0.45 1.45)
			(layers "F.Cu" "F.Mask" "F.Paste")
			(net "UART1_TXD")
		)
		(pad "5" smd oval
			(at -2.725 0.3175 90)
			(size 0.45 1.45)
			(layers "F.Cu" "F.Mask" "F.Paste")
			(net "GND")
		)
		(pad "6" smd oval
			(at -2.725 0.9525 90)
			(size 0.45 1.45)
			(layers "F.Cu" "F.Mask" "F.Paste")
		)
		(pad "7" smd oval
			(at -2.725 1.5875 90)
			(size 0.45 1.45)
			(layers "F.Cu" "F.Mask" "F.Paste")
		)
		(pad "8" smd oval
			(at -2.725 2.2225 90)
			(size 0.45 1.45)
			(layers "F.Cu" "F.Mask" "F.Paste")
			(net "NetJ3_3")
		)
		(pad "9" smd oval
			(at 2.725 2.2225 90)
			(size 0.45 1.45)
			(layers "F.Cu" "F.Mask" "F.Paste")
			(net "NetJ3_2")
		)
		(pad "10" smd oval
			(at 2.725 1.5875 90)
			(size 0.45 1.45)
			(layers "F.Cu" "F.Mask" "F.Paste")
			(net "NetU6_3")
		)
		(pad "11" smd oval
			(at 2.725 0.9525 90)
			(size 0.45 1.45)
			(layers "F.Cu" "F.Mask" "F.Paste")
			(net "NetR27_2")
		)
		(pad "12" smd oval
			(at 2.725 0.3175 90)
			(size 0.45 1.45)
			(layers "F.Cu" "F.Mask" "F.Paste")
			(net "NetC54_2")
		)
		(pad "13" smd oval
			(at 2.725 -0.3175 90)
			(size 0.45 1.45)
			(layers "F.Cu" "F.Mask" "F.Paste")
			(net "GND")
		)
		(pad "14" smd oval
			(at 2.725 -0.9525 90)
			(size 0.45 1.45)
			(layers "F.Cu" "F.Mask" "F.Paste")
		)
		(pad "15" smd oval
			(at 2.725 -1.5875 90)
			(size 0.45 1.45)
			(layers "F.Cu" "F.Mask" "F.Paste")
		)
		(pad "16" smd oval
			(at 2.725 -2.2225 90)
			(size 0.45 1.45)
			(layers "F.Cu" "F.Mask" "F.Paste")
		)
	)
	(footprint "Vault:CAPC1608X87X45ML20T05"
		(layer "F.Cu")
		(at 143.788595 90.3786 90)
		(property "Reference" "C23"
			(at -2.5714 0.026931 90)
			(unlocked yes)
			(layer "F.SilkS")
			(effects
				(font
					(size 0.762 0.762)
					(thickness 0.2286)
				)
			)
		)
		(property "Value" "0.1uF"
			(at 2.09443 2.657602 90)
			(unlocked yes)
			(layer "F.SilkS")
			(hide yes)
			(effects
				(font
					(size 1.524 1.524)
					(thickness 0.254)
				)
			)
		)
		(sheetname "GPS_IMU_SENSORS")
		(sheetfile "GPS_IMU_SENSORS.kicad_sch")
		(duplicate_pad_numbers_are_jumpers no)
		(pad "1" smd rect
			(at -0.7 0 180)
			(size 1.1 1.05)
			(layers "F.Cu" "F.Mask" "F.Paste")
			(net "GND")
		)
		(pad "2" smd rect
			(at 0.7 0 180)
			(size 1.1 1.05)
			(layers "F.Cu" "F.Mask" "F.Paste")
			(net "+3.3V_CLEAN")
		)
	)
	(footprint "Connectors:USB_1734035"
		(layer "F.Cu")
		(at 158.423595 58.3766 180)
		(property "Reference" "J3"
			(at -4.62041 5.313545 0)
			(unlocked yes)
			(layer "F.SilkS")
			(effects
				(font
					(size 0.762 0.762)
					(thickness 0.2286)
				)
				(justify left bottom)
			)
		)
		(property "Value" "USB_B_1734035"
			(at 3.0545 -5.81979 0)
			(unlocked yes)
			(layer "F.SilkS")
			(hide yes)
			(effects
				(font
					(size 1.524 1.524)
					(thickness 0.254)
				)
				(justify left bottom)
			)
		)
		(sheetname "UART")
		(sheetfile "UART.kicad_sch")
		(duplicate_pad_numbers_are_jumpers no)
		(fp_line
			(start 6.35 1.905)
			(end 6.35 3.81)
			(stroke
				(width 0.1524)
				(type solid)
			)
			(layer "F.SilkS")
		)
		(fp_line
			(start -3.175 1.905)
			(end -3.175 3.81)
			(stroke
				(width 0.1524)
				(type solid)
			)
			(layer "F.SilkS")
		)
		(fp_text user "1"
			(at -1.27 -1.08331 180)
			(unlocked yes)
			(layer "F.SilkS")
			(effects
				(font
					(size 1.524 1.524)
					(thickness 0.254)
				)
				(justify left bottom)
			)
		)
		(pad "" np_thru_hole circle
			(at -0.6 2.6 180)
			(size 0.8 0.8)
			(drill 0.9)
			(layers "*.Cu" "*.Mask")
			(thermal_bridge_angle 90)
		)
		(pad "" np_thru_hole circle
			(at 3.8 2.6 180)
			(size 0.8 0.8)
			(drill 0.9)
			(layers "*.Cu" "*.Mask")
			(thermal_bridge_angle 90)
		)
		(pad "0" smd rect
			(at -2.85 0.1 180)
			(size 2 2.5)
			(layers "F.Cu" "F.Mask" "F.Paste")
		)
		(pad "0" smd rect
			(at -2.85 5.6 180)
			(size 2 2.5)
			(layers "F.Cu" "F.Mask" "F.Paste")
		)
		(pad "0" smd rect
			(at 6.05 0.1 180)
			(size 2 2.5)
			(layers "F.Cu" "F.Mask" "F.Paste")
		)
		(pad "0" smd rect
			(at 6.05 5.6 180)
			(size 2 2.5)
			(layers "F.Cu" "F.Mask" "F.Paste")
		)
		(pad "1" smd rect
			(at 0 0 180)
			(size 0.5 2.3)
			(layers "F.Cu" "F.Mask" "F.Paste")
			(net "NetC54_2")
		)
		(pad "2" smd rect
			(at 0.8 0 180)
			(size 0.5 2.3)
			(layers "F.Cu" "F.Mask" "F.Paste")
			(net "NetJ3_2")
		)
		(pad "3" smd rect
			(at 1.6 0 180)
			(size 0.5 2.3)
			(layers "F.Cu" "F.Mask" "F.Paste")
			(net "NetJ3_3")
		)
		(pad "4" smd rect
			(at 2.4 0 180)
			(size 0.5 2.3)
			(layers "F.Cu" "F.Mask" "F.Paste")
		)
		(pad "5" smd rect
			(at 3.2 0 180)
			(size 0.5 2.3)
			(layers "F.Cu" "F.Mask" "F.Paste")
			(net "GND")
		)
	)
	(footprint "Vault:CAPC1608X87X45ML20T05"
		(layer "F.Cu")
		(at 164.275595 82.8276 -90)
		(property "Reference" "C78"
			(at -3.224 1.693655 90)
			(unlocked yes)
			(layer "F.SilkS")
			(effects
				(font
					(size 0.762 0.762)
					(thickness 0.2286)
				)
				(justify left bottom)
			)
		)
		(property "Value" "0.1uF"
			(at 3.47599 0.2921 0)
			(unlocked yes)
			(layer "F.SilkS")
			(hide yes)
			(effects
				(font
					(size 1.524 1.524)
					(thickness 0.254)
				)
				(justify left bottom)
			)
		)
		(sheetname "MAC")
		(sheetfile "MAC.kicad_sch")
		(duplicate_pad_numbers_are_jumpers no)
		(pad "1" smd rect
			(at -0.7 0)
			(size 1.1 1.05)
			(layers "F.Cu" "F.Mask" "F.Paste")
			(net "GND")
		)
		(pad "2" smd rect
			(at 0.7 0)
			(size 1.1 1.05)
			(layers "F.Cu" "F.Mask" "F.Paste")
			(net "+3.3V_CLEAN")
		)
	)
	(footprint "Capacitors:CAPC2012X14N"
		(layer "F.Cu")
		(at 152.312195 80.4908 90)
		(property "Reference" "C65"
			(at -5.2878 0.469745 90)
			(unlocked yes)
			(layer "F.SilkS")
			(effects
				(font
					(size 0.762 0.762)
					(thickness 0.2286)
				)
				(justify left bottom)
			)
		)
		(property "Value" "CAP_0805_1UF_50V"
			(at -3.52679 -1.5875 0)
			(unlocked yes)
			(layer "F.SilkS")
			(hide yes)
			(effects
				(font
					(size 1.524 1.524)
					(thickness 0.254)
				)
				(justify left bottom)
			)
		)
		(sheetname "MAC")
		(sheetfile "MAC.kicad_sch")
		(duplicate_pad_numbers_are_jumpers no)
		(fp_line
			(start -0.762 -0.9652)
			(end 0.762 -0.9652)
			(stroke
				(width 0.1524)
				(type solid)
			)
			(layer "F.SilkS")
		)
		(fp_line
			(start -0.762 0.9652)
			(end 0.762 0.9652)
			(stroke
				(width 0.1524)
				(type solid)
			)
			(layer "F.SilkS")
		)
		(pad "1" smd rect
			(at -0.9 0 180)
			(size 1.45 1.15)
			(layers "F.Cu" "F.Mask" "F.Paste")
			(net "GND")
		)
		(pad "2" smd rect
			(at 0.9 0 180)
			(size 1.45 1.15)
			(layers "F.Cu" "F.Mask" "F.Paste")
			(net "+3.3V_CLEAN")
		)
	)
	(footprint "Vault:CAPC1608X87X45ML20T05"
		(layer "F.Cu")
		(at 219.588595 94.3786 180)
		(property "Reference" "C11"
			(at 4.1 0.606655 0)
			(unlocked yes)
			(layer "F.SilkS")
			(effects
				(font
					(size 0.762 0.762)
					(thickness 0.2286)
				)
				(justify left bottom)
			)
		)
		(property "Value" "0.1uF"
			(at -11.3919 -1.69799 0)
			(unlocked yes)
			(layer "F.SilkS")
			(hide yes)
			(effects
				(font
					(size 1.524 1.524)
					(thickness 0.254)
				)
				(justify left bottom)
			)
		)
		(sheetname "POWER")
		(sheetfile "POWER.kicad_sch")
		(duplicate_pad_numbers_are_jumpers no)
		(pad "1" smd rect
			(at -0.7 0 270)
			(size 1.1 1.05)
			(layers "F.Cu" "F.Mask" "F.Paste")
			(net "GND")
		)
		(pad "2" smd rect
			(at 0.7 0 270)
			(size 1.1 1.05)
			(layers "F.Cu" "F.Mask" "F.Paste")
			(net "+3.3V")
		)
	)
	(footprint "Resistors:RESC1608X50N"
		(layer "F.Cu")
		(at 210.988595 100.5786 -90)
		(property "Reference" "R9"
			(at -2.427 -0.395345 90)
			(unlocked yes)
			(layer "F.SilkS")
			(effects
				(font
					(size 0.762 0.762)
					(thickness 0.2286)
				)
				(justify left bottom)
			)
		)
		(property "Value" "ERJ-3EKF2201V"
			(at -8.25881 -27.9527 0)
			(unlocked yes)
			(layer "F.SilkS")
			(hide yes)
			(effects
				(font
					(size 1.524 1.524)
					(thickness 0.254)
				)
				(justify left bottom)
			)
		)
		(sheetname "POWER")
		(sheetfile "POWER.kicad_sch")
		(duplicate_pad_numbers_are_jumpers no)
		(fp_line
			(start 0 0.5)
			(end 0 -0.5)
			(stroke
				(width 0.1524)
				(type solid)
			)
			(layer "F.SilkS")
		)
		(pad "1" smd rect
			(at -0.69 0)
			(size 1 0.72)
			(layers "F.Cu" "F.Mask" "F.Paste")
			(net "GND")
		)
		(pad "2" smd rect
			(at 0.69 0)
			(size 1 0.72)
			(layers "F.Cu" "F.Mask" "F.Paste")
			(net "NetC22_1")
		)
	)
	(footprint "Passives:DIOM6959X26N"
		(layer "F.Cu")
		(at 85.027595 97.5596 180)
		(property "Reference" "D16"
			(at 4.1402 4.097655 0)
			(unlocked yes)
			(layer "F.SilkS")
			(effects
				(font
					(size 0.762 0.762)
					(thickness 0.2286)
				)
				(justify left bottom)
			)
		)
		(property "Value" "SMCJ6.5CA"
			(at 4.2545 -5.91439 0)
			(unlocked yes)
			(layer "F.SilkS")
			(hide yes)
			(effects
				(font
					(size 1.524 1.524)
					(thickness 0.254)
				)
				(justify left bottom)
			)
		)
		(sheetname "USER_IO")
		(sheetfile "USER_IO.kicad_sch")
		(duplicate_pad_numbers_are_jumpers no)
		(fp_line
			(start 3.6 3.15)
			(end -3.6 3.15)
			(stroke
				(width 0.2)
				(type solid)
			)
			(layer "F.SilkS")
		)
		(fp_line
			(start 3.6 1.975)
			(end 3.6 3.15)
			(stroke
				(width 0.2)
				(type solid)
			)
			(layer "F.SilkS")
		)
		(fp_line
			(start 3.6 -3.15)
			(end 3.6 -1.975)
			(stroke
				(width 0.2)
				(type solid)
			)
			(layer "F.SilkS")
		)
		(fp_line
			(start 3.6 -3.15)
			(end -3.6 -3.15)
			(stroke
				(width 0.2)
				(type solid)
			)
			(layer "F.SilkS")
		)
		(fp_line
			(start -3.6 1.975)
			(end -3.6 3.15)
			(stroke
				(width 0.2)
				(type solid)
			)
			(layer "F.SilkS")
		)
		(fp_line
			(start -3.6 -3.15)
			(end -3.6 -1.975)
			(stroke
				(width 0.2)
				(type solid)
			)
			(layer "F.SilkS")
		)
		(fp_circle
			(center -4.25 -2.125)
			(end -4.25 -2)
			(stroke
				(width 0.25)
				(type solid)
			)
			(fill no)
			(layer "F.SilkS")
		)
		(pad "A" smd rect
			(at 2.85 0 270)
			(size 3.15 2.45)
			(layers "F.Cu" "F.Mask" "F.Paste")
			(net "ANT1")
		)
		(pad "K" smd rect
			(at -2.85 0 270)
			(size 3.15 2.45)
			(layers "F.Cu" "F.Mask" "F.Paste")
			(net "GND")
		)
	)
	(footprint "Capacitors:CAPC2012X14N"
		(layer "F.Cu")
		(at 166.053595 89.0506 90)
		(property "Reference" "C73"
			(at 2.00709 0.740865 90)
			(unlocked yes)
			(layer "F.SilkS")
			(effects
				(font
					(size 0.762 0.762)
					(thickness 0.2286)
				)
				(justify left bottom)
			)
		)
		(property "Value" "CAP_0805_22UF_16V"
			(at -3.52679 -1.5875 0)
			(unlocked yes)
			(layer "F.SilkS")
			(hide yes)
			(effects
				(font
					(size 1.524 1.524)
					(thickness 0.254)
				)
				(justify left bottom)
			)
		)
		(sheetname "MAC")
		(sheetfile "MAC.kicad_sch")
		(duplicate_pad_numbers_are_jumpers no)
		(fp_line
			(start -0.762 -0.9652)
			(end 0.762 -0.9652)
			(stroke
				(width 0.1524)
				(type solid)
			)
			(layer "F.SilkS")
		)
		(fp_line
			(start -0.762 0.9652)
			(end 0.762 0.9652)
			(stroke
				(width 0.1524)
				(type solid)
			)
			(layer "F.SilkS")
		)
		(pad "1" smd rect
			(at -0.9 0 180)
			(size 1.45 1.15)
			(layers "F.Cu" "F.Mask" "F.Paste")
			(net "GND")
		)
		(pad "2" smd rect
			(at 0.9 0 180)
			(size 1.45 1.15)
			(layers "F.Cu" "F.Mask" "F.Paste")
			(net "NetC72_2")
		)
	)
	(footprint "Capacitors:CAPC2012X14N"
		(layer "F.Cu")
		(at 162.751595 63.9046 -90)
		(property "Reference" "C54"
			(at -2.926 -1.830345 90)
			(unlocked yes)
			(layer "F.SilkS")
			(effects
				(font
					(size 0.762 0.762)
					(thickness 0.2286)
				)
				(justify left bottom)
			)
		)
		(property "Value" "CAP_0805_1UF_25V"
			(at 3.52679 1.5875 0)
			(unlocked yes)
			(layer "F.SilkS")
			(hide yes)
			(effects
				(font
					(size 1.524 1.524)
					(thickness 0.254)
				)
				(justify left bottom)
			)
		)
		(sheetname "UART")
		(sheetfile "UART.kicad_sch")
		(duplicate_pad_numbers_are_jumpers no)
		(fp_line
			(start 0.762 0.9652)
			(end -0.762 0.9652)
			(stroke
				(width 0.1524)
				(type solid)
			)
			(layer "F.SilkS")
		)
		(fp_line
			(start 0.762 -0.9652)
			(end -0.762 -0.9652)
			(stroke
				(width 0.1524)
				(type solid)
			)
			(layer "F.SilkS")
		)
		(pad "1" smd rect
			(at -0.9 0)
			(size 1.45 1.15)
			(layers "F.Cu" "F.Mask" "F.Paste")
			(net "GND")
		)
		(pad "2" smd rect
			(at 0.9 0)
			(size 1.45 1.15)
			(layers "F.Cu" "F.Mask" "F.Paste")
			(net "NetC54_2")
		)
	)
	(footprint "Modules:RCB-F9T"
		(locked yes)
		(layer "F.Cu")
		(at 126.126095 91.5736 90)
		(property "Reference" "U9"
			(at 25.162655 -6.9605 0)
			(unlocked yes)
			(layer "F.SilkS")
			(effects
				(font
					(size 0.762 0.762)
					(thickness 0.2286)
				)
				(justify left bottom)
			)
		)
		(property "Value" "RCB-F9T"
			(at 6.55051 -25.6882 0)
			(unlocked yes)
			(layer "F.SilkS")
			(hide yes)
			(effects
				(font
					(size 1.524 1.524)
					(thickness 0.254)
				)
				(justify left bottom)
			)
		)
		(sheetname "GPS_IMU_SENSORS")
		(sheetfile "GPS_IMU_SENSORS.kicad_sch")
		(duplicate_pad_numbers_are_jumpers no)
		(fp_line
			(start 31.75 -67.18)
			(end 31.75 0)
			(stroke
				(width 0.254)
				(type solid)
			)
			(layer "F.SilkS")
		)
		(fp_line
			(start 0 -67.18)
			(end 31.75 -67.18)
			(stroke
				(width 0.254)
				(type solid)
			)
			(layer "F.SilkS")
		)
		(fp_line
			(start 0 -67.18)
			(end 0 0)
			(stroke
				(width 0.254)
				(type solid)
			)
			(layer "F.SilkS")
		)
		(fp_line
			(start 0 0)
			(end 31.75 0)
			(stroke
				(width 0.254)
				(type solid)
			)
			(layer "F.SilkS")
		)
		(fp_circle
			(center 28.875 -63.84)
			(end 30.425 -63.84)
			(stroke
				(width 0.254)
				(type solid)
			)
			(fill no)
			(layer "F.SilkS")
		)
		(fp_circle
			(center 2.875 -63.84)
			(end 4.425 -63.84)
			(stroke
				(width 0.254)
				(type solid)
			)
			(fill no)
			(layer "F.SilkS")
		)
		(fp_circle
			(center 28.875 -3.34)
			(end 30.425 -3.34)
			(stroke
				(width 0.254)
				(type solid)
			)
			(fill no)
			(layer "F.SilkS")
		)
		(fp_circle
			(center 2.875 -3.34)
			(end 4.425 -3.34)
			(stroke
				(width 0.254)
				(type solid)
			)
			(fill no)
			(layer "F.SilkS")
		)
		(pad "0" thru_hole circle
			(at 18.47 -6.11 90)
			(size 0 0)
			(drill 0.76)
			(layers "*.Cu" "*.Mask")
			(remove_unused_layers no)
			(thermal_bridge_angle 90)
		)
		(pad "0" thru_hole circle
			(at 22.47 -6.11 90)
			(size 0 0)
			(drill 0.76)
			(layers "*.Cu" "*.Mask")
			(remove_unused_layers no)
			(thermal_bridge_angle 90)
		)
		(pad "1" smd rect
			(at 23.47 -3.8875 90)
			(size 1.12 2.105)
			(layers "F.Cu" "F.Mask" "F.Paste")
			(net "+5.0V")
		)
		(pad "2" smd rect
			(at 23.47 -8.3325 90)
			(size 1.12 2.105)
			(layers "F.Cu" "F.Mask" "F.Paste")
			(net "+3.3V")
		)
		(pad "3" smd rect
			(at 21.47 -3.8875 90)
			(size 1.12 2.105)
			(layers "F.Cu" "F.Mask" "F.Paste")
			(net "GPS1_TX")
		)
		(pad "4" smd rect
			(at 21.47 -8.3325 90)
			(size 1.12 2.105)
			(layers "F.Cu" "F.Mask" "F.Paste")
			(net "GPS1_RST")
		)
		(pad "5" smd rect
			(at 19.47 -3.8875 90)
			(size 1.12 2.105)
			(layers "F.Cu" "F.Mask" "F.Paste")
			(net "GPS1_RX")
		)
		(pad "6" smd rect
			(at 19.47 -8.3325 90)
			(size 1.12 2.105)
			(layers "F.Cu" "F.Mask" "F.Paste")
			(net "GPS1_TP1")
		)
		(pad "7" smd rect
			(at 17.47 -3.8875 90)
			(size 1.12 2.105)
			(layers "F.Cu" "F.Mask" "F.Paste")
			(net "GPS1_TP2")
		)
		(pad "8" smd rect
			(at 17.47 -8.3325 90)
			(size 1.12 2.105)
			(layers "F.Cu" "F.Mask" "F.Paste")
			(net "GND")
		)
	)
	(footprint "Passives:FUSM1608X60N"
		(layer "F.Cu")
		(at 212.484795 70.2546 180)
		(property "Reference" "F1"
			(at 0.7962 0.882655 0)
			(unlocked yes)
			(layer "F.SilkS")
			(effects
				(font
					(size 0.762 0.762)
					(thickness 0.2286)
				)
				(justify left bottom)
			)
		)
		(property "Value" "FUSE_0603_2.00A"
			(at 2.8829 -4.39039 0)
			(unlocked yes)
			(layer "F.SilkS")
			(hide yes)
			(effects
				(font
					(size 1.524 1.524)
					(thickness 0.254)
				)
				(justify left bottom)
			)
		)
		(sheetname "POWER")
		(sheetfile "POWER.kicad_sch")
		(duplicate_pad_numbers_are_jumpers no)
		(fp_line
			(start 0 -0.5)
			(end 0 0.5)
			(stroke
				(width 0.1524)
				(type solid)
			)
			(layer "F.SilkS")
		)
		(pad "1" smd rect
			(at -0.69 0 270)
			(size 1 0.72)
			(layers "F.Cu" "F.Mask" "F.Paste")
			(net "NetD2_1")
		)
		(pad "2" smd rect
			(at 0.69 0 270)
			(size 1 0.72)
			(layers "F.Cu" "F.Mask" "F.Paste")
			(net "+12V")
		)
	)
	(footprint "Vault:CAPC1608X87X45ML20T05"
		(layer "F.Cu")
		(at 171.641595 82.8276 -90)
		(property "Reference" "C83"
			(at -2.649 -1.565345 90)
			(unlocked yes)
			(layer "F.SilkS")
			(effects
				(font
					(size 0.762 0.762)
					(thickness 0.2286)
				)
				(justify left bottom)
			)
		)
		(property "Value" "0.1uF"
			(at 3.47599 0.2921 0)
			(unlocked yes)
			(layer "F.SilkS")
			(hide yes)
			(effects
				(font
					(size 1.524 1.524)
					(thickness 0.254)
				)
				(justify left bottom)
			)
		)
		(sheetname "MAC")
		(sheetfile "MAC.kicad_sch")
		(duplicate_pad_numbers_are_jumpers no)
		(pad "1" smd rect
			(at -0.7 0)
			(size 1.1 1.05)
			(layers "F.Cu" "F.Mask" "F.Paste")
			(net "GND")
		)
		(pad "2" smd rect
			(at 0.7 0)
			(size 1.1 1.05)
			(layers "F.Cu" "F.Mask" "F.Paste")
			(net "+3.3V_CLEAN")
		)
	)
	(footprint "Connectors:CUI_PJ-002A"
		(layer "F.Cu")
		(at 213.932595 63.5546 90)
		(property "Reference" "J1"
			(at 8.510345 5.38505 0)
			(unlocked yes)
			(layer "F.SilkS")
			(effects
				(font
					(size 0.762 0.762)
					(thickness 0.2286)
				)
				(justify left bottom)
			)
		)
		(property "Value" "PJ-002A"
			(at -4.87299 -6.1849 0)
			(unlocked yes)
			(layer "F.SilkS")
			(hide yes)
			(effects
				(font
					(size 1.524 1.524)
					(thickness 0.254)
				)
				(justify left bottom)
			)
		)
		(sheetname "POWER")
		(sheetfile "POWER.kicad_sch")
		(duplicate_pad_numbers_are_jumpers no)
		(fp_line
			(start 9.8 -5.334)
			(end 9.8 4.826)
			(stroke
				(width 0.2032)
				(type solid)
			)
			(layer "F.SilkS")
		)
		(fp_line
			(start 5.55 -5.334)
			(end 9.8 -5.334)
			(stroke
				(width 0.2032)
				(type solid)
			)
			(layer "F.SilkS")
		)
		(fp_line
			(start -0.7 -5.334)
			(end 0.45 -5.334)
			(stroke
				(width 0.2032)
				(type solid)
			)
			(layer "F.SilkS")
		)
		(fp_line
			(start -0.7 -5.334)
			(end -0.7 -2.55)
			(stroke
				(width 0.2032)
				(type solid)
			)
			(layer "F.SilkS")
		)
		(fp_line
			(start -0.7 2.65)
			(end -0.7 4.826)
			(stroke
				(width 0.2032)
				(type solid)
			)
			(layer "F.SilkS")
		)
		(fp_line
			(start -0.7 4.826)
			(end 9.8 4.826)
			(stroke
				(width 0.2032)
				(type solid)
			)
			(layer "F.SilkS")
		)
		(fp_circle
			(center -2 0)
			(end -1.8 0)
			(stroke
				(width 0.4)
				(type solid)
			)
			(fill no)
			(layer "F.SilkS")
		)
		(pad "1" thru_hole oval
			(at 0 0 180)
			(size 5 2.5)
			(drill oval 3.5 1)
			(layers "*.Cu" "*.Mask")
			(remove_unused_layers no)
			(net "NetD1_2")
		)
		(pad "2" thru_hole oval
			(at 6 0 180)
			(size 4.5 2.25)
			(drill oval 3 1)
			(layers "*.Cu" "*.Mask")
			(remove_unused_layers no)
			(net "GND")
		)
		(pad "3" thru_hole oval
			(at 3 -4.7 270)
			(size 4.5 2.25)
			(drill oval 3 1)
			(layers "*.Cu" "*.Mask")
			(remove_unused_layers no)
			(net "GND")
		)
	)
	(footprint "Vault:CAPC1608X87X45ML20T05"
		(layer "F.Cu")
		(at 154.288595 81.5786 90)
		(property "Reference" "C66"
			(at -4.3 0.393345 90)
			(unlocked yes)
			(layer "F.SilkS")
			(effects
				(font
					(size 0.762 0.762)
					(thickness 0.2286)
				)
				(justify left bottom)
			)
		)
		(property "Value" "0.1uF"
			(at -3.47599 -0.2921 0)
			(unlocked yes)
			(layer "F.SilkS")
			(hide yes)
			(effects
				(font
					(size 1.524 1.524)
					(thickness 0.254)
				)
				(justify left bottom)
			)
		)
		(sheetname "MAC")
		(sheetfile "MAC.kicad_sch")
		(duplicate_pad_numbers_are_jumpers no)
		(pad "1" smd rect
			(at -0.7 0 180)
			(size 1.1 1.05)
			(layers "F.Cu" "F.Mask" "F.Paste")
			(net "GND")
		)
		(pad "2" smd rect
			(at 0.7 0 180)
			(size 1.1 1.05)
			(layers "F.Cu" "F.Mask" "F.Paste")
			(net "+3.3V_CLEAN")
		)
	)
	(footprint "Vault:TECO-1909763-1_V"
		(layer "F.Cu")
		(at 75.088595 97.5786 90)
		(property "Reference" "J6"
			(at -2.726931 2.028605 0)
			(unlocked yes)
			(layer "F.SilkS")
			(effects
				(font
					(size 0.762 0.762)
					(thickness 0.2286)
				)
			)
		)
		(property "Value" "1909763-1"
			(at 4.608085 3.749802 90)
			(unlocked yes)
			(layer "F.SilkS")
			(hide yes)
			(effects
				(font
					(size 1.524 1.524)
					(thickness 0.254)
				)
			)
		)
		(sheetname "USER_IO")
		(sheetfile "USER_IO.kicad_sch")
		(duplicate_pad_numbers_are_jumpers no)
		(fp_line
			(start -0.55 -1.3)
			(end 0.55 -1.3)
			(stroke
				(width 0.2)
				(type solid)
			)
			(layer "F.SilkS")
		)
		(fp_circle
			(center -1.778 1.65)
			(end -1.653 1.65)
			(stroke
				(width 0.25)
				(type solid)
			)
			(fill no)
			(layer "F.SilkS")
		)
		(pad "1" smd rect
			(at -1.475 0 90)
			(size 1.05 2.2)
			(layers "F.Cu" "F.Mask" "F.Paste")
			(net "GND")
		)
		(pad "2" smd rect
			(at 0 1.525 90)
			(size 1 1.05)
			(layers "F.Cu" "F.Mask" "F.Paste")
			(net "ANT1")
		)
		(pad "3" smd rect
			(at 1.475 0 90)
			(size 1.05 2.2)
			(layers "F.Cu" "F.Mask" "F.Paste")
			(net "GND")
		)
	)
	(footprint "Vault:CAPC1608X87X45ML20T05"
		(layer "F.Cu")
		(at 137.888595 90.4786 90)
		(property "Reference" "C24"
			(at -2.9714 -0.073069 90)
			(unlocked yes)
			(layer "F.SilkS")
			(effects
				(font
					(size 0.762 0.762)
					(thickness 0.2286)
				)
			)
		)
		(property "Value" "0.1uF"
			(at 2.09443 2.657602 90)
			(unlocked yes)
			(layer "F.SilkS")
			(hide yes)
			(effects
				(font
					(size 1.524 1.524)
					(thickness 0.254)
				)
			)
		)
		(sheetname "GPS_IMU_SENSORS")
		(sheetfile "GPS_IMU_SENSORS.kicad_sch")
		(duplicate_pad_numbers_are_jumpers no)
		(pad "1" smd rect
			(at -0.7 0 180)
			(size 1.1 1.05)
			(layers "F.Cu" "F.Mask" "F.Paste")
			(net "GND")
		)
		(pad "2" smd rect
			(at 0.7 0 180)
			(size 1.1 1.05)
			(layers "F.Cu" "F.Mask" "F.Paste")
			(net "+3.3V_CLEAN")
		)
	)
	(footprint "Capacitors:CAPC1608X10N"
		(layer "F.Cu")
		(at 226.251595 76.8586 -90)
		(property "Reference" "C86"
			(at -1.98 -0.430345 90)
			(unlocked yes)
			(layer "F.SilkS")
			(effects
				(font
					(size 0.762 0.762)
					(thickness 0.2286)
				)
				(justify left bottom)
			)
		)
		(property "Value" "CAP_0603_22PF_50V"
			(at 7.89559 -10.3759 0)
			(unlocked yes)
			(layer "F.SilkS")
			(hide yes)
			(effects
				(font
					(size 1.524 1.524)
					(thickness 0.254)
				)
				(justify left bottom)
			)
		)
		(sheetname "GPS_IMU_SENSORS")
		(sheetfile "GPS_IMU_SENSORS.kicad_sch")
		(duplicate_pad_numbers_are_jumpers no)
		(fp_line
			(start 0.635 0.7112)
			(end -0.635 0.7112)
			(stroke
				(width 0.1524)
				(type solid)
			)
			(layer "F.SilkS")
		)
		(fp_line
			(start 0.635 -0.7112)
			(end -0.635 -0.7112)
			(stroke
				(width 0.1524)
				(type solid)
			)
			(layer "F.SilkS")
		)
		(pad "1" smd rect
			(at -0.8 0)
			(size 0.95 1)
			(layers "F.Cu" "F.Mask" "F.Paste")
			(net "GND")
		)
		(pad "2" smd rect
			(at 0.8 0)
			(size 0.95 1)
			(layers "F.Cu" "F.Mask" "F.Paste")
			(net "NetC86_2")
		)
	)
	(footprint "Vault:CAPC1608X87X45ML20T05"
		(layer "F.Cu")
		(at 227.648595 115.4666)
		(property "Reference" "C18"
			(at 1.74 0.905345 0)
			(unlocked yes)
			(layer "F.SilkS")
			(effects
				(font
					(size 0.762 0.762)
					(thickness 0.2286)
				)
				(justify left bottom)
			)
		)
		(property "Value" "0.1uF"
			(at 3.0099 9.82599 0)
			(unlocked yes)
			(layer "F.SilkS")
			(hide yes)
			(effects
				(font
					(size 1.524 1.524)
					(thickness 0.254)
				)
				(justify left bottom)
			)
		)
		(sheetname "POWER")
		(sheetfile "POWER.kicad_sch")
		(duplicate_pad_numbers_are_jumpers no)
		(pad "1" smd rect
			(at -0.7 0 90)
			(size 1.1 1.05)
			(layers "F.Cu" "F.Mask" "F.Paste")
			(net "GND")
		)
		(pad "2" smd rect
			(at 0.7 0 90)
			(size 1.1 1.05)
			(layers "F.Cu" "F.Mask" "F.Paste")
			(net "+5.0V")
		)
	)
	(footprint "Passives:DIOM1608X06N"
		(layer "F.Cu")
		(at 90.234595 53.2366 90)
		(property "Reference" "D14"
			(at -1.47909 -1.367335 90)
			(unlocked yes)
			(layer "F.SilkS")
			(effects
				(font
					(size 0.762 0.762)
					(thickness 0.2286)
				)
				(justify left bottom)
			)
		)
		(property "Value" "RED"
			(at -4.13639 -0.5715 0)
			(unlocked yes)
			(layer "F.SilkS")
			(hide yes)
			(effects
				(font
					(size 1.524 1.524)
					(thickness 0.254)
				)
				(justify left bottom)
			)
		)
		(sheetname "USER_IO")
		(sheetfile "USER_IO.kicad_sch")
		(duplicate_pad_numbers_are_jumpers no)
		(fp_circle
			(center -1.275 -0.725)
			(end -1.225 -0.725)
			(stroke
				(width 0.1)
				(type solid)
			)
			(fill no)
			(layer "F.SilkS")
		)
		(pad "1" smd rect
			(at -0.725 0 180)
			(size 0.85 1)
			(layers "F.Cu" "F.Mask" "F.Paste")
			(net "NetD14_1")
		)
		(pad "2" smd rect
			(at 0.725 0 180)
			(size 0.85 1)
			(layers "F.Cu" "F.Mask" "F.Paste")
			(net "+3.3V")
		)
	)
	(footprint "Capacitors:CAPC2012X14N"
		(layer "F.Cu")
		(at 220.088595 87.9786 90)
		(property "Reference" "C8"
			(at 3 0.393345 90)
			(unlocked yes)
			(layer "F.SilkS")
			(effects
				(font
					(size 0.762 0.762)
					(thickness 0.2286)
				)
				(justify left bottom)
			)
		)
		(property "Value" "CAP_0805_10UF_25V"
			(at -10.63879 10.0965 0)
			(unlocked yes)
			(layer "F.SilkS")
			(hide yes)
			(effects
				(font
					(size 1.524 1.524)
					(thickness 0.254)
				)
				(justify left bottom)
			)
		)
		(sheetname "POWER")
		(sheetfile "POWER.kicad_sch")
		(duplicate_pad_numbers_are_jumpers no)
		(fp_line
			(start -0.762 -0.9652)
			(end 0.762 -0.9652)
			(stroke
				(width 0.1524)
				(type solid)
			)
			(layer "F.SilkS")
		)
		(fp_line
			(start -0.762 0.9652)
			(end 0.762 0.9652)
			(stroke
				(width 0.1524)
				(type solid)
			)
			(layer "F.SilkS")
		)
		(pad "1" smd rect
			(at -0.9 0 180)
			(size 1.45 1.15)
			(layers "F.Cu" "F.Mask" "F.Paste")
			(net "+3.3V")
		)
		(pad "2" smd rect
			(at 0.9 0 180)
			(size 1.45 1.15)
			(layers "F.Cu" "F.Mask" "F.Paste")
			(net "GND")
		)
	)
	(footprint "Vault:FP-5TS1-IPC_C"
		(layer "F.Cu")
		(at 170.588595 63.5786 90)
		(property "Reference" "U7"
			(at -0.698915 -3.135129 90)
			(unlocked yes)
			(layer "F.SilkS")
			(effects
				(font
					(size 0.762 0.762)
					(thickness 0.2286)
				)
			)
		)
		(property "Value" "AT24MAC402-STUM-T"
			(at 10.752795 3.216402 90)
			(unlocked yes)
			(layer "F.SilkS")
			(hide yes)
			(effects
				(font
					(size 1.524 1.524)
					(thickness 0.254)
				)
			)
		)
		(sheetname "GPS_IMU_SENSORS")
		(sheetfile "GPS_IMU_SENSORS.kicad_sch")
		(duplicate_pad_numbers_are_jumpers no)
		(fp_line
			(start -0.17207 -1.45)
			(end 0.17207 -1.45)
			(stroke
				(width 0.2)
				(type solid)
			)
			(layer "F.SilkS")
		)
		(fp_line
			(start 0.8 -0.30893)
			(end 0.8 0.30894)
			(stroke
				(width 0.2)
				(type solid)
			)
			(layer "F.SilkS")
		)
		(fp_line
			(start -0.17207 1.45)
			(end 0.17207 1.45)
			(stroke
				(width 0.2)
				(type solid)
			)
			(layer "F.SilkS")
		)
		(fp_circle
			(center -2.21035 -0.95)
			(end -2.08535 -0.95)
			(stroke
				(width 0.25)
				(type solid)
			)
			(fill no)
			(layer "F.SilkS")
		)
		(fp_line
			(start 1.68536 -1.55)
			(end 1.68536 1.55)
			(stroke
				(width 0.2)
				(type solid)
			)
			(layer "F.CrtYd")
		)
		(fp_line
			(start -1.68536 -1.55)
			(end 1.68536 -1.55)
			(stroke
				(width 0.2)
				(type solid)
			)
			(layer "F.CrtYd")
		)
		(fp_line
			(start -1.68536 -1.55)
			(end -1.68536 1.55)
			(stroke
				(width 0.2)
				(type solid)
			)
			(layer "F.CrtYd")
		)
		(fp_line
			(start -1.68536 1.55)
			(end 1.68536 1.55)
			(stroke
				(width 0.2)
				(type solid)
			)
			(layer "F.CrtYd")
		)
		(fp_line
			(start 1.68536 -1.55)
			(end 1.68536 1.55)
			(stroke
				(width 0.2)
				(type solid)
			)
			(layer "F.Fab")
		)
		(fp_line
			(start -1.68536 -1.55)
			(end 1.68536 -1.55)
			(stroke
				(width 0.2)
				(type solid)
			)
			(layer "F.Fab")
		)
		(fp_line
			(start -1.68536 -1.55)
			(end -1.68536 1.55)
			(stroke
				(width 0.2)
				(type solid)
			)
			(layer "F.Fab")
		)
		(fp_line
			(start 0 -0.5)
			(end 0 0.5)
			(stroke
				(width 0.1)
				(type solid)
			)
			(layer "F.Fab")
		)
		(fp_line
			(start -0.5 0)
			(end 0.5 0)
			(stroke
				(width 0.1)
				(type solid)
			)
			(layer "F.Fab")
		)
		(fp_line
			(start -1.68536 1.55)
			(end 1.68536 1.55)
			(stroke
				(width 0.2)
				(type solid)
			)
			(layer "F.Fab")
		)
		(fp_text user "${REFERENCE}"
			(at 0 0.28494 90)
			(unlocked yes)
			(layer "F.Fab")
			(effects
				(font
					(face "Arial")
					(size 0.63 0.63)
					(thickness 0.1)
				)
				(justify left bottom)
			)
		)
		(pad "1" smd rect
			(at -1.06621 -0.95 90)
			(size 1.03828 0.53213)
			(layers "F.Cu" "F.Mask" "F.Paste")
			(net "SCL")
			(solder_mask_margin 0)
			(solder_paste_margin 0)
		)
		(pad "2" smd roundrect
			(at -1.06621 0 90)
			(size 1.03828 0.53213)
			(layers "F.Cu" "F.Mask" "F.Paste")
			(roundrect_rratio 0.5)
			(net "GND")
			(solder_mask_margin 0)
			(solder_paste_margin 0)
		)
		(pad "3" smd roundrect
			(at -1.06621 0.95 90)
			(size 1.03828 0.53213)
			(layers "F.Cu" "F.Mask" "F.Paste")
			(roundrect_rratio 0.5)
			(net "SDA")
			(solder_mask_margin 0)
			(solder_paste_margin 0)
		)
		(pad "4" smd roundrect
			(at 1.06621 0.95 90)
			(size 1.03828 0.53213)
			(layers "F.Cu" "F.Mask" "F.Paste")
			(roundrect_rratio 0.5)
			(net "+3.3V")
			(solder_mask_margin 0)
			(solder_paste_margin 0)
		)
		(pad "5" smd roundrect
			(at 1.06621 -0.95 90)
			(size 1.03828 0.53213)
			(layers "F.Cu" "F.Mask" "F.Paste")
			(roundrect_rratio 0.5)
			(net "EXT_EEPROM_WP")
			(solder_mask_margin 0)
			(solder_paste_margin 0)
		)
	)
	(footprint "Resistors:RESC1005X04N"
		(layer "F.Cu")
		(at 122.088595 145.5786 -90)
		(property "Reference" "R23"
			(at 1.27491 0.808535 90)
			(unlocked yes)
			(layer "F.SilkS")
			(effects
				(font
					(size 0.762 0.762)
					(thickness 0.2286)
				)
				(justify left bottom)
			)
		)
		(property "Value" "ERJ-2GE0R00X"
			(at 3.42519 0.2413 0)
			(unlocked yes)
			(layer "F.SilkS")
			(hide yes)
			(effects
				(font
					(size 1.524 1.524)
					(thickness 0.254)
				)
				(justify left bottom)
			)
		)
		(sheetname "PCIe_JTAG")
		(sheetfile "PCIe_JTAG.kicad_sch")
		(duplicate_pad_numbers_are_jumpers no)
		(pad "1" smd rect
			(at -0.425 0)
			(size 0.6 0.65)
			(layers "F.Cu" "F.Mask" "F.Paste")
			(net "PRSNT")
		)
		(pad "2" smd rect
			(at 0.425 0)
			(size 0.6 0.65)
			(layers "F.Cu" "F.Mask" "F.Paste")
			(net "NetP2_B17")
		)
	)
	(footprint "Passives:SOT65P210X110-3N"
		(layer "F.Cu")
		(at 130.493595 66.4446 -90)
		(property "Reference" "D5"
			(at 4.00019 -1.629865 90)
			(unlocked yes)
			(layer "F.SilkS")
			(effects
				(font
					(size 0.762 0.762)
					(thickness 0.2286)
				)
				(justify left bottom)
			)
		)
		(property "Value" "BAT54SW"
			(at 3.88239 1.5875 0)
			(unlocked yes)
			(layer "F.SilkS")
			(hide yes)
			(effects
				(font
					(size 1.524 1.524)
					(thickness 0.254)
				)
				(justify left bottom)
			)
		)
		(sheetname "PCIe_JTAG")
		(sheetfile "PCIe_JTAG.kicad_sch")
		(duplicate_pad_numbers_are_jumpers no)
		(fp_line
			(start 0.675 1.1)
			(end -0.325 1.1)
			(stroke
				(width 0.2)
				(type solid)
			)
			(layer "F.SilkS")
		)
		(fp_line
			(start 0.675 1.1)
			(end 0.675 0.65)
			(stroke
				(width 0.2)
				(type solid)
			)
			(layer "F.SilkS")
		)
		(fp_line
			(start 0.675 -0.65)
			(end 0.675 -1.1)
			(stroke
				(width 0.2)
				(type solid)
			)
			(layer "F.SilkS")
		)
		(fp_line
			(start 0.675 -1.1)
			(end -0.325 -1.1)
			(stroke
				(width 0.2)
				(type solid)
			)
			(layer "F.SilkS")
		)
		(fp_circle
			(center -1.125 -1.45)
			(end -1.25 -1.45)
			(stroke
				(width 0.25)
				(type solid)
			)
			(fill no)
			(layer "F.SilkS")
		)
		(pad "1" smd rect
			(at -1.125 -0.65)
			(size 0.5 0.9)
			(layers "F.Cu" "F.Mask" "F.Paste")
			(net "GND")
		)
		(pad "2" smd rect
			(at -1.125 0.65)
			(size 0.5 0.9)
			(layers "F.Cu" "F.Mask" "F.Paste")
			(net "+3.3V")
		)
		(pad "3" smd rect
			(at 1.125 0)
			(size 0.5 0.9)
			(layers "F.Cu" "F.Mask" "F.Paste")
			(net "FPGA_TCK")
		)
	)
	(footprint "Passives:DIOM1608X06N"
		(layer "F.Cu")
		(at 74.867595 53.2366 90)
		(property "Reference" "D11"
			(at -1.21245 -1.265735 90)
			(unlocked yes)
			(layer "F.SilkS")
			(effects
				(font
					(size 0.762 0.762)
					(thickness 0.2286)
				)
				(justify left bottom)
			)
		)
		(property "Value" "RED"
			(at -3.22199 -1.4097 0)
			(unlocked yes)
			(layer "F.SilkS")
			(hide yes)
			(effects
				(font
					(size 1.524 1.524)
					(thickness 0.254)
				)
				(justify left bottom)
			)
		)
		(sheetname "USER_IO")
		(sheetfile "USER_IO.kicad_sch")
		(duplicate_pad_numbers_are_jumpers no)
		(fp_circle
			(center -1.275 -0.725)
			(end -1.225 -0.725)
			(stroke
				(width 0.1)
				(type solid)
			)
			(fill no)
			(layer "F.SilkS")
		)
		(pad "1" smd rect
			(at -0.725 0 180)
			(size 0.85 1)
			(layers "F.Cu" "F.Mask" "F.Paste")
			(net "NetD11_1")
		)
		(pad "2" smd rect
			(at 0.725 0 180)
			(size 0.85 1)
			(layers "F.Cu" "F.Mask" "F.Paste")
			(net "+3.3V")
		)
	)
	(footprint "FPGA_CONN:FPGA_CONN"
		(locked yes)
		(layer "F.Cu")
		(at 125.389655 117.45847)
		(property "Reference" "P1"
			(at -27.35726 -23.285325 0)
			(unlocked yes)
			(layer "F.SilkS")
			(effects
				(font
					(size 0.762 0.762)
					(thickness 0.2286)
				)
				(justify left bottom)
			)
		)
		(property "Value" "FPGA_CONN"
			(at -43.9575 52.70297 0)
			(unlocked yes)
			(layer "F.SilkS")
			(hide yes)
			(effects
				(font
					(size 1.524 1.524)
					(thickness 0.254)
				)
				(justify left bottom)
			)
		)
		(sheetname "FPGA")
		(sheetfile "FPGA.kicad_sch")
		(duplicate_pad_numbers_are_jumpers no)
		(fp_line
			(start -27.51976 -22.5712)
			(end 27.48039 -22.5712)
			(stroke
				(width 0.127)
				(type solid)
			)
			(layer "F.SilkS")
		)
		(fp_line
			(start -27.51976 22.42896)
			(end -27.51976 -22.5712)
			(stroke
				(width 0.127)
				(type solid)
			)
			(layer "F.SilkS")
		)
		(fp_line
			(start -27.51976 22.42896)
			(end 27.48039 22.42896)
			(stroke
				(width 0.127)
				(type solid)
			)
			(layer "F.SilkS")
		)
		(fp_line
			(start -25.81135 -10.82624)
			(end -25.21141 -10.82624)
			(stroke
				(width 0.15011)
				(type solid)
			)
			(layer "F.SilkS")
		)
		(fp_line
			(start -25.81135 -10.15924)
			(end -25.81135 -10.82624)
			(stroke
				(width 0.15011)
				(type solid)
			)
			(layer "F.SilkS")
		)
		(fp_line
			(start -25.81135 10.57377)
			(end -25.81135 9.90676)
			(stroke
				(width 0.15011)
				(type solid)
			)
			(layer "F.SilkS")
		)
		(fp_line
			(start -25.81135 10.57377)
			(end -25.21141 10.57377)
			(stroke
				(width 0.15011)
				(type solid)
			)
			(layer "F.SilkS")
		)
		(fp_line
			(start -25.21141 -11.37615)
			(end -22.41131 -11.37615)
			(stroke
				(width 0.15011)
				(type solid)
			)
			(layer "F.SilkS")
		)
		(fp_line
			(start -25.21141 -10.82624)
			(end -25.21141 -11.37615)
			(stroke
				(width 0.15011)
				(type solid)
			)
			(layer "F.SilkS")
		)
		(fp_line
			(start -25.21141 11.12368)
			(end -25.21141 10.57377)
			(stroke
				(width 0.15011)
				(type solid)
			)
			(layer "F.SilkS")
		)
		(fp_line
			(start -25.21141 11.12368)
			(end -22.41131 11.12368)
			(stroke
				(width 0.15011)
				(type solid)
			)
			(layer "F.SilkS")
		)
		(fp_line
			(start -22.41131 -10.82624)
			(end -22.41131 -11.37615)
			(stroke
				(width 0.15011)
				(type solid)
			)
			(layer "F.SilkS")
		)
		(fp_line
			(start -22.41131 -10.82624)
			(end -21.81136 -10.82624)
			(stroke
				(width 0.15011)
				(type solid)
			)
			(layer "F.SilkS")
		)
		(fp_line
			(start -22.41131 10.57377)
			(end -21.81136 10.57377)
			(stroke
				(width 0.15011)
				(type solid)
			)
			(layer "F.SilkS")
		)
		(fp_line
			(start -22.41131 11.12368)
			(end -22.41131 10.57377)
			(stroke
				(width 0.15011)
				(type solid)
			)
			(layer "F.SilkS")
		)
		(fp_line
			(start -21.81136 -10.15924)
			(end -21.81136 -10.82624)
			(stroke
				(width 0.15011)
				(type solid)
			)
			(layer "F.SilkS")
		)
		(fp_line
			(start -21.81136 10.57377)
			(end -21.81136 9.90676)
			(stroke
				(width 0.15011)
				(type solid)
			)
			(layer "F.SilkS")
		)
		(fp_line
			(start -12.20127 -20.19528)
			(end -11.65136 -20.19528)
			(stroke
				(width 0.15011)
				(type solid)
			)
			(layer "F.SilkS")
		)
		(fp_line
			(start -12.20127 -17.39519)
			(end -12.20127 -20.19528)
			(stroke
				(width 0.15011)
				(type solid)
			)
			(layer "F.SilkS")
		)
		(fp_line
			(start -12.20127 -17.39519)
			(end -11.65136 -17.39519)
			(stroke
				(width 0.15011)
				(type solid)
			)
			(layer "F.SilkS")
		)
		(fp_line
			(start -12.20102 17.39519)
			(end -11.65111 17.39519)
			(stroke
				(width 0.15011)
				(type solid)
			)
			(layer "F.SilkS")
		)
		(fp_line
			(start -12.20102 20.19529)
			(end -12.20102 17.39519)
			(stroke
				(width 0.15011)
				(type solid)
			)
			(layer "F.SilkS")
		)
		(fp_line
			(start -12.20102 20.19529)
			(end -11.65111 20.19529)
			(stroke
				(width 0.15011)
				(type solid)
			)
			(layer "F.SilkS")
		)
		(fp_line
			(start -11.65136 -20.79523)
			(end -10.98436 -20.79523)
			(stroke
				(width 0.15011)
				(type solid)
			)
			(layer "F.SilkS")
		)
		(fp_line
			(start -11.65136 -20.19528)
			(end -11.65136 -20.79523)
			(stroke
				(width 0.15011)
				(type solid)
			)
			(layer "F.SilkS")
		)
		(fp_line
			(start -11.65136 -16.79524)
			(end -11.65136 -17.39519)
			(stroke
				(width 0.15011)
				(type solid)
			)
			(layer "F.SilkS")
		)
		(fp_line
			(start -11.65136 -16.79524)
			(end -10.98436 -16.79524)
			(stroke
				(width 0.15011)
				(type solid)
			)
			(layer "F.SilkS")
		)
		(fp_line
			(start -11.65111 16.79524)
			(end -10.9841 16.79524)
			(stroke
				(width 0.15011)
				(type solid)
			)
			(layer "F.SilkS")
		)
		(fp_line
			(start -11.65111 17.39519)
			(end -11.65111 16.79524)
			(stroke
				(width 0.15011)
				(type solid)
			)
			(layer "F.SilkS")
		)
		(fp_line
			(start -11.65111 20.79524)
			(end -11.65111 20.19529)
			(stroke
				(width 0.15011)
				(type solid)
			)
			(layer "F.SilkS")
		)
		(fp_line
			(start -11.65111 20.79524)
			(end -10.9841 20.79524)
			(stroke
				(width 0.15011)
				(type solid)
			)
			(layer "F.SilkS")
		)
		(fp_line
			(start 9.08164 -20.79523)
			(end 9.74865 -20.79523)
			(stroke
				(width 0.15011)
				(type solid)
			)
			(layer "F.SilkS")
		)
		(fp_line
			(start 9.08164 -16.79524)
			(end 9.74865 -16.79524)
			(stroke
				(width 0.15011)
				(type solid)
			)
			(layer "F.SilkS")
		)
		(fp_line
			(start 9.0819 16.79524)
			(end 9.7489 16.79524)
			(stroke
				(width 0.15011)
				(type solid)
			)
			(layer "F.SilkS")
		)
		(fp_line
			(start 9.0819 20.79524)
			(end 9.7489 20.79524)
			(stroke
				(width 0.15011)
				(type solid)
			)
			(layer "F.SilkS")
		)
		(fp_line
			(start 9.74865 -20.19528)
			(end 9.74865 -20.79523)
			(stroke
				(width 0.15011)
				(type solid)
			)
			(layer "F.SilkS")
		)
		(fp_line
			(start 9.74865 -20.19528)
			(end 10.29856 -20.19528)
			(stroke
				(width 0.15011)
				(type solid)
			)
			(layer "F.SilkS")
		)
		(fp_line
			(start 9.74865 -17.39519)
			(end 10.29856 -17.39519)
			(stroke
				(width 0.15011)
				(type solid)
			)
			(layer "F.SilkS")
		)
		(fp_line
			(start 9.74865 -16.79524)
			(end 9.74865 -17.39519)
			(stroke
				(width 0.15011)
				(type solid)
			)
			(layer "F.SilkS")
		)
		(fp_line
			(start 9.7489 17.39519)
			(end 9.7489 16.79524)
			(stroke
				(width 0.15011)
				(type solid)
			)
			(layer "F.SilkS")
		)
		(fp_line
			(start 9.7489 17.39519)
			(end 10.29881 17.39519)
			(stroke
				(width 0.15011)
				(type solid)
			)
			(layer "F.SilkS")
		)
		(fp_line
			(start 9.7489 20.19529)
			(end 10.29881 20.19529)
			(stroke
				(width 0.15011)
				(type solid)
			)
			(layer "F.SilkS")
		)
		(fp_line
			(start 9.7489 20.79524)
			(end 9.7489 20.19529)
			(stroke
				(width 0.15011)
				(type solid)
			)
			(layer "F.SilkS")
		)
		(fp_line
			(start 10.29856 -17.39519)
			(end 10.29856 -20.19528)
			(stroke
				(width 0.15011)
				(type solid)
			)
			(layer "F.SilkS")
		)
		(fp_line
			(start 10.29881 20.19529)
			(end 10.29881 17.39519)
			(stroke
				(width 0.15011)
				(type solid)
			)
			(layer "F.SilkS")
		)
		(fp_line
			(start 21.81136 -10.82522)
			(end 22.41131 -10.82522)
			(stroke
				(width 0.15011)
				(type solid)
			)
			(layer "F.SilkS")
		)
		(fp_line
			(start 21.81136 -10.15822)
			(end 21.81136 -10.82522)
			(stroke
				(width 0.15011)
				(type solid)
			)
			(layer "F.SilkS")
		)
		(fp_line
			(start 21.81136 10.57478)
			(end 21.81136 9.90778)
			(stroke
				(width 0.15011)
				(type solid)
			)
			(layer "F.SilkS")
		)
		(fp_line
			(start 21.81136 10.57478)
			(end 22.41131 10.57478)
			(stroke
				(width 0.15011)
				(type solid)
			)
			(layer "F.SilkS")
		)
		(fp_line
			(start 22.41131 -11.37513)
			(end 25.2114 -11.37513)
			(stroke
				(width 0.15011)
				(type solid)
			)
			(layer "F.SilkS")
		)
		(fp_line
			(start 22.41131 -10.82522)
			(end 22.41131 -11.37513)
			(stroke
				(width 0.15011)
				(type solid)
			)
			(layer "F.SilkS")
		)
		(fp_line
			(start 22.41131 11.12469)
			(end 22.41131 10.57478)
			(stroke
				(width 0.15011)
				(type solid)
			)
			(layer "F.SilkS")
		)
		(fp_line
			(start 22.41131 11.12469)
			(end 25.2114 11.12469)
			(stroke
				(width 0.15011)
				(type solid)
			)
			(layer "F.SilkS")
		)
		(fp_line
			(start 25.2114 -10.82522)
			(end 25.2114 -11.37513)
			(stroke
				(width 0.15011)
				(type solid)
			)
			(layer "F.SilkS")
		)
		(fp_line
			(start 25.2114 -10.82522)
			(end 25.81135 -10.82522)
			(stroke
				(width 0.15011)
				(type solid)
			)
			(layer "F.SilkS")
		)
		(fp_line
			(start 25.2114 10.57478)
			(end 25.81135 10.57478)
			(stroke
				(width 0.15011)
				(type solid)
			)
			(layer "F.SilkS")
		)
		(fp_line
			(start 25.2114 11.12469)
			(end 25.2114 10.57478)
			(stroke
				(width 0.15011)
				(type solid)
			)
			(layer "F.SilkS")
		)
		(fp_line
			(start 25.81135 -10.15822)
			(end 25.81135 -10.82522)
			(stroke
				(width 0.15011)
				(type solid)
			)
			(layer "F.SilkS")
		)
		(fp_line
			(start 25.81135 10.57478)
			(end 25.81135 9.90778)
			(stroke
				(width 0.15011)
				(type solid)
			)
			(layer "F.SilkS")
		)
		(fp_line
			(start 27.48039 22.42896)
			(end 27.48039 -22.5712)
			(stroke
				(width 0.127)
				(type solid)
			)
			(layer "F.SilkS")
		)
		(fp_circle
			(center -20.30616 9.64921)
			(end -20.30616 9.44906)
			(stroke
				(width 0.40005)
				(type solid)
			)
			(fill no)
			(layer "F.SilkS")
		)
		(fp_circle
			(center -10.7268 -15.29004)
			(end -10.7268 -15.49019)
			(stroke
				(width 0.40005)
				(type solid)
			)
			(fill no)
			(layer "F.SilkS")
		)
		(fp_circle
			(center 8.82434 15.29004)
			(end 8.82434 15.08989)
			(stroke
				(width 0.40005)
				(type solid)
			)
			(fill no)
			(layer "F.SilkS")
		)
		(fp_circle
			(center 20.30616 -9.90066)
			(end 20.30616 -10.10081)
			(stroke
				(width 0.40005)
				(type solid)
			)
			(fill no)
			(layer "F.SilkS")
		)
		(fp_text user "3"
			(at -24.53272 -12.1572 360)
			(unlocked yes)
			(layer "F.SilkS")
			(effects
				(font
					(size 1.524 1.524)
					(thickness 0.254)
				)
				(justify left bottom)
			)
		)
		(fp_text user "2"
			(at -14.37272 -17.8722 360)
			(unlocked yes)
			(layer "F.SilkS")
			(effects
				(font
					(size 1.524 1.524)
					(thickness 0.254)
				)
				(justify left bottom)
			)
		)
		(fp_text user "4"
			(at -14.37272 19.5928 360)
			(unlocked yes)
			(layer "F.SilkS")
			(effects
				(font
					(size 1.524 1.524)
					(thickness 0.254)
				)
				(justify left bottom)
			)
		)
		(fp_text user "1"
			(at 23.09228 -12.1572 360)
			(unlocked yes)
			(layer "F.SilkS")
			(effects
				(font
					(size 1.524 1.524)
					(thickness 0.254)
				)
				(justify left bottom)
			)
		)
		(pad "A-1" smd rect
			(at 21.78647 -9.87526)
			(size 1.54991 0.24994)
			(layers "F.Cu" "F.Mask" "F.Paste")
			(net "+5.0V")
		)
		(pad "A-2" smd rect
			(at 25.83624 -9.87526)
			(size 1.54991 0.24994)
			(layers "F.Cu" "F.Mask" "F.Paste")
			(net "+5.0V")
		)
		(pad "A-3" smd rect
			(at 21.78647 -9.37514)
			(size 1.54991 0.24994)
			(layers "F.Cu" "F.Mask" "F.Paste")
			(net "+5.0V")
		)
		(pad "A-4" smd rect
			(at 25.83624 -9.37514)
			(size 1.54991 0.24994)
			(layers "F.Cu" "F.Mask" "F.Paste")
			(net "+5.0V")
		)
		(pad "A-5" smd rect
			(at 21.78647 -8.87527)
			(size 1.54991 0.24994)
			(layers "F.Cu" "F.Mask" "F.Paste")
			(net "+5.0V")
		)
		(pad "A-6" smd rect
			(at 25.83624 -8.87527)
			(size 1.54991 0.24994)
			(layers "F.Cu" "F.Mask" "F.Paste")
			(net "+5.0V")
		)
		(pad "A-7" smd rect
			(at 21.78647 -8.37514)
			(size 1.54991 0.24994)
			(layers "F.Cu" "F.Mask" "F.Paste")
			(net "+5.0V")
		)
		(pad "A-8" smd rect
			(at 25.83624 -8.37514)
			(size 1.54991 0.24994)
			(layers "F.Cu" "F.Mask" "F.Paste")
			(net "+5.0V")
		)
		(pad "A-9" smd rect
			(at 21.78647 -7.87527)
			(size 1.54991 0.24994)
			(layers "F.Cu" "F.Mask" "F.Paste")
			(net "GND")
		)
		(pad "A-10" smd rect
			(at 25.83624 -7.87527)
			(size 1.54991 0.24994)
			(layers "F.Cu" "F.Mask" "F.Paste")
			(net "GND")
		)
		(pad "A-11" smd rect
			(at 21.78647 -7.37514)
			(size 1.54991 0.24994)
			(layers "F.Cu" "F.Mask" "F.Paste")
		)
		(pad "A-12" smd rect
			(at 25.83624 -7.37514)
			(size 1.54991 0.24994)
			(layers "F.Cu" "F.Mask" "F.Paste")
		)
		(pad "A-13" smd rect
			(at 21.78647 -6.87527)
			(size 1.54991 0.24994)
			(layers "F.Cu" "F.Mask" "F.Paste")
		)
		(pad "A-14" smd rect
			(at 25.83624 -6.87527)
			(size 1.54991 0.24994)
			(layers "F.Cu" "F.Mask" "F.Paste")
		)
		(pad "A-15" smd rect
			(at 21.78647 -6.37514)
			(size 1.54991 0.24994)
			(layers "F.Cu" "F.Mask" "F.Paste")
		)
		(pad "A-16" smd rect
			(at 25.83624 -6.37514)
			(size 1.54991 0.24994)
			(layers "F.Cu" "F.Mask" "F.Paste")
		)
		(pad "A-17" smd rect
			(at 21.78647 -5.87527)
			(size 1.54991 0.24994)
			(layers "F.Cu" "F.Mask" "F.Paste")
		)
		(pad "A-18" smd rect
			(at 25.83624 -5.87527)
			(size 1.54991 0.24994)
			(layers "F.Cu" "F.Mask" "F.Paste")
		)
		(pad "A-19" smd rect
			(at 21.78647 -5.37515)
			(size 1.54991 0.24994)
			(layers "F.Cu" "F.Mask" "F.Paste")
			(net "GND")
		)
		(pad "A-20" smd rect
			(at 25.83624 -5.37515)
			(size 1.54991 0.24994)
			(layers "F.Cu" "F.Mask" "F.Paste")
			(net "GND")
		)
		(pad "A-21" smd rect
			(at 21.78647 -4.87527)
			(size 1.54991 0.24994)
			(layers "F.Cu" "F.Mask" "F.Paste")
			(net "MOSI")
		)
		(pad "A-22" smd rect
			(at 25.83624 -4.87527)
			(size 1.54991 0.24994)
			(layers "F.Cu" "F.Mask" "F.Paste")
			(net "GPS1_RST")
		)
		(pad "A-23" smd rect
			(at 21.78647 -4.37515)
			(size 1.54991 0.24994)
			(layers "F.Cu" "F.Mask" "F.Paste")
			(net "MISO")
		)
		(pad "A-24" smd rect
			(at 25.83624 -4.37515)
			(size 1.54991 0.24994)
			(layers "F.Cu" "F.Mask" "F.Paste")
		)
		(pad "A-25" smd rect
			(at 21.78647 -3.87528)
			(size 1.54991 0.24994)
			(layers "F.Cu" "F.Mask" "F.Paste")
			(net "SCK")
		)
		(pad "A-26" smd rect
			(at 25.83624 -3.87528)
			(size 1.54991 0.24994)
			(layers "F.Cu" "F.Mask" "F.Paste")
		)
		(pad "A-27" smd rect
			(at 21.78647 -3.37515)
			(size 1.54991 0.24994)
			(layers "F.Cu" "F.Mask" "F.Paste")
			(net "CSN")
		)
		(pad "A-28" smd rect
			(at 25.83624 -3.37515)
			(size 1.54991 0.24994)
			(layers "F.Cu" "F.Mask" "F.Paste")
		)
		(pad "A-29" smd rect
			(at 21.78647 -2.87528)
			(size 1.54991 0.24994)
			(layers "F.Cu" "F.Mask" "F.Paste")
			(net "GND")
		)
		(pad "A-30" smd rect
			(at 25.83624 -2.87528)
			(size 1.54991 0.24994)
			(layers "F.Cu" "F.Mask" "F.Paste")
			(net "GND")
		)
		(pad "A-31" smd rect
			(at 21.78647 -2.37515)
			(size 1.54991 0.24994)
			(layers "F.Cu" "F.Mask" "F.Paste")
		)
		(pad "A-32" smd rect
			(at 25.83624 -2.37515)
			(size 1.54991 0.24994)
			(layers "F.Cu" "F.Mask" "F.Paste")
			(net "GPS1_TP1")
		)
		(pad "A-33" smd rect
			(at 21.78647 -1.87528)
			(size 1.54991 0.24994)
			(layers "F.Cu" "F.Mask" "F.Paste")
		)
		(pad "A-34" smd rect
			(at 25.83624 -1.87528)
			(size 1.54991 0.24994)
			(layers "F.Cu" "F.Mask" "F.Paste")
			(net "GPS1_TP2")
		)
		(pad "A-35" smd rect
			(at 21.78647 -1.37515)
			(size 1.54991 0.24994)
			(layers "F.Cu" "F.Mask" "F.Paste")
			(net "GPS2_RST")
		)
		(pad "A-36" smd rect
			(at 25.83624 -1.37515)
			(size 1.54991 0.24994)
			(layers "F.Cu" "F.Mask" "F.Paste")
		)
		(pad "A-37" smd rect
			(at 21.78647 -0.87528)
			(size 1.54991 0.24994)
			(layers "F.Cu" "F.Mask" "F.Paste")
		)
		(pad "A-38" smd rect
			(at 25.83624 -0.87528)
			(size 1.54991 0.24994)
			(layers "F.Cu" "F.Mask" "F.Paste")
		)
		(pad "A-39" smd rect
			(at 21.78647 -0.37516)
			(size 1.54991 0.24994)
			(layers "F.Cu" "F.Mask" "F.Paste")
			(net "GND")
		)
		(pad "A-40" smd rect
			(at 25.83624 -0.37516)
			(size 1.54991 0.24994)
			(layers "F.Cu" "F.Mask" "F.Paste")
			(net "GND")
		)
		(pad "A-41" smd rect
			(at 21.78647 0.12472)
			(size 1.54991 0.24994)
			(layers "F.Cu" "F.Mask" "F.Paste")
		)
		(pad "A-42" smd rect
			(at 25.83624 0.12472)
			(size 1.54991 0.24994)
			(layers "F.Cu" "F.Mask" "F.Paste")
		)
		(pad "A-43" smd rect
			(at 21.78647 0.62484)
			(size 1.54991 0.24994)
			(layers "F.Cu" "F.Mask" "F.Paste")
			(net "GPS2_TP1")
		)
		(pad "A-44" smd rect
			(at 25.83624 0.62484)
			(size 1.54991 0.24994)
			(layers "F.Cu" "F.Mask" "F.Paste")
			(net "EXT_EEPROM_WP")
		)
		(pad "A-45" smd rect
			(at 21.78647 1.12471)
			(size 1.54991 0.24994)
			(layers "F.Cu" "F.Mask" "F.Paste")
			(net "GPS2_TP2")
		)
		(pad "A-46" smd rect
			(at 25.83624 1.12471)
			(size 1.54991 0.24994)
			(layers "F.Cu" "F.Mask" "F.Paste")
			(net "IMU_INT")
		)
		(pad "A-47" smd rect
			(at 21.78647 1.62484)
			(size 1.54991 0.24994)
			(layers "F.Cu" "F.Mask" "F.Paste")
		)
		(pad "A-48" smd rect
			(at 25.83624 1.62484)
			(size 1.54991 0.24994)
			(layers "F.Cu" "F.Mask" "F.Paste")
			(net "IMU_NRST")
		)
		(pad "A-49" smd rect
			(at 21.78647 2.12471)
			(size 1.54991 0.24994)
			(layers "F.Cu" "F.Mask" "F.Paste")
			(net "GND")
		)
		(pad "A-50" smd rect
			(at 25.83624 2.12471)
			(size 1.54991 0.24994)
			(layers "F.Cu" "F.Mask" "F.Paste")
			(net "GND")
		)
		(pad "A-51" smd rect
			(at 21.78647 2.62484)
			(size 1.54991 0.24994)
			(layers "F.Cu" "F.Mask" "F.Paste")
		)
		(pad "A-52" smd rect
			(at 25.83624 2.62484)
			(size 1.54991 0.24994)
			(layers "F.Cu" "F.Mask" "F.Paste")
		)
		(pad "A-53" smd rect
			(at 21.78647 3.12471)
			(size 1.54991 0.24994)
			(layers "F.Cu" "F.Mask" "F.Paste")
		)
		(pad "A-54" smd rect
			(at 25.83624 3.12471)
			(size 1.54991 0.24994)
			(layers "F.Cu" "F.Mask" "F.Paste")
			(net "IMU_PS0")
		)
		(pad "A-55" smd rect
			(at 21.78647 3.62484)
			(size 1.54991 0.24994)
			(layers "F.Cu" "F.Mask" "F.Paste")
		)
		(pad "A-56" smd rect
			(at 25.83624 3.62484)
			(size 1.54991 0.24994)
			(layers "F.Cu" "F.Mask" "F.Paste")
			(net "IMU_PS1")
		)
		(pad "A-57" smd rect
			(at 21.78647 4.12471)
			(size 1.54991 0.24994)
			(layers "F.Cu" "F.Mask" "F.Paste")
		)
		(pad "A-58" smd rect
			(at 25.83624 4.12471)
			(size 1.54991 0.24994)
			(layers "F.Cu" "F.Mask" "F.Paste")
		)
		(pad "A-59" smd rect
			(at 21.78647 4.62483)
			(size 1.54991 0.24994)
			(layers "F.Cu" "F.Mask" "F.Paste")
			(net "GND")
		)
		(pad "A-60" smd rect
			(at 25.83624 4.62483)
			(size 1.54991 0.24994)
			(layers "F.Cu" "F.Mask" "F.Paste")
			(net "GND")
		)
		(pad "A-61" smd rect
			(at 21.78647 5.12471)
			(size 1.54991 0.24994)
			(layers "F.Cu" "F.Mask" "F.Paste")
		)
		(pad "A-62" smd rect
			(at 25.83624 5.12471)
			(size 1.54991 0.24994)
			(layers "F.Cu" "F.Mask" "F.Paste")
			(net "IMU_BOOT")
		)
		(pad "A-63" smd rect
			(at 21.78647 5.62483)
			(size 1.54991 0.24994)
			(layers "F.Cu" "F.Mask" "F.Paste")
		)
		(pad "A-64" smd rect
			(at 25.83624 5.62483)
			(size 1.54991 0.24994)
			(layers "F.Cu" "F.Mask" "F.Paste")
			(net "IMU_CLKSEL0")
		)
		(pad "A-65" smd rect
			(at 21.78647 6.1247)
			(size 1.54991 0.24994)
			(layers "F.Cu" "F.Mask" "F.Paste")
		)
		(pad "A-66" smd rect
			(at 25.83624 6.1247)
			(size 1.54991 0.24994)
			(layers "F.Cu" "F.Mask" "F.Paste")
		)
		(pad "A-67" smd rect
			(at 21.78647 6.62483)
			(size 1.54991 0.24994)
			(layers "F.Cu" "F.Mask" "F.Paste")
			(net "KEY2")
		)
		(pad "A-68" smd rect
			(at 25.83624 6.62483)
			(size 1.54991 0.24994)
			(layers "F.Cu" "F.Mask" "F.Paste")
		)
		(pad "A-69" smd rect
			(at 21.78647 7.1247)
			(size 1.54991 0.24994)
			(layers "F.Cu" "F.Mask" "F.Paste")
			(net "GND")
		)
		(pad "A-70" smd rect
			(at 25.83624 7.1247)
			(size 1.54991 0.24994)
			(layers "F.Cu" "F.Mask" "F.Paste")
			(net "GND")
		)
		(pad "A-71" smd rect
			(at 21.78647 7.62483)
			(size 1.54991 0.24994)
			(layers "F.Cu" "F.Mask" "F.Paste")
			(net "LED4")
		)
		(pad "A-72" smd rect
			(at 25.83624 7.62483)
			(size 1.54991 0.24994)
			(layers "F.Cu" "F.Mask" "F.Paste")
		)
		(pad "A-73" smd rect
			(at 21.78647 8.1247)
			(size 1.54991 0.24994)
			(layers "F.Cu" "F.Mask" "F.Paste")
			(net "LED3")
		)
		(pad "A-74" smd rect
			(at 25.83624 8.1247)
			(size 1.54991 0.24994)
			(layers "F.Cu" "F.Mask" "F.Paste")
		)
		(pad "A-75" smd rect
			(at 21.78647 8.62483)
			(size 1.54991 0.24994)
			(layers "F.Cu" "F.Mask" "F.Paste")
			(net "LED2")
		)
		(pad "A-76" smd rect
			(at 25.83624 8.62483)
			(size 1.54991 0.24994)
			(layers "F.Cu" "F.Mask" "F.Paste")
		)
		(pad "A-77" smd rect
			(at 21.78647 9.1247)
			(size 1.54991 0.24994)
			(layers "F.Cu" "F.Mask" "F.Paste")
			(net "LED1")
		)
		(pad "A-78" smd rect
			(at 25.83624 9.1247)
			(size 1.54991 0.24994)
			(layers "F.Cu" "F.Mask" "F.Paste")
		)
		(pad "A-79" smd rect
			(at 21.78647 9.62482)
			(size 1.54991 0.24994)
			(layers "F.Cu" "F.Mask" "F.Paste")
		)
		(pad "A-80" smd rect
			(at 25.83624 9.62482)
			(size 1.54991 0.24994)
			(layers "F.Cu" "F.Mask" "F.Paste")
		)
		(pad "A-81" smd rect
			(at 23.8 -11.3)
			(size 1.70002 1.35001)
			(layers "F.Cu" "F.Mask" "F.Paste")
		)
		(pad "A-82" thru_hole circle
			(at 23.81136 -10.1252)
			(size 0.55016 0.55016)
			(drill 0.55016)
			(layers "*.Cu" "*.Mask")
			(remove_unused_layers no)
			(thermal_bridge_angle 90)
		)
		(pad "A-83" thru_hole circle
			(at 23.81136 9.87476)
			(size 0.55016 0.55016)
			(drill 0.55016)
			(layers "*.Cu" "*.Mask")
			(remove_unused_layers no)
			(thermal_bridge_angle 90)
		)
		(pad "A-84" smd rect
			(at 23.8 11.05)
			(size 1.70002 1.35001)
			(layers "F.Cu" "F.Mask" "F.Paste")
		)
		(pad "B-1" smd rect
			(at -10.7014 -16.77035)
			(size 0.24994 1.54991)
			(layers "F.Cu" "F.Mask" "F.Paste")
		)
		(pad "B-2" smd rect
			(at -10.7014 -20.82012)
			(size 0.24994 1.54991)
			(layers "F.Cu" "F.Mask" "F.Paste")
		)
		(pad "B-3" smd rect
			(at -10.20128 -16.77035)
			(size 0.24994 1.54991)
			(layers "F.Cu" "F.Mask" "F.Paste")
		)
		(pad "B-4" smd rect
			(at -10.20128 -20.82012)
			(size 0.24994 1.54991)
			(layers "F.Cu" "F.Mask" "F.Paste")
		)
		(pad "B-5" smd rect
			(at -9.7014 -16.77035)
			(size 0.24994 1.54991)
			(layers "F.Cu" "F.Mask" "F.Paste")
		)
		(pad "B-6" smd rect
			(at -9.7014 -20.82012)
			(size 0.24994 1.54991)
			(layers "F.Cu" "F.Mask" "F.Paste")
			(net "OE_5356")
		)
		(pad "B-7" smd rect
			(at -9.20128 -16.77035)
			(size 0.24994 1.54991)
			(layers "F.Cu" "F.Mask" "F.Paste")
		)
		(pad "B-8" smd rect
			(at -9.20128 -20.82012)
			(size 0.24994 1.54991)
			(layers "F.Cu" "F.Mask" "F.Paste")
			(net "MAC_USB_PWR")
		)
		(pad "B-9" smd rect
			(at -8.70141 -16.77035)
			(size 0.24994 1.54991)
			(layers "F.Cu" "F.Mask" "F.Paste")
			(net "GND")
		)
		(pad "B-10" smd rect
			(at -8.70141 -20.82012)
			(size 0.24994 1.54991)
			(layers "F.Cu" "F.Mask" "F.Paste")
			(net "GND")
		)
		(pad "B-11" smd rect
			(at -8.20128 -16.77035)
			(size 0.24994 1.54991)
			(layers "F.Cu" "F.Mask" "F.Paste")
			(net "MAC_10Mout")
		)
		(pad "B-12" smd rect
			(at -8.20128 -20.82012)
			(size 0.24994 1.54991)
			(layers "F.Cu" "F.Mask" "F.Paste")
		)
		(pad "B-13" smd rect
			(at -7.70141 -16.77035)
			(size 0.24994 1.54991)
			(layers "F.Cu" "F.Mask" "F.Paste")
			(net "MAC_10Mout")
		)
		(pad "B-14" smd rect
			(at -7.70141 -20.82012)
			(size 0.24994 1.54991)
			(layers "F.Cu" "F.Mask" "F.Paste")
		)
		(pad "B-15" smd rect
			(at -7.20128 -16.77035)
			(size 0.24994 1.54991)
			(layers "F.Cu" "F.Mask" "F.Paste")
		)
		(pad "B-16" smd rect
			(at -7.20128 -20.82012)
			(size 0.24994 1.54991)
			(layers "F.Cu" "F.Mask" "F.Paste")
			(net "DCXO2")
		)
		(pad "B-17" smd rect
			(at -6.70141 -16.77035)
			(size 0.24994 1.54991)
			(layers "F.Cu" "F.Mask" "F.Paste")
		)
		(pad "B-18" smd rect
			(at -6.70141 -20.82012)
			(size 0.24994 1.54991)
			(layers "F.Cu" "F.Mask" "F.Paste")
		)
		(pad "B-19" smd rect
			(at -6.20128 -16.77035)
			(size 0.24994 1.54991)
			(layers "F.Cu" "F.Mask" "F.Paste")
			(net "GND")
		)
		(pad "B-20" smd rect
			(at -6.20128 -20.82012)
			(size 0.24994 1.54991)
			(layers "F.Cu" "F.Mask" "F.Paste")
			(net "GND")
		)
		(pad "B-21" smd rect
			(at -5.70141 -16.77035)
			(size 0.24994 1.54991)
			(layers "F.Cu" "F.Mask" "F.Paste")
			(net "ANT1")
		)
		(pad "B-22" smd rect
			(at -5.70141 -20.82012)
			(size 0.24994 1.54991)
			(layers "F.Cu" "F.Mask" "F.Paste")
		)
		(pad "B-23" smd rect
			(at -5.20129 -16.77035)
			(size 0.24994 1.54991)
			(layers "F.Cu" "F.Mask" "F.Paste")
			(net "ANT2")
		)
		(pad "B-24" smd rect
			(at -5.20129 -20.82012)
			(size 0.24994 1.54991)
			(layers "F.Cu" "F.Mask" "F.Paste")
		)
		(pad "B-25" smd rect
			(at -4.70141 -16.77035)
			(size 0.24994 1.54991)
			(layers "F.Cu" "F.Mask" "F.Paste")
			(net "ANT3")
		)
		(pad "B-26" smd rect
			(at -4.70141 -20.82012)
			(size 0.24994 1.54991)
			(layers "F.Cu" "F.Mask" "F.Paste")
			(net "MAC_TX")
		)
		(pad "B-27" smd rect
			(at -4.20129 -16.77035)
			(size 0.24994 1.54991)
			(layers "F.Cu" "F.Mask" "F.Paste")
			(net "ANT4")
		)
		(pad "B-28" smd rect
			(at -4.20129 -20.82012)
			(size 0.24994 1.54991)
			(layers "F.Cu" "F.Mask" "F.Paste")
			(net "MAC_RX")
		)
		(pad "B-29" smd rect
			(at -3.70142 -16.77035)
			(size 0.24994 1.54991)
			(layers "F.Cu" "F.Mask" "F.Paste")
			(net "GND")
		)
		(pad "B-30" smd rect
			(at -3.70142 -20.82012)
			(size 0.24994 1.54991)
			(layers "F.Cu" "F.Mask" "F.Paste")
			(net "GND")
		)
		(pad "B-31" smd rect
			(at -3.20129 -16.77035)
			(size 0.24994 1.54991)
			(layers "F.Cu" "F.Mask" "F.Paste")
		)
		(pad "B-32" smd rect
			(at -3.20129 -20.82012)
			(size 0.24994 1.54991)
			(layers "F.Cu" "F.Mask" "F.Paste")
		)
		(pad "B-33" smd rect
			(at -2.70142 -16.77035)
			(size 0.24994 1.54991)
			(layers "F.Cu" "F.Mask" "F.Paste")
			(net "MAC_10Mout")
		)
		(pad "B-34" smd rect
			(at -2.70142 -20.82012)
			(size 0.24994 1.54991)
			(layers "F.Cu" "F.Mask" "F.Paste")
			(net "DCXO1")
		)
		(pad "B-35" smd rect
			(at -2.20129 -16.77035)
			(size 0.24994 1.54991)
			(layers "F.Cu" "F.Mask" "F.Paste")
			(net "MAC_ALARM")
		)
		(pad "B-36" smd rect
			(at -2.20129 -20.82012)
			(size 0.24994 1.54991)
			(layers "F.Cu" "F.Mask" "F.Paste")
		)
		(pad "B-37" smd rect
			(at -1.70142 -16.77035)
			(size 0.24994 1.54991)
			(layers "F.Cu" "F.Mask" "F.Paste")
			(net "MAC_BITE")
		)
		(pad "B-38" smd rect
			(at -1.70142 -20.82012)
			(size 0.24994 1.54991)
			(layers "F.Cu" "F.Mask" "F.Paste")
		)
		(pad "B-39" smd rect
			(at -1.20129 -16.77035)
			(size 0.24994 1.54991)
			(layers "F.Cu" "F.Mask" "F.Paste")
			(net "GND")
		)
		(pad "B-40" smd rect
			(at -1.20129 -20.82012)
			(size 0.24994 1.54991)
			(layers "F.Cu" "F.Mask" "F.Paste")
			(net "GND")
		)
		(pad "B-41" smd rect
			(at -0.70142 -16.77035)
			(size 0.24994 1.54991)
			(layers "F.Cu" "F.Mask" "F.Paste")
			(net "MAC_PPS_OUT+")
		)
		(pad "B-42" smd rect
			(at -0.70142 -20.82012)
			(size 0.24994 1.54991)
			(layers "F.Cu" "F.Mask" "F.Paste")
		)
		(pad "B-43" smd rect
			(at -0.2013 -16.77035)
			(size 0.24994 1.54991)
			(layers "F.Cu" "F.Mask" "F.Paste")
			(net "MAC_PPS_OUT-")
		)
		(pad "B-44" smd rect
			(at -0.2013 -20.82012)
			(size 0.24994 1.54991)
			(layers "F.Cu" "F.Mask" "F.Paste")
		)
		(pad "B-45" smd rect
			(at 0.29858 -16.77035)
			(size 0.24994 1.54991)
			(layers "F.Cu" "F.Mask" "F.Paste")
			(net "MAC_PPS_IN0+")
		)
		(pad "B-46" smd rect
			(at 0.29858 -20.82012)
			(size 0.24994 1.54991)
			(layers "F.Cu" "F.Mask" "F.Paste")
		)
		(pad "B-47" smd rect
			(at 0.7987 -16.77035)
			(size 0.24994 1.54991)
			(layers "F.Cu" "F.Mask" "F.Paste")
			(net "MAC_PPS_IN0-")
		)
		(pad "B-48" smd rect
			(at 0.7987 -20.82012)
			(size 0.24994 1.54991)
			(layers "F.Cu" "F.Mask" "F.Paste")
		)
		(pad "B-49" smd rect
			(at 1.29857 -16.77035)
			(size 0.24994 1.54991)
			(layers "F.Cu" "F.Mask" "F.Paste")
			(net "GND")
		)
		(pad "B-50" smd rect
			(at 1.29857 -20.82012)
			(size 0.24994 1.54991)
			(layers "F.Cu" "F.Mask" "F.Paste")
			(net "GND")
		)
		(pad "B-51" smd rect
			(at 1.7987 -16.77035)
			(size 0.24994 1.54991)
			(layers "F.Cu" "F.Mask" "F.Paste")
			(net "MAC_PPS_IN1+")
		)
		(pad "B-52" smd rect
			(at 1.7987 -20.82012)
			(size 0.24994 1.54991)
			(layers "F.Cu" "F.Mask" "F.Paste")
		)
		(pad "B-53" smd rect
			(at 2.29857 -16.77035)
			(size 0.24994 1.54991)
			(layers "F.Cu" "F.Mask" "F.Paste")
			(net "MAC_PPS_IN1-")
		)
		(pad "B-54" smd rect
			(at 2.29857 -20.82012)
			(size 0.24994 1.54991)
			(layers "F.Cu" "F.Mask" "F.Paste")
		)
		(pad "B-55" smd rect
			(at 2.7987 -16.77035)
			(size 0.24994 1.54991)
			(layers "F.Cu" "F.Mask" "F.Paste")
		)
		(pad "B-56" smd rect
			(at 2.7987 -20.82012)
			(size 0.24994 1.54991)
			(layers "F.Cu" "F.Mask" "F.Paste")
		)
		(pad "B-57" smd rect
			(at 3.29857 -16.77035)
			(size 0.24994 1.54991)
			(layers "F.Cu" "F.Mask" "F.Paste")
		)
		(pad "B-58" smd rect
			(at 3.29857 -20.82012)
			(size 0.24994 1.54991)
			(layers "F.Cu" "F.Mask" "F.Paste")
		)
		(pad "B-59" smd rect
			(at 3.7987 -16.77035)
			(size 0.24994 1.54991)
			(layers "F.Cu" "F.Mask" "F.Paste")
			(net "GND")
		)
		(pad "B-60" smd rect
			(at 3.7987 -20.82012)
			(size 0.24994 1.54991)
			(layers "F.Cu" "F.Mask" "F.Paste")
			(net "GND")
		)
		(pad "B-61" smd rect
			(at 4.29857 -16.77035)
			(size 0.24994 1.54991)
			(layers "F.Cu" "F.Mask" "F.Paste")
			(net "SDA")
		)
		(pad "B-62" smd rect
			(at 4.29857 -20.82012)
			(size 0.24994 1.54991)
			(layers "F.Cu" "F.Mask" "F.Paste")
		)
		(pad "B-63" smd rect
			(at 4.79869 -16.77035)
			(size 0.24994 1.54991)
			(layers "F.Cu" "F.Mask" "F.Paste")
		)
		(pad "B-64" smd rect
			(at 4.79869 -20.82012)
			(size 0.24994 1.54991)
			(layers "F.Cu" "F.Mask" "F.Paste")
			(net "5721_STATUS")
		)
		(pad "B-65" smd rect
			(at 5.29857 -16.77035)
			(size 0.24994 1.54991)
			(layers "F.Cu" "F.Mask" "F.Paste")
		)
		(pad "B-66" smd rect
			(at 5.29857 -20.82012)
			(size 0.24994 1.54991)
			(layers "F.Cu" "F.Mask" "F.Paste")
		)
		(pad "B-67" smd rect
			(at 5.79869 -16.77035)
			(size 0.24994 1.54991)
			(layers "F.Cu" "F.Mask" "F.Paste")
			(net "SCL")
		)
		(pad "B-68" smd rect
			(at 5.79869 -20.82012)
			(size 0.24994 1.54991)
			(layers "F.Cu" "F.Mask" "F.Paste")
		)
		(pad "B-69" smd rect
			(at 6.29856 -16.77035)
			(size 0.24994 1.54991)
			(layers "F.Cu" "F.Mask" "F.Paste")
			(net "GND")
		)
		(pad "B-70" smd rect
			(at 6.29856 -20.82012)
			(size 0.24994 1.54991)
			(layers "F.Cu" "F.Mask" "F.Paste")
			(net "GND")
		)
		(pad "B-71" smd rect
			(at 6.79869 -16.77035)
			(size 0.24994 1.54991)
			(layers "F.Cu" "F.Mask" "F.Paste")
			(net "UART1_TXD")
		)
		(pad "B-72" smd rect
			(at 6.79869 -20.82012)
			(size 0.24994 1.54991)
			(layers "F.Cu" "F.Mask" "F.Paste")
			(net "MAC_USB+")
		)
		(pad "B-73" smd rect
			(at 7.29856 -16.77035)
			(size 0.24994 1.54991)
			(layers "F.Cu" "F.Mask" "F.Paste")
		)
		(pad "B-74" smd rect
			(at 7.29856 -20.82012)
			(size 0.24994 1.54991)
			(layers "F.Cu" "F.Mask" "F.Paste")
			(net "MAC_USB-")
		)
		(pad "B-75" smd rect
			(at 7.79869 -16.77035)
			(size 0.24994 1.54991)
			(layers "F.Cu" "F.Mask" "F.Paste")
		)
		(pad "B-76" smd rect
			(at 7.79869 -20.82012)
			(size 0.24994 1.54991)
			(layers "F.Cu" "F.Mask" "F.Paste")
		)
		(pad "B-77" smd rect
			(at 8.29856 -16.77035)
			(size 0.24994 1.54991)
			(layers "F.Cu" "F.Mask" "F.Paste")
			(net "UART1_RXD")
		)
		(pad "B-78" smd rect
			(at 8.29856 -20.82012)
			(size 0.24994 1.54991)
			(layers "F.Cu" "F.Mask" "F.Paste")
		)
		(pad "B-79" smd rect
			(at 8.79869 -16.77035)
			(size 0.24994 1.54991)
			(layers "F.Cu" "F.Mask" "F.Paste")
			(net "GPS1_RX")
		)
		(pad "B-80" smd rect
			(at 8.79869 -20.82012)
			(size 0.24994 1.54991)
			(layers "F.Cu" "F.Mask" "F.Paste")
			(net "GPS1_TX")
		)
		(pad "B-81" smd rect
			(at -12.125 -18.8)
			(size 1.35001 1.70002)
			(layers "F.Cu" "F.Mask" "F.Paste")
		)
		(pad "B-82" thru_hole circle
			(at -10.95134 -18.79524)
			(size 0.55016 0.55016)
			(drill 0.55016)
			(layers "*.Cu" "*.Mask")
			(remove_unused_layers no)
			(thermal_bridge_angle 90)
		)
		(pad "B-83" thru_hole circle
			(at 9.04862 -18.79524)
			(size 0.55016 0.55016)
			(drill 0.55016)
			(layers "*.Cu" "*.Mask")
			(remove_unused_layers no)
			(thermal_bridge_angle 90)
		)
		(pad "B-84" smd rect
			(at 10.225 -18.8)
			(size 1.35001 1.70002)
			(layers "F.Cu" "F.Mask" "F.Paste")
		)
		(pad "C-1" smd rect
			(at -21.78647 9.62381)
			(size 1.54991 0.24994)
			(layers "F.Cu" "F.Mask" "F.Paste")
			(net "GPS2_RX")
		)
		(pad "C-2" smd rect
			(at -25.83625 9.62381)
			(size 1.54991 0.24994)
			(layers "F.Cu" "F.Mask" "F.Paste")
			(net "GPS2_TX")
		)
		(pad "C-3" smd rect
			(at -21.78647 9.12368)
			(size 1.54991 0.24994)
			(layers "F.Cu" "F.Mask" "F.Paste")
		)
		(pad "C-4" smd rect
			(at -25.83625 9.12368)
			(size 1.54991 0.24994)
			(layers "F.Cu" "F.Mask" "F.Paste")
		)
		(pad "C-5" smd rect
			(at -21.78647 8.62381)
			(size 1.54991 0.24994)
			(layers "F.Cu" "F.Mask" "F.Paste")
		)
		(pad "C-6" smd rect
			(at -25.83625 8.62381)
			(size 1.54991 0.24994)
			(layers "F.Cu" "F.Mask" "F.Paste")
		)
		(pad "C-7" smd rect
			(at -21.78647 8.12368)
			(size 1.54991 0.24994)
			(layers "F.Cu" "F.Mask" "F.Paste")
		)
		(pad "C-8" smd rect
			(at -25.83625 8.12368)
			(size 1.54991 0.24994)
			(layers "F.Cu" "F.Mask" "F.Paste")
		)
		(pad "C-9" smd rect
			(at -21.78647 7.62381)
			(size 1.54991 0.24994)
			(layers "F.Cu" "F.Mask" "F.Paste")
			(net "GND")
		)
		(pad "C-10" smd rect
			(at -25.83625 7.62381)
			(size 1.54991 0.24994)
			(layers "F.Cu" "F.Mask" "F.Paste")
			(net "GND")
		)
		(pad "C-11" smd rect
			(at -21.78647 7.12369)
			(size 1.54991 0.24994)
			(layers "F.Cu" "F.Mask" "F.Paste")
		)
		(pad "C-12" smd rect
			(at -25.83625 7.12369)
			(size 1.54991 0.24994)
			(layers "F.Cu" "F.Mask" "F.Paste")
		)
		(pad "C-13" smd rect
			(at -21.78647 6.62381)
			(size 1.54991 0.24994)
			(layers "F.Cu" "F.Mask" "F.Paste")
		)
		(pad "C-14" smd rect
			(at -25.83625 6.62381)
			(size 1.54991 0.24994)
			(layers "F.Cu" "F.Mask" "F.Paste")
		)
		(pad "C-15" smd rect
			(at -21.78647 6.12369)
			(size 1.54991 0.24994)
			(layers "F.Cu" "F.Mask" "F.Paste")
		)
		(pad "C-16" smd rect
			(at -25.83625 6.12369)
			(size 1.54991 0.24994)
			(layers "F.Cu" "F.Mask" "F.Paste")
		)
		(pad "C-17" smd rect
			(at -21.78647 5.62382)
			(size 1.54991 0.24994)
			(layers "F.Cu" "F.Mask" "F.Paste")
		)
		(pad "C-18" smd rect
			(at -25.83625 5.62382)
			(size 1.54991 0.24994)
			(layers "F.Cu" "F.Mask" "F.Paste")
		)
		(pad "C-19" smd rect
			(at -21.78647 5.12369)
			(size 1.54991 0.24994)
			(layers "F.Cu" "F.Mask" "F.Paste")
			(net "GND")
		)
		(pad "C-20" smd rect
			(at -25.83625 5.12369)
			(size 1.54991 0.24994)
			(layers "F.Cu" "F.Mask" "F.Paste")
			(net "GND")
		)
		(pad "C-21" smd rect
			(at -21.78647 4.62382)
			(size 1.54991 0.24994)
			(layers "F.Cu" "F.Mask" "F.Paste")
			(net "PCIE_PERST")
		)
		(pad "C-22" smd rect
			(at -25.83625 4.62382)
			(size 1.54991 0.24994)
			(layers "F.Cu" "F.Mask" "F.Paste")
		)
		(pad "C-23" smd rect
			(at -21.78647 4.12369)
			(size 1.54991 0.24994)
			(layers "F.Cu" "F.Mask" "F.Paste")
			(net "KEY1")
		)
		(pad "C-24" smd rect
			(at -25.83625 4.12369)
			(size 1.54991 0.24994)
			(layers "F.Cu" "F.Mask" "F.Paste")
		)
		(pad "C-25" smd rect
			(at -21.78647 3.62382)
			(size 1.54991 0.24994)
			(layers "F.Cu" "F.Mask" "F.Paste")
		)
		(pad "C-26" smd rect
			(at -25.83625 3.62382)
			(size 1.54991 0.24994)
			(layers "F.Cu" "F.Mask" "F.Paste")
		)
		(pad "C-27" smd rect
			(at -21.78647 3.12369)
			(size 1.54991 0.24994)
			(layers "F.Cu" "F.Mask" "F.Paste")
		)
		(pad "C-28" smd rect
			(at -25.83625 3.12369)
			(size 1.54991 0.24994)
			(layers "F.Cu" "F.Mask" "F.Paste")
		)
		(pad "C-29" smd rect
			(at -21.78647 2.62382)
			(size 1.54991 0.24994)
			(layers "F.Cu" "F.Mask" "F.Paste")
			(net "GND")
		)
		(pad "C-30" smd rect
			(at -25.83625 2.62382)
			(size 1.54991 0.24994)
			(layers "F.Cu" "F.Mask" "F.Paste")
			(net "GND")
		)
		(pad "C-31" smd rect
			(at -21.78647 2.1237)
			(size 1.54991 0.24994)
			(layers "F.Cu" "F.Mask" "F.Paste")
			(net "IMU_ENV_SCL")
		)
		(pad "C-32" smd rect
			(at -25.83625 2.1237)
			(size 1.54991 0.24994)
			(layers "F.Cu" "F.Mask" "F.Paste")
		)
		(pad "C-33" smd rect
			(at -21.78647 1.62382)
			(size 1.54991 0.24994)
			(layers "F.Cu" "F.Mask" "F.Paste")
		)
		(pad "C-34" smd rect
			(at -25.83625 1.62382)
			(size 1.54991 0.24994)
			(layers "F.Cu" "F.Mask" "F.Paste")
		)
		(pad "C-35" smd rect
			(at -21.78647 1.1237)
			(size 1.54991 0.24994)
			(layers "F.Cu" "F.Mask" "F.Paste")
		)
		(pad "C-36" smd rect
			(at -25.83625 1.1237)
			(size 1.54991 0.24994)
			(layers "F.Cu" "F.Mask" "F.Paste")
		)
		(pad "C-37" smd rect
			(at -21.78647 0.62383)
			(size 1.54991 0.24994)
			(layers "F.Cu" "F.Mask" "F.Paste")
			(net "IMU_ENV_SDA")
		)
		(pad "C-38" smd rect
			(at -25.83625 0.62383)
			(size 1.54991 0.24994)
			(layers "F.Cu" "F.Mask" "F.Paste")
		)
		(pad "C-39" smd rect
			(at -21.78647 0.1237)
			(size 1.54991 0.24994)
			(layers "F.Cu" "F.Mask" "F.Paste")
			(net "GND")
		)
		(pad "C-40" smd rect
			(at -25.83625 0.1237)
			(size 1.54991 0.24994)
			(layers "F.Cu" "F.Mask" "F.Paste")
			(net "GND")
		)
		(pad "C-41" smd rect
			(at -21.78647 -0.37617)
			(size 1.54991 0.24994)
			(layers "F.Cu" "F.Mask" "F.Paste")
		)
		(pad "C-42" smd rect
			(at -25.83625 -0.37617)
			(size 1.54991 0.24994)
			(layers "F.Cu" "F.Mask" "F.Paste")
		)
		(pad "C-43" smd rect
			(at -21.78647 -0.8763)
			(size 1.54991 0.24994)
			(layers "F.Cu" "F.Mask" "F.Paste")
		)
		(pad "C-44" smd rect
			(at -25.83625 -0.8763)
			(size 1.54991 0.24994)
			(layers "F.Cu" "F.Mask" "F.Paste")
		)
		(pad "C-45" smd rect
			(at -21.78647 -1.37617)
			(size 1.54991 0.24994)
			(layers "F.Cu" "F.Mask" "F.Paste")
		)
		(pad "C-46" smd rect
			(at -25.83625 -1.37617)
			(size 1.54991 0.24994)
			(layers "F.Cu" "F.Mask" "F.Paste")
		)
		(pad "C-47" smd rect
			(at -21.78647 -1.8763)
			(size 1.54991 0.24994)
			(layers "F.Cu" "F.Mask" "F.Paste")
		)
		(pad "C-48" smd rect
			(at -25.83625 -1.8763)
			(size 1.54991 0.24994)
			(layers "F.Cu" "F.Mask" "F.Paste")
		)
		(pad "C-49" smd rect
			(at -21.78647 -2.37617)
			(size 1.54991 0.24994)
			(layers "F.Cu" "F.Mask" "F.Paste")
			(net "GND")
		)
		(pad "C-50" smd rect
			(at -25.83625 -2.37617)
			(size 1.54991 0.24994)
			(layers "F.Cu" "F.Mask" "F.Paste")
			(net "GND")
		)
		(pad "C-51" smd rect
			(at -21.78647 -2.87629)
			(size 1.54991 0.24994)
			(layers "F.Cu" "F.Mask" "F.Paste")
			(net "RTC_MFP")
		)
		(pad "C-52" smd rect
			(at -25.83625 -2.87629)
			(size 1.54991 0.24994)
			(layers "F.Cu" "F.Mask" "F.Paste")
		)
		(pad "C-53" smd rect
			(at -21.78647 -3.37617)
			(size 1.54991 0.24994)
			(layers "F.Cu" "F.Mask" "F.Paste")
		)
		(pad "C-54" smd rect
			(at -25.83625 -3.37617)
			(size 1.54991 0.24994)
			(layers "F.Cu" "F.Mask" "F.Paste")
		)
		(pad "C-55" smd rect
			(at -21.78647 -3.87629)
			(size 1.54991 0.24994)
			(layers "F.Cu" "F.Mask" "F.Paste")
		)
		(pad "C-56" smd rect
			(at -25.83625 -3.87629)
			(size 1.54991 0.24994)
			(layers "F.Cu" "F.Mask" "F.Paste")
		)
		(pad "C-57" smd rect
			(at -21.78647 -4.37616)
			(size 1.54991 0.24994)
			(layers "F.Cu" "F.Mask" "F.Paste")
		)
		(pad "C-58" smd rect
			(at -25.83625 -4.37616)
			(size 1.54991 0.24994)
			(layers "F.Cu" "F.Mask" "F.Paste")
		)
		(pad "C-59" smd rect
			(at -21.78647 -4.87629)
			(size 1.54991 0.24994)
			(layers "F.Cu" "F.Mask" "F.Paste")
			(net "GND")
		)
		(pad "C-60" smd rect
			(at -25.83625 -4.87629)
			(size 1.54991 0.24994)
			(layers "F.Cu" "F.Mask" "F.Paste")
			(net "GND")
		)
		(pad "C-61" smd rect
			(at -21.78647 -5.37616)
			(size 1.54991 0.24994)
			(layers "F.Cu" "F.Mask" "F.Paste")
		)
		(pad "C-62" smd rect
			(at -25.83625 -5.37616)
			(size 1.54991 0.24994)
			(layers "F.Cu" "F.Mask" "F.Paste")
		)
		(pad "C-63" smd rect
			(at -21.78647 -5.87629)
			(size 1.54991 0.24994)
			(layers "F.Cu" "F.Mask" "F.Paste")
		)
		(pad "C-64" smd rect
			(at -25.83625 -5.87629)
			(size 1.54991 0.24994)
			(layers "F.Cu" "F.Mask" "F.Paste")
		)
		(pad "C-65" smd rect
			(at -21.78647 -6.37616)
			(size 1.54991 0.24994)
			(layers "F.Cu" "F.Mask" "F.Paste")
		)
		(pad "C-66" smd rect
			(at -25.83625 -6.37616)
			(size 1.54991 0.24994)
			(layers "F.Cu" "F.Mask" "F.Paste")
		)
		(pad "C-67" smd rect
			(at -21.78647 -6.87629)
			(size 1.54991 0.24994)
			(layers "F.Cu" "F.Mask" "F.Paste")
		)
		(pad "C-68" smd rect
			(at -25.83625 -6.87629)
			(size 1.54991 0.24994)
			(layers "F.Cu" "F.Mask" "F.Paste")
		)
		(pad "C-69" smd rect
			(at -21.78647 -7.37616)
			(size 1.54991 0.24994)
			(layers "F.Cu" "F.Mask" "F.Paste")
			(net "GND")
		)
		(pad "C-70" smd rect
			(at -25.83625 -7.37616)
			(size 1.54991 0.24994)
			(layers "F.Cu" "F.Mask" "F.Paste")
			(net "GND")
		)
		(pad "C-71" smd rect
			(at -21.78647 -7.87628)
			(size 1.54991 0.24994)
			(layers "F.Cu" "F.Mask" "F.Paste")
		)
		(pad "C-72" smd rect
			(at -25.83625 -7.87628)
			(size 1.54991 0.24994)
			(layers "F.Cu" "F.Mask" "F.Paste")
		)
		(pad "C-73" smd rect
			(at -21.78647 -8.37616)
			(size 1.54991 0.24994)
			(layers "F.Cu" "F.Mask" "F.Paste")
		)
		(pad "C-74" smd rect
			(at -25.83625 -8.37616)
			(size 1.54991 0.24994)
			(layers "F.Cu" "F.Mask" "F.Paste")
		)
		(pad "C-75" smd rect
			(at -21.78647 -8.87628)
			(size 1.54991 0.24994)
			(layers "F.Cu" "F.Mask" "F.Paste")
		)
		(pad "C-76" smd rect
			(at -25.83625 -8.87628)
			(size 1.54991 0.24994)
			(layers "F.Cu" "F.Mask" "F.Paste")
		)
		(pad "C-77" smd rect
			(at -21.78647 -9.37615)
			(size 1.54991 0.24994)
			(layers "F.Cu" "F.Mask" "F.Paste")
			(net "FPGA_TCK")
		)
		(pad "C-78" smd rect
			(at -25.83625 -9.37615)
			(size 1.54991 0.24994)
			(layers "F.Cu" "F.Mask" "F.Paste")
			(net "FPGA_TDI")
		)
		(pad "C-79" smd rect
			(at -21.78647 -9.87628)
			(size 1.54991 0.24994)
			(layers "F.Cu" "F.Mask" "F.Paste")
			(net "FPGA_TDO")
		)
		(pad "C-80" smd rect
			(at -25.83625 -9.87628)
			(size 1.54991 0.24994)
			(layers "F.Cu" "F.Mask" "F.Paste")
			(net "FPGA_TMS")
		)
		(pad "C-81" smd rect
			(at -23.8 11.05)
			(size 1.70002 1.35001)
			(layers "F.Cu" "F.Mask" "F.Paste")
		)
		(pad "C-82" thru_hole circle
			(at -23.81136 9.87374)
			(size 0.55016 0.55016)
			(drill 0.55016)
			(layers "*.Cu" "*.Mask")
			(remove_unused_layers no)
			(thermal_bridge_angle 90)
		)
		(pad "C-83" thru_hole circle
			(at -23.81136 -10.12622)
			(size 0.55016 0.55016)
			(drill 0.55016)
			(layers "*.Cu" "*.Mask")
			(remove_unused_layers no)
			(thermal_bridge_angle 90)
		)
		(pad "C-84" smd rect
			(at -23.8 -11.3)
			(size 1.70002 1.35001)
			(layers "F.Cu" "F.Mask" "F.Paste")
		)
		(pad "D-1" smd rect
			(at 8.79894 16.77035)
			(size 0.24994 1.54991)
			(layers "F.Cu" "F.Mask" "F.Paste")
		)
		(pad "D-2" smd rect
			(at 8.79894 20.82013)
			(size 0.24994 1.54991)
			(layers "F.Cu" "F.Mask" "F.Paste")
		)
		(pad "D-3" smd rect
			(at 8.29881 16.77035)
			(size 0.24994 1.54991)
			(layers "F.Cu" "F.Mask" "F.Paste")
		)
		(pad "D-4" smd rect
			(at 8.29881 20.82013)
			(size 0.24994 1.54991)
			(layers "F.Cu" "F.Mask" "F.Paste")
		)
		(pad "D-5" smd rect
			(at 7.79894 16.77035)
			(size 0.24994 1.54991)
			(layers "F.Cu" "F.Mask" "F.Paste")
		)
		(pad "D-6" smd rect
			(at 7.79894 20.82013)
			(size 0.24994 1.54991)
			(layers "F.Cu" "F.Mask" "F.Paste")
		)
		(pad "D-7" smd rect
			(at 7.29882 16.77035)
			(size 0.24994 1.54991)
			(layers "F.Cu" "F.Mask" "F.Paste")
		)
		(pad "D-8" smd rect
			(at 7.29882 20.82013)
			(size 0.24994 1.54991)
			(layers "F.Cu" "F.Mask" "F.Paste")
		)
		(pad "D-9" smd rect
			(at 6.79894 16.77035)
			(size 0.24994 1.54991)
			(layers "F.Cu" "F.Mask" "F.Paste")
			(net "GND")
		)
		(pad "D-10" smd rect
			(at 6.79894 20.82013)
			(size 0.24994 1.54991)
			(layers "F.Cu" "F.Mask" "F.Paste")
			(net "GND")
		)
		(pad "D-11" smd rect
			(at 6.29882 16.77035)
			(size 0.24994 1.54991)
			(layers "F.Cu" "F.Mask" "F.Paste")
		)
		(pad "D-12" smd rect
			(at 6.29882 20.82013)
			(size 0.24994 1.54991)
			(layers "F.Cu" "F.Mask" "F.Paste")
			(net "PCIE_TX2_P")
		)
		(pad "D-13" smd rect
			(at 5.79895 16.77035)
			(size 0.24994 1.54991)
			(layers "F.Cu" "F.Mask" "F.Paste")
		)
		(pad "D-14" smd rect
			(at 5.79895 20.82013)
			(size 0.24994 1.54991)
			(layers "F.Cu" "F.Mask" "F.Paste")
			(net "PCIE_TX2_N")
		)
		(pad "D-15" smd rect
			(at 5.29882 16.77035)
			(size 0.24994 1.54991)
			(layers "F.Cu" "F.Mask" "F.Paste")
			(net "GND")
		)
		(pad "D-16" smd rect
			(at 5.29882 20.82013)
			(size 0.24994 1.54991)
			(layers "F.Cu" "F.Mask" "F.Paste")
		)
		(pad "D-17" smd rect
			(at 4.79895 16.77035)
			(size 0.24994 1.54991)
			(layers "F.Cu" "F.Mask" "F.Paste")
			(net "PCIE_TX3_P")
		)
		(pad "D-18" smd rect
			(at 4.79895 20.82013)
			(size 0.24994 1.54991)
			(layers "F.Cu" "F.Mask" "F.Paste")
			(net "PCIE_RX2_P")
		)
		(pad "D-19" smd rect
			(at 4.29882 16.77035)
			(size 0.24994 1.54991)
			(layers "F.Cu" "F.Mask" "F.Paste")
			(net "PCIE_TX3_N")
		)
		(pad "D-20" smd rect
			(at 4.29882 20.82013)
			(size 0.24994 1.54991)
			(layers "F.Cu" "F.Mask" "F.Paste")
			(net "PCIE_RX2_N")
		)
		(pad "D-21" smd rect
			(at 3.79895 16.77035)
			(size 0.24994 1.54991)
			(layers "F.Cu" "F.Mask" "F.Paste")
			(net "GND")
		)
		(pad "D-22" smd rect
			(at 3.79895 20.82013)
			(size 0.24994 1.54991)
			(layers "F.Cu" "F.Mask" "F.Paste")
		)
		(pad "D-23" smd rect
			(at 3.29882 16.77035)
			(size 0.24994 1.54991)
			(layers "F.Cu" "F.Mask" "F.Paste")
			(net "PCIE_RX3_P")
		)
		(pad "D-24" smd rect
			(at 3.29882 20.82013)
			(size 0.24994 1.54991)
			(layers "F.Cu" "F.Mask" "F.Paste")
			(net "PCIE_TX1_P")
		)
		(pad "D-25" smd rect
			(at 2.79895 16.77035)
			(size 0.24994 1.54991)
			(layers "F.Cu" "F.Mask" "F.Paste")
			(net "PCIE_RX3_N")
		)
		(pad "D-26" smd rect
			(at 2.79895 20.82013)
			(size 0.24994 1.54991)
			(layers "F.Cu" "F.Mask" "F.Paste")
			(net "PCIE_TX1_N")
		)
		(pad "D-27" smd rect
			(at 2.29883 16.77035)
			(size 0.24994 1.54991)
			(layers "F.Cu" "F.Mask" "F.Paste")
			(net "GND")
		)
		(pad "D-28" smd rect
			(at 2.29883 20.82013)
			(size 0.24994 1.54991)
			(layers "F.Cu" "F.Mask" "F.Paste")
		)
		(pad "D-29" smd rect
			(at 1.79895 16.77035)
			(size 0.24994 1.54991)
			(layers "F.Cu" "F.Mask" "F.Paste")
			(net "PCIE_TX0_P")
		)
		(pad "D-30" smd rect
			(at 1.79895 20.82013)
			(size 0.24994 1.54991)
			(layers "F.Cu" "F.Mask" "F.Paste")
			(net "PCIE_RX1_P")
		)
		(pad "D-31" smd rect
			(at 1.29883 16.77035)
			(size 0.24994 1.54991)
			(layers "F.Cu" "F.Mask" "F.Paste")
			(net "PCIE_TX0_N")
		)
		(pad "D-32" smd rect
			(at 1.29883 20.82013)
			(size 0.24994 1.54991)
			(layers "F.Cu" "F.Mask" "F.Paste")
			(net "PCIE_RX1_N")
		)
		(pad "D-33" smd rect
			(at 0.79896 16.77035)
			(size 0.24994 1.54991)
			(layers "F.Cu" "F.Mask" "F.Paste")
			(net "GND")
		)
		(pad "D-34" smd rect
			(at 0.79896 20.82013)
			(size 0.24994 1.54991)
			(layers "F.Cu" "F.Mask" "F.Paste")
		)
		(pad "D-35" smd rect
			(at 0.29883 16.77035)
			(size 0.24994 1.54991)
			(layers "F.Cu" "F.Mask" "F.Paste")
			(net "PCIE_RX0_P")
		)
		(pad "D-36" smd rect
			(at 0.29883 20.82013)
			(size 0.24994 1.54991)
			(layers "F.Cu" "F.Mask" "F.Paste")
			(net "PCIE_CLK_P")
		)
		(pad "D-37" smd rect
			(at -0.20104 16.77035)
			(size 0.24994 1.54991)
			(layers "F.Cu" "F.Mask" "F.Paste")
			(net "PCIE_RX0_N")
		)
		(pad "D-38" smd rect
			(at -0.20104 20.82013)
			(size 0.24994 1.54991)
			(layers "F.Cu" "F.Mask" "F.Paste")
			(net "PCIE_CLK_N")
		)
		(pad "D-39" smd rect
			(at -0.70117 16.77035)
			(size 0.24994 1.54991)
			(layers "F.Cu" "F.Mask" "F.Paste")
			(net "GND")
		)
		(pad "D-40" smd rect
			(at -0.70117 20.82013)
			(size 0.24994 1.54991)
			(layers "F.Cu" "F.Mask" "F.Paste")
			(net "GND")
		)
		(pad "D-41" smd rect
			(at -1.20104 16.77035)
			(size 0.24994 1.54991)
			(layers "F.Cu" "F.Mask" "F.Paste")
		)
		(pad "D-42" smd rect
			(at -1.20104 20.82013)
			(size 0.24994 1.54991)
			(layers "F.Cu" "F.Mask" "F.Paste")
		)
		(pad "D-43" smd rect
			(at -1.70117 16.77035)
			(size 0.24994 1.54991)
			(layers "F.Cu" "F.Mask" "F.Paste")
		)
		(pad "D-44" smd rect
			(at -1.70117 20.82013)
			(size 0.24994 1.54991)
			(layers "F.Cu" "F.Mask" "F.Paste")
		)
		(pad "D-45" smd rect
			(at -2.20104 16.77035)
			(size 0.24994 1.54991)
			(layers "F.Cu" "F.Mask" "F.Paste")
		)
		(pad "D-46" smd rect
			(at -2.20104 20.82013)
			(size 0.24994 1.54991)
			(layers "F.Cu" "F.Mask" "F.Paste")
		)
		(pad "D-47" smd rect
			(at -2.70116 16.77035)
			(size 0.24994 1.54991)
			(layers "F.Cu" "F.Mask" "F.Paste")
		)
		(pad "D-48" smd rect
			(at -2.70116 20.82013)
			(size 0.24994 1.54991)
			(layers "F.Cu" "F.Mask" "F.Paste")
		)
		(pad "D-49" smd rect
			(at -3.20104 16.77035)
			(size 0.24994 1.54991)
			(layers "F.Cu" "F.Mask" "F.Paste")
			(net "GND")
		)
		(pad "D-50" smd rect
			(at -3.20104 20.82013)
			(size 0.24994 1.54991)
			(layers "F.Cu" "F.Mask" "F.Paste")
			(net "GND")
		)
		(pad "D-51" smd rect
			(at -3.70116 16.77035)
			(size 0.24994 1.54991)
			(layers "F.Cu" "F.Mask" "F.Paste")
		)
		(pad "D-52" smd rect
			(at -3.70116 20.82013)
			(size 0.24994 1.54991)
			(layers "F.Cu" "F.Mask" "F.Paste")
		)
		(pad "D-53" smd rect
			(at -4.20103 16.77035)
			(size 0.24994 1.54991)
			(layers "F.Cu" "F.Mask" "F.Paste")
		)
		(pad "D-54" smd rect
			(at -4.20103 20.82013)
			(size 0.24994 1.54991)
			(layers "F.Cu" "F.Mask" "F.Paste")
		)
		(pad "D-55" smd rect
			(at -4.70116 16.77035)
			(size 0.24994 1.54991)
			(layers "F.Cu" "F.Mask" "F.Paste")
		)
		(pad "D-56" smd rect
			(at -4.70116 20.82013)
			(size 0.24994 1.54991)
			(layers "F.Cu" "F.Mask" "F.Paste")
		)
		(pad "D-57" smd rect
			(at -5.20103 16.77035)
			(size 0.24994 1.54991)
			(layers "F.Cu" "F.Mask" "F.Paste")
		)
		(pad "D-58" smd rect
			(at -5.20103 20.82013)
			(size 0.24994 1.54991)
			(layers "F.Cu" "F.Mask" "F.Paste")
		)
		(pad "D-59" smd rect
			(at -5.70116 16.77035)
			(size 0.24994 1.54991)
			(layers "F.Cu" "F.Mask" "F.Paste")
			(net "GND")
		)
		(pad "D-60" smd rect
			(at -5.70116 20.82013)
			(size 0.24994 1.54991)
			(layers "F.Cu" "F.Mask" "F.Paste")
			(net "GND")
		)
		(pad "D-61" smd rect
			(at -6.20103 16.77035)
			(size 0.24994 1.54991)
			(layers "F.Cu" "F.Mask" "F.Paste")
		)
		(pad "D-62" smd rect
			(at -6.20103 20.82013)
			(size 0.24994 1.54991)
			(layers "F.Cu" "F.Mask" "F.Paste")
		)
		(pad "D-63" smd rect
			(at -6.70116 16.77035)
			(size 0.24994 1.54991)
			(layers "F.Cu" "F.Mask" "F.Paste")
		)
		(pad "D-64" smd rect
			(at -6.70116 20.82013)
			(size 0.24994 1.54991)
			(layers "F.Cu" "F.Mask" "F.Paste")
		)
		(pad "D-65" smd rect
			(at -7.20103 16.77035)
			(size 0.24994 1.54991)
			(layers "F.Cu" "F.Mask" "F.Paste")
		)
		(pad "D-66" smd rect
			(at -7.20103 20.82013)
			(size 0.24994 1.54991)
			(layers "F.Cu" "F.Mask" "F.Paste")
		)
		(pad "D-67" smd rect
			(at -7.70115 16.77035)
			(size 0.24994 1.54991)
			(layers "F.Cu" "F.Mask" "F.Paste")
		)
		(pad "D-68" smd rect
			(at -7.70115 20.82013)
			(size 0.24994 1.54991)
			(layers "F.Cu" "F.Mask" "F.Paste")
		)
		(pad "D-69" smd rect
			(at -8.20103 16.77035)
			(size 0.24994 1.54991)
			(layers "F.Cu" "F.Mask" "F.Paste")
			(net "GND")
		)
		(pad "D-70" smd rect
			(at -8.20103 20.82013)
			(size 0.24994 1.54991)
			(layers "F.Cu" "F.Mask" "F.Paste")
			(net "GND")
		)
		(pad "D-71" smd rect
			(at -8.70115 16.77035)
			(size 0.24994 1.54991)
			(layers "F.Cu" "F.Mask" "F.Paste")
		)
		(pad "D-72" smd rect
			(at -8.70115 20.82013)
			(size 0.24994 1.54991)
			(layers "F.Cu" "F.Mask" "F.Paste")
		)
		(pad "D-73" smd rect
			(at -9.20102 16.77035)
			(size 0.24994 1.54991)
			(layers "F.Cu" "F.Mask" "F.Paste")
		)
		(pad "D-74" smd rect
			(at -9.20102 20.82013)
			(size 0.24994 1.54991)
			(layers "F.Cu" "F.Mask" "F.Paste")
		)
		(pad "D-75" smd rect
			(at -9.70115 16.77035)
			(size 0.24994 1.54991)
			(layers "F.Cu" "F.Mask" "F.Paste")
		)
		(pad "D-76" smd rect
			(at -9.70115 20.82013)
			(size 0.24994 1.54991)
			(layers "F.Cu" "F.Mask" "F.Paste")
		)
		(pad "D-77" smd rect
			(at -10.20102 16.77035)
			(size 0.24994 1.54991)
			(layers "F.Cu" "F.Mask" "F.Paste")
		)
		(pad "D-78" smd rect
			(at -10.20102 20.82013)
			(size 0.24994 1.54991)
			(layers "F.Cu" "F.Mask" "F.Paste")
		)
		(pad "D-79" smd rect
			(at -10.70115 16.77035)
			(size 0.24994 1.54991)
			(layers "F.Cu" "F.Mask" "F.Paste")
		)
		(pad "D-80" smd rect
			(at -10.70115 20.82013)
			(size 0.24994 1.54991)
			(layers "F.Cu" "F.Mask" "F.Paste")
		)
		(pad "D-81" smd rect
			(at 10.225 18.8)
			(size 1.35001 1.70002)
			(layers "F.Cu" "F.Mask" "F.Paste")
		)
		(pad "D-82" thru_hole circle
			(at 9.04888 18.79524)
			(size 0.55016 0.55016)
			(drill 0.55016)
			(layers "*.Cu" "*.Mask")
			(remove_unused_layers no)
			(thermal_bridge_angle 90)
		)
		(pad "D-83" thru_hole circle
			(at -10.95108 18.79524)
			(size 0.55016 0.55016)
			(drill 0.55016)
			(layers "*.Cu" "*.Mask")
			(remove_unused_layers no)
			(thermal_bridge_angle 90)
		)
		(pad "D-84" smd rect
			(at -12.125 18.8)
			(size 1.35001 1.70002)
			(layers "F.Cu" "F.Mask" "F.Paste")
		)
		(pad "MNT-1" thru_hole rect
			(at -24.95156 -20.00834)
			(size 0 0)
			(drill 2.99999)
			(layers "*.Cu" "*.Mask")
			(remove_unused_layers no)
		)
		(pad "MNT-2" thru_hole rect
			(at 24.98484 -20.00834)
			(size 0 0)
			(drill 2.99999)
			(layers "*.Cu" "*.Mask")
			(remove_unused_layers no)
		)
		(pad "MNT-3" thru_hole rect
			(at 24.98484 19.86966)
			(size 0 0)
			(drill 2.99999)
			(layers "*.Cu" "*.Mask")
			(remove_unused_layers no)
		)
		(pad "MNT-4" thru_hole rect
			(at -24.92616 19.86966)
			(size 0 0)
			(drill 2.99999)
			(layers "*.Cu" "*.Mask")
			(remove_unused_layers no)
		)
	)
	(footprint "Miscellaneous:L101011MS02Q"
		(layer "F.Cu")
		(at 201.013595 62.9286 180)
		(property "Reference" "SW1"
			(at 5.57487 -11.713655 0)
			(unlocked yes)
			(layer "F.SilkS")
			(effects
				(font
					(size 0.762 0.762)
					(thickness 0.2286)
				)
				(justify left bottom)
			)
		)
		(property "Value" "L101011MS02Q"
			(at 5.6261 -12.41679 0)
			(unlocked yes)
			(layer "F.SilkS")
			(hide yes)
			(effects
				(font
					(size 1.524 1.524)
					(thickness 0.254)
				)
				(justify left bottom)
			)
		)
		(sheetname "POWER")
		(sheetfile "POWER.kicad_sch")
		(duplicate_pad_numbers_are_jumpers no)
		(fp_line
			(start 5.44828 9.652)
			(end -5.588 9.652)
			(stroke
				(width 0.1524)
				(type solid)
			)
			(layer "F.SilkS")
		)
		(fp_line
			(start 5.44828 3.50504)
			(end 5.44828 9.652)
			(stroke
				(width 0.1524)
				(type solid)
			)
			(layer "F.SilkS")
		)
		(fp_line
			(start 5.44828 -9.652)
			(end 5.44828 3.50504)
			(stroke
				(width 0.1524)
				(type solid)
			)
			(layer "F.SilkS")
		)
		(fp_line
			(start 5.44828 -9.652)
			(end -5.588 -9.652)
			(stroke
				(width 0.1524)
				(type solid)
			)
			(layer "F.SilkS")
		)
		(fp_line
			(start -5.588 -9.652)
			(end -5.588 9.652)
			(stroke
				(width 0.1524)
				(type solid)
			)
			(layer "F.SilkS")
		)
		(pad "1" thru_hole circle
			(at -2.85 4.6 180)
			(size 2.5 2.5)
			(drill 1.65)
			(layers "*.Cu" "*.Mask")
			(remove_unused_layers no)
			(net "NetD2_1")
			(thermal_bridge_angle 90)
		)
		(pad "2" thru_hole circle
			(at -2.85 0 180)
			(size 2.5 2.5)
			(drill 1.65)
			(layers "*.Cu" "*.Mask")
			(remove_unused_layers no)
			(net "NetD1_1")
			(thermal_bridge_angle 90)
		)
	)
	(footprint "Passives:SODFL370X135-2N"
		(layer "F.Cu")
		(at 217.869595 70.0006)
		(property "Reference" "D2"
			(at 3.512345 0.578 90)
			(unlocked yes)
			(layer "F.SilkS")
			(effects
				(font
					(size 0.762 0.762)
					(thickness 0.2286)
				)
				(justify left bottom)
			)
		)
		(property "Value" "DFLZ39-TP"
			(at -2.0955 3.62839 0)
			(unlocked yes)
			(layer "F.SilkS")
			(hide yes)
			(effects
				(font
					(size 1.524 1.524)
					(thickness 0.254)
				)
				(justify left bottom)
			)
		)
		(sheetname "POWER")
		(sheetfile "POWER.kicad_sch")
		(duplicate_pad_numbers_are_jumpers no)
		(fp_line
			(start -1.55 -0.95)
			(end 1.55 -0.95)
			(stroke
				(width 0.2)
				(type solid)
			)
			(layer "F.SilkS")
		)
		(fp_line
			(start -1.55 -0.825)
			(end -1.55 -0.95)
			(stroke
				(width 0.2)
				(type solid)
			)
			(layer "F.SilkS")
		)
		(fp_line
			(start -1.55 0.95)
			(end -1.55 0.825)
			(stroke
				(width 0.2)
				(type solid)
			)
			(layer "F.SilkS")
		)
		(fp_line
			(start -1.55 0.95)
			(end 1.55 0.95)
			(stroke
				(width 0.2)
				(type solid)
			)
			(layer "F.SilkS")
		)
		(fp_line
			(start 1.55 -0.825)
			(end 1.55 -0.95)
			(stroke
				(width 0.2)
				(type solid)
			)
			(layer "F.SilkS")
		)
		(fp_line
			(start 1.55 0.95)
			(end 1.55 0.825)
			(stroke
				(width 0.2)
				(type solid)
			)
			(layer "F.SilkS")
		)
		(fp_circle
			(center -2.05 -0.825)
			(end -2.05 -0.875)
			(stroke
				(width 0.1)
				(type solid)
			)
			(fill no)
			(layer "F.SilkS")
		)
		(pad "1" smd rect
			(at -1.825 0 90)
			(size 1.05 0.65)
			(layers "F.Cu" "F.Mask" "F.Paste")
			(net "NetD2_1")
		)
		(pad "2" smd rect
			(at 1.825 0 90)
			(size 1.05 0.65)
			(layers "F.Cu" "F.Mask" "F.Paste")
			(net "NetD2_2")
		)
	)
	(footprint "SamacSys:BMP388"
		(layer "F.Cu")
		(at 140.763595 89.0786)
		(property "Reference" "U4"
			(at -0.313405 -2.921949 0)
			(unlocked yes)
			(layer "F.SilkS")
			(effects
				(font
					(size 0.762 0.762)
					(thickness 0.254)
				)
			)
		)
		(property "Value" "BMP388"
			(at 3.364105 3.038602 0)
			(unlocked yes)
			(layer "F.SilkS")
			(hide yes)
			(effects
				(font
					(size 1.524 1.524)
					(thickness 0.254)
				)
			)
		)
		(sheetname "GPS_IMU_SENSORS")
		(sheetfile "GPS_IMU_SENSORS.kicad_sch")
		(duplicate_pad_numbers_are_jumpers no)
		(fp_line
			(start -1 -1)
			(end -0.5 -1)
			(stroke
				(width 0.1)
				(type solid)
			)
			(layer "F.SilkS")
		)
		(fp_line
			(start -1 -0.8)
			(end -1 -1)
			(stroke
				(width 0.1)
				(type solid)
			)
			(layer "F.SilkS")
		)
		(fp_line
			(start -1 1)
			(end -1 0.8)
			(stroke
				(width 0.1)
				(type solid)
			)
			(layer "F.SilkS")
		)
		(fp_line
			(start -1 1)
			(end -0.5 1)
			(stroke
				(width 0.1)
				(type solid)
			)
			(layer "F.SilkS")
		)
		(fp_line
			(start 0.5 -1)
			(end 1 -1)
			(stroke
				(width 0.1)
				(type solid)
			)
			(layer "F.SilkS")
		)
		(fp_line
			(start 0.5 1)
			(end 1 1)
			(stroke
				(width 0.1)
				(type solid)
			)
			(layer "F.SilkS")
		)
		(fp_line
			(start 1 -0.8)
			(end 1 -1)
			(stroke
				(width 0.1)
				(type solid)
			)
			(layer "F.SilkS")
		)
		(fp_line
			(start 1 1)
			(end 1 0.8)
			(stroke
				(width 0.1)
				(type solid)
			)
			(layer "F.SilkS")
		)
		(fp_arc
			(start 0.2 -1.3)
			(mid 0.25 -1.35)
			(end 0.3 -1.3)
			(stroke
				(width 0.1)
				(type solid)
			)
			(layer "F.SilkS")
		)
		(fp_arc
			(start 0.3 -1.3)
			(mid 0.25 -1.25)
			(end 0.2 -1.3)
			(stroke
				(width 0.1)
				(type solid)
			)
			(layer "F.SilkS")
		)
		(pad "1" smd rect
			(at 0.25 -0.763 90)
			(size 0.275 0.25)
			(layers "F.Cu" "F.Mask" "F.Paste")
			(net "+3.3V_CLEAN")
		)
		(pad "2" smd rect
			(at -0.25 -0.763 90)
			(size 0.275 0.25)
			(layers "F.Cu" "F.Mask" "F.Paste")
			(net "SCL")
		)
		(pad "3" smd rect
			(at -0.762 -0.5)
			(size 0.275 0.25)
			(layers "F.Cu" "F.Mask" "F.Paste")
			(net "GND")
		)
		(pad "4" smd rect
			(at -0.762 0)
			(size 0.275 0.25)
			(layers "F.Cu" "F.Mask" "F.Paste")
			(net "SDA")
		)
		(pad "5" smd rect
			(at -0.762 0.5)
			(size 0.275 0.25)
			(layers "F.Cu" "F.Mask" "F.Paste")
		)
		(pad "6" smd rect
			(at -0.25 0.763 90)
			(size 0.275 0.25)
			(layers "F.Cu" "F.Mask" "F.Paste")
			(net "+3.3V_CLEAN")
		)
		(pad "7" smd rect
			(at 0.25 0.763 90)
			(size 0.275 0.25)
			(layers "F.Cu" "F.Mask" "F.Paste")
		)
		(pad "8" smd rect
			(at 0.762 0.5)
			(size 0.275 0.25)
			(layers "F.Cu" "F.Mask" "F.Paste")
			(net "GND")
		)
		(pad "9" smd rect
			(at 0.762 0)
			(size 0.275 0.25)
			(layers "F.Cu" "F.Mask" "F.Paste")
			(net "GND")
		)
		(pad "10" smd rect
			(at 0.762 -0.5)
			(size 0.275 0.25)
			(layers "F.Cu" "F.Mask" "F.Paste")
			(net "+3.3V_CLEAN")
		)
	)
	(footprint "Resistors:RESC1608X50N"
		(layer "F.Cu")
		(at 107.608195 56.3862 -90)
		(property "Reference" "R43"
			(at -1.557775 0.96487 0)
			(unlocked yes)
			(layer "F.SilkS")
			(effects
				(font
					(size 0.762 0.762)
					(thickness 0.2286)
				)
				(justify left bottom)
			)
		)
		(property "Value" "ERJ-3EKF1002V"
			(at 3.72999 0.4445 0)
			(unlocked yes)
			(layer "F.SilkS")
			(hide yes)
			(effects
				(font
					(size 1.524 1.524)
					(thickness 0.254)
				)
				(justify left bottom)
			)
		)
		(sheetname "GPS_IMU_SENSORS")
		(sheetfile "GPS_IMU_SENSORS.kicad_sch")
		(duplicate_pad_numbers_are_jumpers no)
		(fp_line
			(start 0 0.5)
			(end 0 -0.5)
			(stroke
				(width 0.1524)
				(type solid)
			)
			(layer "F.SilkS")
		)
		(pad "1" smd rect
			(at -0.69 0)
			(size 1 0.72)
			(layers "F.Cu" "F.Mask" "F.Paste")
			(net "+5.0V")
		)
		(pad "2" smd rect
			(at 0.69 0)
			(size 1 0.72)
			(layers "F.Cu" "F.Mask" "F.Paste")
			(net "NetR43_2")
		)
	)
	(footprint "Miscellaneous Devices:J1-0603"
		(layer "F.Cu")
		(at 92.688595 58.7786 90)
		(property "Reference" "R11"
			(at 0.375005 -1.270584 90)
			(unlocked yes)
			(layer "F.SilkS")
			(effects
				(font
					(face "Arial")
					(size 0.48006 0.48006)
					(thickness 0.254)
				)
			)
		)
		(property "Value" "MACTX"
			(at 0.164598 3.46595 0)
			(unlocked yes)
			(layer "F.SilkS")
			(hide yes)
			(effects
				(font
					(size 1.524 1.524)
					(thickness 0.254)
				)
			)
		)
		(sheetname "GPS_IMU_SENSORS")
		(sheetfile "GPS_IMU_SENSORS.kicad_sch")
		(duplicate_pad_numbers_are_jumpers no)
		(fp_line
			(start -0.2 -0.35)
			(end 0.2 -0.35)
			(stroke
				(width 0.2)
				(type solid)
			)
			(layer "F.SilkS")
		)
		(fp_line
			(start -0.2 0.35)
			(end 0.2 0.35)
			(stroke
				(width 0.2)
				(type solid)
			)
			(layer "F.SilkS")
		)
		(pad "1" smd rect
			(at -0.75 0 180)
			(size 0.9 0.7)
			(layers "F.Cu" "F.Mask" "F.Paste")
			(net "MAC_TX")
		)
		(pad "2" smd rect
			(at 0.75 0 180)
			(size 0.9 0.7)
			(layers "F.Cu" "F.Mask" "F.Paste")
			(net "NetJP1_3")
		)
	)
	(footprint "Capacitors:CAPC2012X14N"
		(layer "F.Cu")
		(at 205.213595 75.2036 180)
		(property "Reference" "C1"
			(at 0.81255 -3.026855 0)
			(unlocked yes)
			(layer "F.SilkS")
			(effects
				(font
					(size 0.762 0.762)
					(thickness 0.2286)
				)
				(justify left bottom)
			)
		)
		(property "Value" "CAP_0805_10UF_25V"
			(at 1.5875 -3.52679 0)
			(unlocked yes)
			(layer "F.SilkS")
			(hide yes)
			(effects
				(font
					(size 1.524 1.524)
					(thickness 0.254)
				)
				(justify left bottom)
			)
		)
		(sheetname "POWER")
		(sheetfile "POWER.kicad_sch")
		(duplicate_pad_numbers_are_jumpers no)
		(fp_line
			(start 0.762 0.9652)
			(end -0.762 0.9652)
			(stroke
				(width 0.1524)
				(type solid)
			)
			(layer "F.SilkS")
		)
		(fp_line
			(start 0.762 -0.9652)
			(end -0.762 -0.9652)
			(stroke
				(width 0.1524)
				(type solid)
			)
			(layer "F.SilkS")
		)
		(pad "1" smd rect
			(at -0.9 0 270)
			(size 1.45 1.15)
			(layers "F.Cu" "F.Mask" "F.Paste")
			(net "+12V")
		)
		(pad "2" smd rect
			(at 0.9 0 270)
			(size 1.45 1.15)
			(layers "F.Cu" "F.Mask" "F.Paste")
			(net "GND")
		)
	)
	(footprint "Vault:RESC1608X50X30NL20T20"
		(layer "F.Cu")
		(at 152.083595 64.4126 180)
		(property "Reference" "R26"
			(at 1.195 -2.459345 0)
			(unlocked yes)
			(layer "F.SilkS")
			(effects
				(font
					(size 0.762 0.762)
					(thickness 0.2286)
				)
				(justify left bottom)
			)
		)
		(property "Value" "499 OHM"
			(at 0.2413 -3.42519 0)
			(unlocked yes)
			(layer "F.SilkS")
			(hide yes)
			(effects
				(font
					(size 1.524 1.524)
					(thickness 0.254)
				)
				(justify left bottom)
			)
		)
		(sheetname "UART")
		(sheetfile "UART.kicad_sch")
		(duplicate_pad_numbers_are_jumpers no)
		(pad "1" smd rect
			(at -0.65 0 270)
			(size 1 0.9)
			(layers "F.Cu" "F.Mask" "F.Paste")
			(net "UART1_TXD")
		)
		(pad "2" smd rect
			(at 0.65 0 270)
			(size 1 0.9)
			(layers "F.Cu" "F.Mask" "F.Paste")
			(net "NetD10_1")
		)
	)
	(footprint "IntegratedCircuits:SOIC127P600X175-8N"
		(layer "F.Cu")
		(at 217.361595 101.7506 180)
		(property "Reference" "U2"
			(at 6.13379 -2.264855 0)
			(unlocked yes)
			(layer "F.SilkS")
			(effects
				(font
					(size 0.762 0.762)
					(thickness 0.2286)
				)
				(justify left bottom)
			)
		)
		(property "Value" "MP1482DS-LF"
			(at -12.7381 8.69061 0)
			(unlocked yes)
			(layer "F.SilkS")
			(hide yes)
			(effects
				(font
					(size 1.524 1.524)
					(thickness 0.254)
				)
				(justify left bottom)
			)
		)
		(sheetname "POWER")
		(sheetfile "POWER.kicad_sch")
		(duplicate_pad_numbers_are_jumpers no)
		(fp_line
			(start 2 2.5)
			(end -2 2.5)
			(stroke
				(width 0.12)
				(type solid)
			)
			(layer "F.SilkS")
		)
		(fp_line
			(start 2 -2.5)
			(end -3.4 -2.5)
			(stroke
				(width 0.12)
				(type solid)
			)
			(layer "F.SilkS")
		)
		(pad "1" smd rect
			(at -2.475 -1.905 180)
			(size 1.97 0.57)
			(layers "F.Cu" "F.Mask" "F.Paste")
			(net "NetC3_1")
		)
		(pad "2" smd rect
			(at -2.475 -0.635 180)
			(size 1.97 0.57)
			(layers "F.Cu" "F.Mask" "F.Paste")
			(net "+12V")
		)
		(pad "3" smd rect
			(at -2.475 0.635 180)
			(size 1.97 0.57)
			(layers "F.Cu" "F.Mask" "F.Paste")
			(net "NetC3_2")
		)
		(pad "4" smd rect
			(at -2.475 1.905 180)
			(size 1.97 0.57)
			(layers "F.Cu" "F.Mask" "F.Paste")
			(net "GND")
		)
		(pad "5" smd rect
			(at 2.475 1.905 180)
			(size 1.97 0.57)
			(layers "F.Cu" "F.Mask" "F.Paste")
			(net "NetR5_1")
		)
		(pad "6" smd rect
			(at 2.475 0.635 180)
			(size 1.97 0.57)
			(layers "F.Cu" "F.Mask" "F.Paste")
			(net "NetC22_2")
		)
		(pad "7" smd rect
			(at 2.475 -0.635 180)
			(size 1.97 0.57)
			(layers "F.Cu" "F.Mask" "F.Paste")
			(net "NetR3_1")
		)
		(pad "8" smd rect
			(at 2.475 -1.905 180)
			(size 1.97 0.57)
			(layers "F.Cu" "F.Mask" "F.Paste")
			(net "NetC21_2")
		)
	)
	(footprint "Capacitors:CAPC2012X14N"
		(layer "F.Cu")
		(at 125.540595 69.8736 -90)
		(property "Reference" "C60"
			(at 4.805 -2.641345 90)
			(unlocked yes)
			(layer "F.SilkS")
			(effects
				(font
					(size 0.762 0.762)
					(thickness 0.2286)
				)
				(justify left bottom)
			)
		)
		(property "Value" "CAP_0805_10UF_25V"
			(at 3.52679 1.5875 0)
			(unlocked yes)
			(layer "F.SilkS")
			(hide yes)
			(effects
				(font
					(size 1.524 1.524)
					(thickness 0.254)
				)
				(justify left bottom)
			)
		)
		(sheetname "GPS_IMU_SENSORS")
		(sheetfile "GPS_IMU_SENSORS.kicad_sch")
		(duplicate_pad_numbers_are_jumpers no)
		(fp_line
			(start 0.762 0.9652)
			(end -0.762 0.9652)
			(stroke
				(width 0.1524)
				(type solid)
			)
			(layer "F.SilkS")
		)
		(fp_line
			(start 0.762 -0.9652)
			(end -0.762 -0.9652)
			(stroke
				(width 0.1524)
				(type solid)
			)
			(layer "F.SilkS")
		)
		(pad "1" smd rect
			(at -0.9 0)
			(size 1.45 1.15)
			(layers "F.Cu" "F.Mask" "F.Paste")
			(net "+5.0V")
		)
		(pad "2" smd rect
			(at 0.9 0)
			(size 1.45 1.15)
			(layers "F.Cu" "F.Mask" "F.Paste")
			(net "GND")
		)
	)
	(footprint "Vault:CAPC1608X90X35NL10T15"
		(layer "F.Cu")
		(at 212.535595 100.6076 90)
		(property "Reference" "C22"
			(at 1.479 0.396345 90)
			(unlocked yes)
			(layer "F.SilkS")
			(effects
				(font
					(size 0.762 0.762)
					(thickness 0.2286)
				)
				(justify left bottom)
			)
		)
		(property "Value" "0.033uF"
			(at 8.20801 25.6159 0)
			(unlocked yes)
			(layer "F.SilkS")
			(hide yes)
			(effects
				(font
					(size 1.524 1.524)
					(thickness 0.254)
				)
				(justify left bottom)
			)
		)
		(sheetname "POWER")
		(sheetfile "POWER.kicad_sch")
		(duplicate_pad_numbers_are_jumpers no)
		(pad "1" smd rect
			(at -0.675 0 180)
			(size 0.95 0.85)
			(layers "F.Cu" "F.Mask" "F.Paste")
			(net "NetC22_1")
		)
		(pad "2" smd rect
			(at 0.675 0 180)
			(size 0.95 0.85)
			(layers "F.Cu" "F.Mask" "F.Paste")
			(net "NetC22_2")
		)
	)
	(footprint "Passives:INDC1608X09N"
		(layer "F.Cu")
		(at 171.133595 89.0506 90)
		(property "Reference" "FB2"
			(at 0.45769 2.417265 90)
			(unlocked yes)
			(layer "F.SilkS")
			(effects
				(font
					(size 0.762 0.762)
					(thickness 0.2286)
				)
				(justify left bottom)
			)
		)
		(property "Value" "MPZ1608_220OHM_0603"
			(at -3.88239 -0.5461 0)
			(unlocked yes)
			(layer "F.SilkS")
			(hide yes)
			(effects
				(font
					(size 1.524 1.524)
					(thickness 0.254)
				)
				(justify left bottom)
			)
		)
		(sheetname "MAC")
		(sheetfile "MAC.kicad_sch")
		(duplicate_pad_numbers_are_jumpers no)
		(pad "1" smd rect
			(at -0.665 0 180)
			(size 0.98 0.87)
			(layers "F.Cu" "F.Mask" "F.Paste")
			(net "+3.3V")
		)
		(pad "2" smd rect
			(at 0.665 0 180)
			(size 0.98 0.87)
			(layers "F.Cu" "F.Mask" "F.Paste")
			(net "NetC72_2")
		)
	)
	(footprint "Passives:DIOM1608X06N"
		(layer "F.Cu")
		(at 167.813595 69.0536)
		(property "Reference" "D4"
			(at 2.175 0.418345 0)
			(unlocked yes)
			(layer "F.SilkS")
			(effects
				(font
					(size 0.762 0.762)
					(thickness 0.2286)
				)
				(justify left bottom)
			)
		)
		(property "Value" "RED"
			(at -1.4097 3.22199 0)
			(unlocked yes)
			(layer "F.SilkS")
			(hide yes)
			(effects
				(font
					(size 1.524 1.524)
					(thickness 0.254)
				)
				(justify left bottom)
			)
		)
		(sheetname "POWER")
		(sheetfile "POWER.kicad_sch")
		(duplicate_pad_numbers_are_jumpers no)
		(fp_circle
			(center -1.275 -0.725)
			(end -1.275 -0.775)
			(stroke
				(width 0.1)
				(type solid)
			)
			(fill no)
			(layer "F.SilkS")
		)
		(pad "1" smd rect
			(at -0.725 0 90)
			(size 0.85 1)
			(layers "F.Cu" "F.Mask" "F.Paste")
			(net "NetD4_1")
		)
		(pad "2" smd rect
			(at 0.725 0 90)
			(size 0.85 1)
			(layers "F.Cu" "F.Mask" "F.Paste")
			(net "+3.3V")
		)
	)
	(footprint "Connectors:39-30-1060"
		(layer "F.Cu")
		(at 225.353595 69.4046 180)
		(property "Reference" "J2"
			(at -9.185 -3.142345 0)
			(unlocked yes)
			(layer "F.SilkS")
			(effects
				(font
					(size 0.762 0.762)
					(thickness 0.2286)
				)
				(justify left bottom)
			)
		)
		(property "Value" "39-30-1060"
			(at 2.8141 -11.19579 0)
			(unlocked yes)
			(layer "F.SilkS")
			(hide yes)
			(effects
				(font
					(size 1.524 1.524)
					(thickness 0.254)
				)
				(justify left bottom)
			)
		)
		(sheetname "POWER")
		(sheetfile "POWER.kicad_sch")
		(duplicate_pad_numbers_are_jumpers no)
		(fp_line
			(start 3.175 -1.524)
			(end 3.175 19.49249)
			(stroke
				(width 0.2032)
				(type solid)
			)
			(layer "F.SilkS")
		)
		(fp_line
			(start 3.175 -1.524)
			(end -11.02502 -1.524)
			(stroke
				(width 0.2032)
				(type solid)
			)
			(layer "F.SilkS")
		)
		(fp_line
			(start -11.02502 -0.44249)
			(end -11.02502 19.49249)
			(stroke
				(width 0.2032)
				(type solid)
			)
			(layer "F.SilkS")
		)
		(fp_line
			(start -11.02502 -1.51445)
			(end -11.02502 -0.44249)
			(stroke
				(width 0.203)
				(type solid)
			)
			(layer "F.SilkS")
		)
		(pad "" np_thru_hole circle
			(at -8.4 12.8 180)
			(size 1.27 1.27)
			(drill 3)
			(layers "*.Cu" "*.Mask")
			(thermal_bridge_angle 90)
		)
		(pad "" np_thru_hole circle
			(at 0 12.8 180)
			(size 1.27 1.27)
			(drill 3)
			(layers "*.Cu" "*.Mask")
			(thermal_bridge_angle 90)
			(padstack
				(mode front_inner_back)
				(layer "Inner"
					(shape circle)
					(size 1.27 1.27)
				)
				(layer "B.Cu"
					(shape circle)
					(size 1.27 1.27)
				)
			)
		)
		(pad "1" thru_hole circle
			(at 0 5.5 270)
			(size 2.5 2.5)
			(drill 1.8)
			(layers "*.Cu" "*.Mask")
			(remove_unused_layers no)
			(net "NetD2_2")
			(thermal_bridge_angle 90)
		)
		(pad "2" thru_hole circle
			(at -4.2 5.5 270)
			(size 2.5 2.5)
			(drill 1.8)
			(layers "*.Cu" "*.Mask")
			(remove_unused_layers no)
			(net "NetD2_2")
			(thermal_bridge_angle 90)
		)
		(pad "3" thru_hole circle
			(at -8.4 5.5 270)
			(size 2.5 2.5)
			(drill 1.8)
			(layers "*.Cu" "*.Mask")
			(remove_unused_layers no)
			(net "NetD2_2")
			(thermal_bridge_angle 90)
		)
		(pad "4" thru_hole circle
			(at 0 0 270)
			(size 2.5 2.5)
			(drill 1.8)
			(layers "*.Cu" "*.Mask")
			(remove_unused_layers no)
			(net "GND")
			(thermal_bridge_angle 90)
		)
		(pad "5" thru_hole circle
			(at -4.2 0 270)
			(size 2.5 2.5)
			(drill 1.8)
			(layers "*.Cu" "*.Mask")
			(remove_unused_layers no)
			(net "GND")
			(thermal_bridge_angle 90)
		)
		(pad "6" thru_hole circle
			(at -8.4 0 270)
			(size 2.5 2.5)
			(drill 1.8)
			(layers "*.Cu" "*.Mask")
			(remove_unused_layers no)
			(net "GND")
			(thermal_bridge_angle 90)
		)
	)
	(footprint "Vault:CAPC1608X87X45ML20T05"
		(layer "F.Cu")
		(at 152.288595 144.1786)
		(property "Reference" "C63"
			(at -4.8 0.193345 0)
			(unlocked yes)
			(layer "F.SilkS")
			(effects
				(font
					(size 0.762 0.762)
					(thickness 0.2286)
				)
				(justify left bottom)
			)
		)
		(property "Value" "0.1uF"
			(at -0.2921 3.47599 0)
			(unlocked yes)
			(layer "F.SilkS")
			(hide yes)
			(effects
				(font
					(size 1.524 1.524)
					(thickness 0.254)
				)
				(justify left bottom)
			)
		)
		(sheetname "MAC")
		(sheetfile "MAC.kicad_sch")
		(duplicate_pad_numbers_are_jumpers no)
		(pad "1" smd rect
			(at -0.7 0 90)
			(size 1.1 1.05)
			(layers "F.Cu" "F.Mask" "F.Paste")
			(net "GND")
		)
		(pad "2" smd rect
			(at 0.7 0 90)
			(size 1.1 1.05)
			(layers "F.Cu" "F.Mask" "F.Paste")
			(net "+5.0V")
		)
	)
	(footprint "Passives:DIOM1608X06N"
		(layer "F.Cu")
		(at 149.670595 61.9996 -90)
		(property "Reference" "D9"
			(at -1.921 -0.411345 90)
			(unlocked yes)
			(layer "F.SilkS")
			(effects
				(font
					(size 0.762 0.762)
					(thickness 0.2286)
				)
				(justify left bottom)
			)
		)
		(property "Value" "RED"
			(at 3.22199 1.4097 0)
			(unlocked yes)
			(layer "F.SilkS")
			(hide yes)
			(effects
				(font
					(size 1.524 1.524)
					(thickness 0.254)
				)
				(justify left bottom)
			)
		)
		(sheetname "UART")
		(sheetfile "UART.kicad_sch")
		(duplicate_pad_numbers_are_jumpers no)
		(fp_circle
			(center -1.275 -0.725)
			(end -1.325 -0.725)
			(stroke
				(width 0.1)
				(type solid)
			)
			(fill no)
			(layer "F.SilkS")
		)
		(pad "1" smd rect
			(at -0.725 0)
			(size 0.85 1)
			(layers "F.Cu" "F.Mask" "F.Paste")
			(net "NetD9_1")
		)
		(pad "2" smd rect
			(at 0.725 0)
			(size 0.85 1)
			(layers "F.Cu" "F.Mask" "F.Paste")
			(net "+3.3V")
		)
	)
	(footprint "Miscellaneous:OMRON-B3U-1000P"
		(layer "F.Cu")
		(at 172.784595 53.7446)
		(property "Reference" "S5"
			(at -2.3622 -2.218055 0)
			(unlocked yes)
			(layer "F.SilkS")
			(effects
				(font
					(size 0.762 0.762)
					(thickness 0.2286)
				)
				(justify left bottom)
			)
		)
		(property "Value" "B3U-1000P"
			(at -2.3241 4.03479 0)
			(unlocked yes)
			(layer "F.SilkS")
			(hide yes)
			(effects
				(font
					(size 1.524 1.524)
					(thickness 0.254)
				)
				(justify left bottom)
			)
		)
		(sheetname "USER_IO")
		(sheetfile "USER_IO.kicad_sch")
		(duplicate_pad_numbers_are_jumpers no)
		(fp_line
			(start -2.286 -1.397)
			(end 2.286 -1.397)
			(stroke
				(width 0.2032)
				(type solid)
			)
			(layer "F.SilkS")
		)
		(fp_line
			(start -2.286 -1.143)
			(end -2.286 -1.397)
			(stroke
				(width 0.2032)
				(type solid)
			)
			(layer "F.SilkS")
		)
		(fp_line
			(start -2.286 1.397)
			(end -2.286 1.143)
			(stroke
				(width 0.2032)
				(type solid)
			)
			(layer "F.SilkS")
		)
		(fp_line
			(start -2.286 1.397)
			(end 2.286 1.397)
			(stroke
				(width 0.2032)
				(type solid)
			)
			(layer "F.SilkS")
		)
		(fp_line
			(start 2.286 -1.143)
			(end 2.286 -1.397)
			(stroke
				(width 0.2032)
				(type solid)
			)
			(layer "F.SilkS")
		)
		(fp_line
			(start 2.286 1.397)
			(end 2.286 1.143)
			(stroke
				(width 0.2032)
				(type solid)
			)
			(layer "F.SilkS")
		)
		(pad "1" smd rect
			(at -1.7 0)
			(size 0.8 1.7)
			(layers "F.Cu" "F.Mask" "F.Paste")
			(net "GND")
		)
		(pad "2" smd rect
			(at 1.7 0)
			(size 0.8 1.7)
			(layers "F.Cu" "F.Mask" "F.Paste")
			(net "NetR33_1")
		)
	)
	(footprint "Vault:MCSM-090-02984-00X"
		(layer "F.Cu")
		(at 181.113595 118.4786 90)
		(property "Reference" "U10AL"
			(at 21.552349 -15.555855 0)
			(unlocked yes)
			(layer "F.SilkS")
			(effects
				(font
					(size 0.762 0.762)
					(thickness 0.254)
				)
			)
		)
		(property "Value" "SA.45s"
			(at -22.749002 -13.069655 0)
			(unlocked yes)
			(layer "F.SilkS")
			(hide yes)
			(effects
				(font
					(size 1.524 1.524)
					(thickness 0.254)
				)
			)
		)
		(sheetname "MAC")
		(sheetfile "MAC.kicad_sch")
		(duplicate_pad_numbers_are_jumpers no)
		(fp_line
			(start 20.32 -17.653)
			(end 20.32 17.653)
			(stroke
				(width 0.2)
				(type solid)
			)
			(layer "F.SilkS")
		)
		(fp_line
			(start -20.32 -17.653)
			(end 20.32 -17.653)
			(stroke
				(width 0.2)
				(type solid)
			)
			(layer "F.SilkS")
		)
		(fp_line
			(start -20.32 -17.653)
			(end -20.32 17.653)
			(stroke
				(width 0.2)
				(type solid)
			)
			(layer "F.SilkS")
		)
		(fp_line
			(start -20.32 17.653)
			(end 20.32 17.653)
			(stroke
				(width 0.2)
				(type solid)
			)
			(layer "F.SilkS")
		)
		(fp_circle
			(center -20.92 -12.7)
			(end -20.795 -12.7)
			(stroke
				(width 0.25)
				(type solid)
			)
			(fill no)
			(layer "F.SilkS")
		)
		(pad "1" thru_hole rect
			(at -16.51 -12.7 90)
			(size 1.55 1.55)
			(drill 1.05)
			(layers "*.Cu" "*.Mask")
			(remove_unused_layers no)
		)
		(pad "4" thru_hole circle
			(at -16.51 2.54 90)
			(size 1.55 1.55)
			(drill 1.05)
			(layers "*.Cu" "*.Mask")
			(remove_unused_layers no)
			(net "MAC_BITE")
			(thermal_bridge_angle 90)
		)
		(pad "5" thru_hole circle
			(at -16.51 7.62 90)
			(size 1.55 1.55)
			(drill 1.05)
			(layers "*.Cu" "*.Mask")
			(remove_unused_layers no)
			(net "MAC_TX")
			(thermal_bridge_angle 90)
		)
		(pad "6" thru_hole circle
			(at -16.51 12.7 90)
			(size 1.55 1.55)
			(drill 1.05)
			(layers "*.Cu" "*.Mask")
			(remove_unused_layers no)
			(net "MAC_RX")
			(thermal_bridge_angle 90)
		)
		(pad "7" thru_hole circle
			(at 16.51 12.7 90)
			(size 1.55 1.55)
			(drill 1.05)
			(layers "*.Cu" "*.Mask")
			(remove_unused_layers no)
			(net "+3.3V_CLEAN")
			(thermal_bridge_angle 90)
		)
		(pad "8" thru_hole circle
			(at 16.51 7.62 90)
			(size 1.55 1.55)
			(drill 1.05)
			(layers "*.Cu" "*.Mask")
			(remove_unused_layers no)
			(net "GND")
			(thermal_bridge_angle 90)
		)
		(pad "9" thru_hole circle
			(at 16.51 2.54 90)
			(size 1.55 1.55)
			(drill 1.05)
			(layers "*.Cu" "*.Mask")
			(remove_unused_layers no)
			(net "MAC_PPS_IN0+")
			(thermal_bridge_angle 90)
		)
		(pad "10" thru_hole circle
			(at 16.51 -2.54 90)
			(size 1.55 1.55)
			(drill 1.05)
			(layers "*.Cu" "*.Mask")
			(remove_unused_layers no)
			(net "MAC_PPS_OUT+")
			(thermal_bridge_angle 90)
		)
		(pad "12" thru_hole circle
			(at 16.51 -12.7 90)
			(size 1.55 1.55)
			(drill 1.05)
			(layers "*.Cu" "*.Mask")
			(remove_unused_layers no)
			(net "MAC_10Mout")
			(thermal_bridge_angle 90)
		)
	)
	(footprint "Vault:RESC1608X55X30LL15T20"
		(layer "F.Cu")
		(at 170.688595 60.7786)
		(property "Reference" "R37"
			(at -2.1714 0.026921 0)
			(unlocked yes)
			(layer "F.SilkS")
			(effects
				(font
					(size 0.762 0.762)
					(thickness 0.2286)
				)
			)
		)
		(property "Value" "10K"
			(at -2.657602 1.790085 270)
			(unlocked yes)
			(layer "F.SilkS")
			(hide yes)
			(effects
				(font
					(size 1.524 1.524)
					(thickness 0.254)
				)
			)
		)
		(sheetname "GPS_IMU_SENSORS")
		(sheetfile "GPS_IMU_SENSORS.kicad_sch")
		(duplicate_pad_numbers_are_jumpers no)
		(pad "1" smd rect
			(at -0.575 0 90)
			(size 0.85 0.75)
			(layers "F.Cu" "F.Mask" "F.Paste")
			(net "EXT_EEPROM_WP")
		)
		(pad "2" smd rect
			(at 0.575 0 90)
			(size 0.85 0.75)
			(layers "F.Cu" "F.Mask" "F.Paste")
			(net "+3.3V")
		)
	)
	(footprint "Capacitors:CAPC1608X10N"
		(layer "F.Cu")
		(at 152.185195 76.8078 -90)
		(property "Reference" "C67"
			(at -2.243455 0.5842 0)
			(unlocked yes)
			(layer "F.SilkS")
			(effects
				(font
					(size 0.762 0.762)
					(thickness 0.2286)
				)
				(justify left bottom)
			)
		)
		(property "Value" "CAP_0603_0.01UF_50V"
			(at 4.08559 0.5461 0)
			(unlocked yes)
			(layer "F.SilkS")
			(hide yes)
			(effects
				(font
					(size 1.524 1.524)
					(thickness 0.254)
				)
				(justify left bottom)
			)
		)
		(sheetname "MAC")
		(sheetfile "MAC.kicad_sch")
		(duplicate_pad_numbers_are_jumpers no)
		(fp_line
			(start 0.635 0.7112)
			(end -0.635 0.7112)
			(stroke
				(width 0.1524)
				(type solid)
			)
			(layer "F.SilkS")
		)
		(fp_line
			(start 0.635 -0.7112)
			(end -0.635 -0.7112)
			(stroke
				(width 0.1524)
				(type solid)
			)
			(layer "F.SilkS")
		)
		(pad "1" smd rect
			(at -0.8 0)
			(size 0.95 1)
			(layers "F.Cu" "F.Mask" "F.Paste")
			(net "GND")
		)
		(pad "2" smd rect
			(at 0.8 0)
			(size 0.95 1)
			(layers "F.Cu" "F.Mask" "F.Paste")
			(net "+3.3V_CLEAN")
		)
	)
	(footprint "Capacitors:CAPC1608X10N"
		(layer "F.Cu")
		(at 101.562995 52.0428 180)
		(property "Reference" "C92"
			(at 4.82551 -0.563055 0)
			(unlocked yes)
			(layer "F.SilkS")
			(effects
				(font
					(size 0.762 0.762)
					(thickness 0.2286)
				)
				(justify left bottom)
			)
		)
		(property "Value" "GRT188R61E106ME13D"
			(at 0.5461 -4.08559 0)
			(unlocked yes)
			(layer "F.SilkS")
			(hide yes)
			(effects
				(font
					(size 1.524 1.524)
					(thickness 0.254)
				)
				(justify left bottom)
			)
		)
		(sheetname "GPS_IMU_SENSORS")
		(sheetfile "GPS_IMU_SENSORS.kicad_sch")
		(duplicate_pad_numbers_are_jumpers no)
		(fp_line
			(start 0.635 0.7112)
			(end -0.635 0.7112)
			(stroke
				(width 0.1524)
				(type solid)
			)
			(layer "F.SilkS")
		)
		(fp_line
			(start 0.635 -0.7112)
			(end -0.635 -0.7112)
			(stroke
				(width 0.1524)
				(type solid)
			)
			(layer "F.SilkS")
		)
		(pad "1" smd rect
			(at -0.8 0 270)
			(size 0.95 1)
			(layers "F.Cu" "F.Mask" "F.Paste")
			(net "GND")
		)
		(pad "2" smd rect
			(at 0.8 0 270)
			(size 0.95 1)
			(layers "F.Cu" "F.Mask" "F.Paste")
			(net "+5.0V")
		)
	)
	(footprint "Capacitors:CAPC2012X14N"
		(layer "F.Cu")
		(at 227.648595 106.4496 90)
		(property "Reference" "C6"
			(at 2.046 0.483345 90)
			(unlocked yes)
			(layer "F.SilkS")
			(effects
				(font
					(size 0.762 0.762)
					(thickness 0.2286)
				)
				(justify left bottom)
			)
		)
		(property "Value" "CAP_0805_10UF_25V"
			(at -3.39979 -5.0165 0)
			(unlocked yes)
			(layer "F.SilkS")
			(hide yes)
			(effects
				(font
					(size 1.524 1.524)
					(thickness 0.254)
				)
				(justify left bottom)
			)
		)
		(sheetname "POWER")
		(sheetfile "POWER.kicad_sch")
		(duplicate_pad_numbers_are_jumpers no)
		(fp_line
			(start -0.762 -0.9652)
			(end 0.762 -0.9652)
			(stroke
				(width 0.1524)
				(type solid)
			)
			(layer "F.SilkS")
		)
		(fp_line
			(start -0.762 0.9652)
			(end 0.762 0.9652)
			(stroke
				(width 0.1524)
				(type solid)
			)
			(layer "F.SilkS")
		)
		(pad "1" smd rect
			(at -0.9 0 180)
			(size 1.45 1.15)
			(layers "F.Cu" "F.Mask" "F.Paste")
			(net "+12V")
		)
		(pad "2" smd rect
			(at 0.9 0 180)
			(size 1.45 1.15)
			(layers "F.Cu" "F.Mask" "F.Paste")
			(net "GND")
		)
	)
	(footprint "Resistors:RESC1005X04N"
		(layer "F.Cu")
		(at 136.088595 145.5786 -90)
		(property "Reference" "R24"
			(at 1.35111 0.884735 90)
			(unlocked yes)
			(layer "F.SilkS")
			(effects
				(font
					(size 0.762 0.762)
					(thickness 0.2286)
				)
				(justify left bottom)
			)
		)
		(property "Value" "ERJ-2GE0R00X"
			(at 3.42519 0.2413 0)
			(unlocked yes)
			(layer "F.SilkS")
			(hide yes)
			(effects
				(font
					(size 1.524 1.524)
					(thickness 0.254)
				)
				(justify left bottom)
			)
		)
		(sheetname "PCIe_JTAG")
		(sheetfile "PCIe_JTAG.kicad_sch")
		(duplicate_pad_numbers_are_jumpers no)
		(pad "1" smd rect
			(at -0.425 0)
			(size 0.6 0.65)
			(layers "F.Cu" "F.Mask" "F.Paste")
			(net "PRSNT")
		)
		(pad "2" smd rect
			(at 0.425 0)
			(size 0.6 0.65)
			(layers "F.Cu" "F.Mask" "F.Paste")
			(net "NetP2_B31")
		)
	)
	(footprint "Vault:CAPC1608X87X45ML20T05"
		(layer "F.Cu")
		(at 225.788595 83.5786 90)
		(property "Reference" "C57"
			(at -2.893345 -0.9 0)
			(unlocked yes)
			(layer "F.SilkS")
			(effects
				(font
					(size 0.762 0.762)
					(thickness 0.2286)
				)
				(justify left bottom)
			)
		)
		(property "Value" "0.1uF"
			(at 4.90601 11.6459 0)
			(unlocked yes)
			(layer "F.SilkS")
			(hide yes)
			(effects
				(font
					(size 1.524 1.524)
					(thickness 0.254)
				)
				(justify left bottom)
			)
		)
		(sheetname "GPS_IMU_SENSORS")
		(sheetfile "GPS_IMU_SENSORS.kicad_sch")
		(duplicate_pad_numbers_are_jumpers no)
		(pad "1" smd rect
			(at -0.7 0 180)
			(size 1.1 1.05)
			(layers "F.Cu" "F.Mask" "F.Paste")
			(net "GND")
		)
		(pad "2" smd rect
			(at 0.7 0 180)
			(size 1.1 1.05)
			(layers "F.Cu" "F.Mask" "F.Paste")
			(net "+3.3V")
		)
	)
	(footprint "Passives:DIOM1608X06N"
		(layer "F.Cu")
		(at 149.670595 65.1746 90)
		(property "Reference" "D10"
			(at -3.604 0.411345 90)
			(unlocked yes)
			(layer "F.SilkS")
			(effects
				(font
					(size 0.762 0.762)
					(thickness 0.2286)
				)
				(justify left bottom)
			)
		)
		(property "Value" "RED"
			(at -4.13639 -0.5715 0)
			(unlocked yes)
			(layer "F.SilkS")
			(hide yes)
			(effects
				(font
					(size 1.524 1.524)
					(thickness 0.254)
				)
				(justify left bottom)
			)
		)
		(sheetname "UART")
		(sheetfile "UART.kicad_sch")
		(duplicate_pad_numbers_are_jumpers no)
		(fp_circle
			(center -1.275 -0.725)
			(end -1.225 -0.725)
			(stroke
				(width 0.1)
				(type solid)
			)
			(fill no)
			(layer "F.SilkS")
		)
		(pad "1" smd rect
			(at -0.725 0 180)
			(size 0.85 1)
			(layers "F.Cu" "F.Mask" "F.Paste")
			(net "NetD10_1")
		)
		(pad "2" smd rect
			(at 0.725 0 180)
			(size 0.85 1)
			(layers "F.Cu" "F.Mask" "F.Paste")
			(net "+3.3V")
		)
	)
	(footprint "Passives:SOT65P210X110-3N"
		(layer "F.Cu")
		(at 146.622595 66.4446 -90)
		(property "Reference" "D8"
			(at -2.32441 -0.690065 90)
			(unlocked yes)
			(layer "F.SilkS")
			(effects
				(font
					(size 0.762 0.762)
					(thickness 0.2286)
				)
				(justify left bottom)
			)
		)
		(property "Value" "BAT54SW"
			(at 3.88239 1.5875 0)
			(unlocked yes)
			(layer "F.SilkS")
			(hide yes)
			(effects
				(font
					(size 1.524 1.524)
					(thickness 0.254)
				)
				(justify left bottom)
			)
		)
		(sheetname "PCIe_JTAG")
		(sheetfile "PCIe_JTAG.kicad_sch")
		(duplicate_pad_numbers_are_jumpers no)
		(fp_line
			(start 0.675 1.1)
			(end -0.325 1.1)
			(stroke
				(width 0.2)
				(type solid)
			)
			(layer "F.SilkS")
		)
		(fp_line
			(start 0.675 1.1)
			(end 0.675 0.65)
			(stroke
				(width 0.2)
				(type solid)
			)
			(layer "F.SilkS")
		)
		(fp_line
			(start 0.675 -0.65)
			(end 0.675 -1.1)
			(stroke
				(width 0.2)
				(type solid)
			)
			(layer "F.SilkS")
		)
		(fp_line
			(start 0.675 -1.1)
			(end -0.325 -1.1)
			(stroke
				(width 0.2)
				(type solid)
			)
			(layer "F.SilkS")
		)
		(fp_circle
			(center -1.125 -1.45)
			(end -1.25 -1.45)
			(stroke
				(width 0.25)
				(type solid)
			)
			(fill no)
			(layer "F.SilkS")
		)
		(pad "1" smd rect
			(at -1.125 -0.65)
			(size 0.5 0.9)
			(layers "F.Cu" "F.Mask" "F.Paste")
			(net "GND")
		)
		(pad "2" smd rect
			(at -1.125 0.65)
			(size 0.5 0.9)
			(layers "F.Cu" "F.Mask" "F.Paste")
			(net "+3.3V")
		)
		(pad "3" smd rect
			(at 1.125 0)
			(size 0.5 0.9)
			(layers "F.Cu" "F.Mask" "F.Paste")
			(net "FPGA_TDI")
		)
	)
	(footprint "Passives:DIOM6959X26N"
		(layer "F.Cu")
		(at 85.027595 137.5646 180)
		(property "Reference" "D18"
			(at 4.1402 4.097655 0)
			(unlocked yes)
			(layer "F.SilkS")
			(effects
				(font
					(size 0.762 0.762)
					(thickness 0.2286)
				)
				(justify left bottom)
			)
		)
		(property "Value" "SMCJ6.5CA"
			(at 4.2545 -5.91439 0)
			(unlocked yes)
			(layer "F.SilkS")
			(hide yes)
			(effects
				(font
					(size 1.524 1.524)
					(thickness 0.254)
				)
				(justify left bottom)
			)
		)
		(sheetname "USER_IO")
		(sheetfile "USER_IO.kicad_sch")
		(duplicate_pad_numbers_are_jumpers no)
		(fp_line
			(start 3.6 3.15)
			(end -3.6 3.15)
			(stroke
				(width 0.2)
				(type solid)
			)
			(layer "F.SilkS")
		)
		(fp_line
			(start 3.6 1.975)
			(end 3.6 3.15)
			(stroke
				(width 0.2)
				(type solid)
			)
			(layer "F.SilkS")
		)
		(fp_line
			(start 3.6 -3.15)
			(end 3.6 -1.975)
			(stroke
				(width 0.2)
				(type solid)
			)
			(layer "F.SilkS")
		)
		(fp_line
			(start 3.6 -3.15)
			(end -3.6 -3.15)
			(stroke
				(width 0.2)
				(type solid)
			)
			(layer "F.SilkS")
		)
		(fp_line
			(start -3.6 1.975)
			(end -3.6 3.15)
			(stroke
				(width 0.2)
				(type solid)
			)
			(layer "F.SilkS")
		)
		(fp_line
			(start -3.6 -3.15)
			(end -3.6 -1.975)
			(stroke
				(width 0.2)
				(type solid)
			)
			(layer "F.SilkS")
		)
		(fp_circle
			(center -4.25 -2.125)
			(end -4.25 -2)
			(stroke
				(width 0.25)
				(type solid)
			)
			(fill no)
			(layer "F.SilkS")
		)
		(pad "A" smd rect
			(at 2.85 0 270)
			(size 3.15 2.45)
			(layers "F.Cu" "F.Mask" "F.Paste")
			(net "ANT4")
		)
		(pad "K" smd rect
			(at -2.85 0 270)
			(size 3.15 2.45)
			(layers "F.Cu" "F.Mask" "F.Paste")
			(net "GND")
		)
	)
	(footprint "Vault:CAPC1608X87X45ML20T05"
		(layer "F.Cu")
		(at 219.588595 92.6786 180)
		(property "Reference" "C12"
			(at 4.2 0.106655 0)
			(unlocked yes)
			(layer "F.SilkS")
			(effects
				(font
					(size 0.762 0.762)
					(thickness 0.2286)
				)
				(justify left bottom)
			)
		)
		(property "Value" "0.1uF"
			(at -12.7889 -3.09499 0)
			(unlocked yes)
			(layer "F.SilkS")
			(hide yes)
			(effects
				(font
					(size 1.524 1.524)
					(thickness 0.254)
				)
				(justify left bottom)
			)
		)
		(sheetname "POWER")
		(sheetfile "POWER.kicad_sch")
		(duplicate_pad_numbers_are_jumpers no)
		(pad "1" smd rect
			(at -0.7 0 270)
			(size 1.1 1.05)
			(layers "F.Cu" "F.Mask" "F.Paste")
			(net "GND")
		)
		(pad "2" smd rect
			(at 0.7 0 270)
			(size 1.1 1.05)
			(layers "F.Cu" "F.Mask" "F.Paste")
			(net "+3.3V")
		)
	)
	(footprint "Capacitors:CAPC2012X14N"
		(layer "F.Cu")
		(at 168.720595 89.0506 90)
		(property "Reference" "C72"
			(at 1.98169 0.690065 90)
			(unlocked yes)
			(layer "F.SilkS")
			(effects
				(font
					(size 0.762 0.762)
					(thickness 0.2286)
				)
				(justify left bottom)
			)
		)
		(property "Value" "CAP_0805_22UF_16V"
			(at -3.52679 -1.5875 0)
			(unlocked yes)
			(layer "F.SilkS")
			(hide yes)
			(effects
				(font
					(size 1.524 1.524)
					(thickness 0.254)
				)
				(justify left bottom)
			)
		)
		(sheetname "MAC")
		(sheetfile "MAC.kicad_sch")
		(duplicate_pad_numbers_are_jumpers no)
		(fp_line
			(start -0.762 -0.9652)
			(end 0.762 -0.9652)
			(stroke
				(width 0.1524)
				(type solid)
			)
			(layer "F.SilkS")
		)
		(fp_line
			(start -0.762 0.9652)
			(end 0.762 0.9652)
			(stroke
				(width 0.1524)
				(type solid)
			)
			(layer "F.SilkS")
		)
		(pad "1" smd rect
			(at -0.9 0 180)
			(size 1.45 1.15)
			(layers "F.Cu" "F.Mask" "F.Paste")
			(net "GND")
		)
		(pad "2" smd rect
			(at 0.9 0 180)
			(size 1.45 1.15)
			(layers "F.Cu" "F.Mask" "F.Paste")
			(net "NetC72_2")
		)
	)
	(footprint "Capacitors:CAPC2012X14N"
		(layer "F.Cu")
		(at 227.775595 124.4836 180)
		(property "Reference" "C13"
			(at -1.94991 -0.690055 0)
			(unlocked yes)
			(layer "F.SilkS")
			(effects
				(font
					(size 0.762 0.762)
					(thickness 0.2286)
				)
				(justify left bottom)
			)
		)
		(property "Value" "CAP_0805_10UF_25V"
			(at 7.4295 -0.98679 0)
			(unlocked yes)
			(layer "F.SilkS")
			(hide yes)
			(effects
				(font
					(size 1.524 1.524)
					(thickness 0.254)
				)
				(justify left bottom)
			)
		)
		(sheetname "POWER")
		(sheetfile "POWER.kicad_sch")
		(duplicate_pad_numbers_are_jumpers no)
		(fp_line
			(start 0.762 0.9652)
			(end -0.762 0.9652)
			(stroke
				(width 0.1524)
				(type solid)
			)
			(layer "F.SilkS")
		)
		(fp_line
			(start 0.762 -0.9652)
			(end -0.762 -0.9652)
			(stroke
				(width 0.1524)
				(type solid)
			)
			(layer "F.SilkS")
		)
		(pad "1" smd rect
			(at -0.9 0 270)
			(size 1.45 1.15)
			(layers "F.Cu" "F.Mask" "F.Paste")
			(net "+5.0V")
		)
		(pad "2" smd rect
			(at 0.9 0 270)
			(size 1.45 1.15)
			(layers "F.Cu" "F.Mask" "F.Paste")
			(net "GND")
		)
	)
	(footprint "Resistors:RESC2012X50N"
		(layer "F.Cu")
		(at 143.574595 66.4446 90)
		(property "Reference" "R21"
			(at -3.934 0.407345 90)
			(unlocked yes)
			(layer "F.SilkS")
			(effects
				(font
					(size 0.762 0.762)
					(thickness 0.2286)
				)
				(justify left bottom)
			)
		)
		(property "Value" "CRCW080533R0FKEA"
			(at -3.52679 -1.5875 0)
			(unlocked yes)
			(layer "F.SilkS")
			(hide yes)
			(effects
				(font
					(size 1.524 1.524)
					(thickness 0.254)
				)
				(justify left bottom)
			)
		)
		(sheetname "PCIe_JTAG")
		(sheetfile "PCIe_JTAG.kicad_sch")
		(duplicate_pad_numbers_are_jumpers no)
		(fp_line
			(start 0 -0.762)
			(end 0 0.762)
			(stroke
				(width 0.1524)
				(type solid)
			)
			(layer "F.SilkS")
		)
		(pad "1" smd rect
			(at -1 0 180)
			(size 1.45 0.95)
			(layers "F.Cu" "F.Mask" "F.Paste")
			(net "FPGA_TDI")
		)
		(pad "2" smd rect
			(at 1 0 180)
			(size 1.45 0.95)
			(layers "F.Cu" "F.Mask" "F.Paste")
			(net "NetR21_2")
		)
	)
	(footprint "Miscellaneous Devices:J1-0603"
		(layer "F.Cu")
		(at 92.688595 56.1286 -90)
		(property "Reference" "R10"
			(at -0.575 1.349544 90)
			(unlocked yes)
			(layer "F.SilkS")
			(effects
				(font
					(face "Arial")
					(size 0.48006 0.48006)
					(thickness 0.254)
				)
			)
		)
		(property "Value" "GPS2TX"
			(at 2.581402 -9.103025 0)
			(unlocked yes)
			(layer "F.SilkS")
			(hide yes)
			(effects
				(font
					(size 1.524 1.524)
					(thickness 0.254)
				)
			)
		)
		(sheetname "GPS_IMU_SENSORS")
		(sheetfile "GPS_IMU_SENSORS.kicad_sch")
		(duplicate_pad_numbers_are_jumpers no)
		(fp_line
			(start 0.2 0.35)
			(end -0.2 0.35)
			(stroke
				(width 0.2)
				(type solid)
			)
			(layer "F.SilkS")
		)
		(fp_line
			(start 0.2 -0.35)
			(end -0.2 -0.35)
			(stroke
				(width 0.2)
				(type solid)
			)
			(layer "F.SilkS")
		)
		(pad "1" smd rect
			(at -0.75 0)
			(size 0.9 0.7)
			(layers "F.Cu" "F.Mask" "F.Paste")
			(net "GPS2_TX")
		)
		(pad "2" smd rect
			(at 0.75 0)
			(size 0.9 0.7)
			(layers "F.Cu" "F.Mask" "F.Paste")
			(net "NetJP1_3")
		)
	)
	(footprint "Passives:SOT65P210X110-3N"
		(layer "F.Cu")
		(at 140.907595 66.4446 -90)
		(property "Reference" "D7"
			(at 4.934 -0.474345 90)
			(unlocked yes)
			(layer "F.SilkS")
			(effects
				(font
					(size 0.762 0.762)
					(thickness 0.2286)
				)
				(justify left bottom)
			)
		)
		(property "Value" "BAT54SW"
			(at 3.88239 1.5875 0)
			(unlocked yes)
			(layer "F.SilkS")
			(hide yes)
			(effects
				(font
					(size 1.524 1.524)
					(thickness 0.254)
				)
				(justify left bottom)
			)
		)
		(sheetname "PCIe_JTAG")
		(sheetfile "PCIe_JTAG.kicad_sch")
		(duplicate_pad_numbers_are_jumpers no)
		(fp_line
			(start 0.675 1.1)
			(end -0.325 1.1)
			(stroke
				(width 0.2)
				(type solid)
			)
			(layer "F.SilkS")
		)
		(fp_line
			(start 0.675 1.1)
			(end 0.675 0.65)
			(stroke
				(width 0.2)
				(type solid)
			)
			(layer "F.SilkS")
		)
		(fp_line
			(start 0.675 -0.65)
			(end 0.675 -1.1)
			(stroke
				(width 0.2)
				(type solid)
			)
			(layer "F.SilkS")
		)
		(fp_line
			(start 0.675 -1.1)
			(end -0.325 -1.1)
			(stroke
				(width 0.2)
				(type solid)
			)
			(layer "F.SilkS")
		)
		(fp_circle
			(center -1.125 -1.45)
			(end -1.25 -1.45)
			(stroke
				(width 0.25)
				(type solid)
			)
			(fill no)
			(layer "F.SilkS")
		)
		(pad "1" smd rect
			(at -1.125 -0.65)
			(size 0.5 0.9)
			(layers "F.Cu" "F.Mask" "F.Paste")
			(net "GND")
		)
		(pad "2" smd rect
			(at -1.125 0.65)
			(size 0.5 0.9)
			(layers "F.Cu" "F.Mask" "F.Paste")
			(net "+3.3V")
		)
		(pad "3" smd rect
			(at 1.125 0)
			(size 0.5 0.9)
			(layers "F.Cu" "F.Mask" "F.Paste")
			(net "FPGA_TMS")
		)
	)
	(footprint "Vault:CAPC1608X87X45ML20T05"
		(layer "F.Cu")
		(at 214.059595 105.4336)
		(property "Reference" "C21"
			(at -4.371 0.538345 0)
			(unlocked yes)
			(layer "F.SilkS")
			(effects
				(font
					(size 0.762 0.762)
					(thickness 0.2286)
				)
				(justify left bottom)
			)
		)
		(property "Value" "0.1uF"
			(at 21.5011 -18.06321 0)
			(unlocked yes)
			(layer "F.SilkS")
			(hide yes)
			(effects
				(font
					(size 1.524 1.524)
					(thickness 0.254)
				)
				(justify left bottom)
			)
		)
		(sheetname "POWER")
		(sheetfile "POWER.kicad_sch")
		(duplicate_pad_numbers_are_jumpers no)
		(pad "1" smd rect
			(at -0.7 0 90)
			(size 1.1 1.05)
			(layers "F.Cu" "F.Mask" "F.Paste")
			(net "GND")
		)
		(pad "2" smd rect
			(at 0.7 0 90)
			(size 1.1 1.05)
			(layers "F.Cu" "F.Mask" "F.Paste")
			(net "NetC21_2")
		)
	)
	(footprint "Resistors:RESC2012X50N"
		(layer "F.Cu")
		(at 135.827595 66.4446 90)
		(property "Reference" "R19"
			(at -4.88269 0.639265 90)
			(unlocked yes)
			(layer "F.SilkS")
			(effects
				(font
					(size 0.762 0.762)
					(thickness 0.2286)
				)
				(justify left bottom)
			)
		)
		(property "Value" "CRCW080533R0FKEA"
			(at -3.52679 -1.5875 0)
			(unlocked yes)
			(layer "F.SilkS")
			(hide yes)
			(effects
				(font
					(size 1.524 1.524)
					(thickness 0.254)
				)
				(justify left bottom)
			)
		)
		(sheetname "PCIe_JTAG")
		(sheetfile "PCIe_JTAG.kicad_sch")
		(duplicate_pad_numbers_are_jumpers no)
		(fp_line
			(start 0 -0.762)
			(end 0 0.762)
			(stroke
				(width 0.1524)
				(type solid)
			)
			(layer "F.SilkS")
		)
		(pad "1" smd rect
			(at -1 0 180)
			(size 1.45 0.95)
			(layers "F.Cu" "F.Mask" "F.Paste")
			(net "FPGA_TDO")
		)
		(pad "2" smd rect
			(at 1 0 180)
			(size 1.45 0.95)
			(layers "F.Cu" "F.Mask" "F.Paste")
			(net "NetR19_2")
		)
	)
	(footprint "Capacitors:CAPC2012X14N"
		(layer "F.Cu")
		(at 219.393595 106.0686 -90)
		(property "Reference" "C5"
			(at 3.41 -0.488345 90)
			(unlocked yes)
			(layer "F.SilkS")
			(effects
				(font
					(size 0.762 0.762)
					(thickness 0.2286)
				)
				(justify left bottom)
			)
		)
		(property "Value" "CAP_0805_10UF_25V"
			(at -19.07921 -10.6045 0)
			(unlocked yes)
			(layer "F.SilkS")
			(hide yes)
			(effects
				(font
					(size 1.524 1.524)
					(thickness 0.254)
				)
				(justify left bottom)
			)
		)
		(sheetname "POWER")
		(sheetfile "POWER.kicad_sch")
		(duplicate_pad_numbers_are_jumpers no)
		(fp_line
			(start 0.762 0.9652)
			(end -0.762 0.9652)
			(stroke
				(width 0.1524)
				(type solid)
			)
			(layer "F.SilkS")
		)
		(fp_line
			(start 0.762 -0.9652)
			(end -0.762 -0.9652)
			(stroke
				(width 0.1524)
				(type solid)
			)
			(layer "F.SilkS")
		)
		(pad "1" smd rect
			(at -0.9 0)
			(size 1.45 1.15)
			(layers "F.Cu" "F.Mask" "F.Paste")
			(net "+12V")
		)
		(pad "2" smd rect
			(at 0.9 0)
			(size 1.45 1.15)
			(layers "F.Cu" "F.Mask" "F.Paste")
			(net "GND")
		)
	)
	(footprint "Vault:CAPC1608X87X45ML20T05"
		(layer "F.Cu")
		(at 201.988595 75.2786 180)
		(property "Reference" "C2"
			(at -1.23159 3.077655 180)
			(unlocked yes)
			(layer "F.SilkS")
			(effects
				(font
					(size 0.762 0.762)
					(thickness 0.2286)
				)
				(justify left bottom)
			)
		)
		(property "Value" "0.1uF"
			(at 0.7493 -3.01879 0)
			(unlocked yes)
			(layer "F.SilkS")
			(hide yes)
			(effects
				(font
					(size 1.524 1.524)
					(thickness 0.254)
				)
				(justify left bottom)
			)
		)
		(sheetname "POWER")
		(sheetfile "POWER.kicad_sch")
		(duplicate_pad_numbers_are_jumpers no)
		(pad "1" smd rect
			(at -0.7 0 270)
			(size 1.1 1.05)
			(layers "F.Cu" "F.Mask" "F.Paste")
			(net "GND")
		)
		(pad "2" smd rect
			(at 0.7 0 270)
			(size 1.1 1.05)
			(layers "F.Cu" "F.Mask" "F.Paste")
			(net "+12V")
		)
	)
	(footprint "Vault:CAPC1608X90X35NL10T15"
		(layer "F.Cu")
		(at 234.760595 112.1646 -90)
		(property "Reference" "C20"
			(at -1.336 -0.346345 90)
			(unlocked yes)
			(layer "F.SilkS")
			(effects
				(font
					(size 0.762 0.762)
					(thickness 0.2286)
				)
				(justify left bottom)
			)
		)
		(property "Value" "0.033uF"
			(at 3.34899 3.7211 0)
			(unlocked yes)
			(layer "F.SilkS")
			(hide yes)
			(effects
				(font
					(size 1.524 1.524)
					(thickness 0.254)
				)
				(justify left bottom)
			)
		)
		(sheetname "POWER")
		(sheetfile "POWER.kicad_sch")
		(duplicate_pad_numbers_are_jumpers no)
		(pad "1" smd rect
			(at -0.675 0)
			(size 0.95 0.85)
			(layers "F.Cu" "F.Mask" "F.Paste")
			(net "NetC20_1")
		)
		(pad "2" smd rect
			(at 0.675 0)
			(size 0.95 0.85)
			(layers "F.Cu" "F.Mask" "F.Paste")
			(net "NetC20_2")
		)
	)
	(footprint "Vault:W16-H2_L"
		(layer "F.Cu")
		(at 133.013595 81.5286)
		(property "Reference" "U3"
			(at -1.470995 -6.423069 0)
			(unlocked yes)
			(layer "F.SilkS")
			(effects
				(font
					(size 0.762 0.762)
					(thickness 0.254)
				)
			)
		)
		(property "Value" "DS3231SN"
			(at 0.59505 6.950202 0)
			(unlocked yes)
			(layer "F.SilkS")
			(hide yes)
			(effects
				(font
					(size 1.524 1.524)
					(thickness 0.254)
				)
			)
		)
		(sheetname "MAC")
		(sheetfile "MAC.kicad_sch")
		(duplicate_pad_numbers_are_jumpers no)
		(fp_line
			(start -3.1 -5.25)
			(end 3.1 -5.25)
			(stroke
				(width 0.2)
				(type solid)
			)
			(layer "F.SilkS")
		)
		(fp_line
			(start -3.1 5.25)
			(end -3.1 -5.25)
			(stroke
				(width 0.2)
				(type solid)
			)
			(layer "F.SilkS")
		)
		(fp_line
			(start -3.1 5.25)
			(end 3.1 5.25)
			(stroke
				(width 0.2)
				(type solid)
			)
			(layer "F.SilkS")
		)
		(fp_line
			(start 3.1 5.25)
			(end 3.1 -5.25)
			(stroke
				(width 0.2)
				(type solid)
			)
			(layer "F.SilkS")
		)
		(fp_circle
			(center -4.5 -5.295)
			(end -4.5 -5.42)
			(stroke
				(width 0.25)
				(type solid)
			)
			(fill no)
			(layer "F.SilkS")
		)
		(fp_circle
			(center -2.1 -4.25)
			(end -2.1 -4.55)
			(stroke
				(width 0.6)
				(type solid)
			)
			(fill no)
			(layer "F.SilkS")
		)
		(pad "1" smd oval
			(at -4.5 -4.445 90)
			(size 0.6 2)
			(layers "F.Cu" "F.Mask" "F.Paste")
		)
		(pad "2" smd oval
			(at -4.5 -3.175 90)
			(size 0.6 2)
			(layers "F.Cu" "F.Mask" "F.Paste")
			(net "+3.3V_CLEAN")
		)
		(pad "3" smd oval
			(at -4.5 -1.905 90)
			(size 0.6 2)
			(layers "F.Cu" "F.Mask" "F.Paste")
			(net "RTC_MFP")
		)
		(pad "4" smd oval
			(at -4.5 -0.635 90)
			(size 0.6 2)
			(layers "F.Cu" "F.Mask" "F.Paste")
		)
		(pad "5" smd oval
			(at -4.5 0.635 90)
			(size 0.6 2)
			(layers "F.Cu" "F.Mask" "F.Paste")
		)
		(pad "6" smd oval
			(at -4.5 1.905 90)
			(size 0.6 2)
			(layers "F.Cu" "F.Mask" "F.Paste")
		)
		(pad "7" smd oval
			(at -4.5 3.175 90)
			(size 0.6 2)
			(layers "F.Cu" "F.Mask" "F.Paste")
		)
		(pad "8" smd oval
			(at -4.5 4.445 90)
			(size 0.6 2)
			(layers "F.Cu" "F.Mask" "F.Paste")
		)
		(pad "9" smd oval
			(at 4.5 4.445 90)
			(size 0.6 2)
			(layers "F.Cu" "F.Mask" "F.Paste")
		)
		(pad "10" smd oval
			(at 4.5 3.175 90)
			(size 0.6 2)
			(layers "F.Cu" "F.Mask" "F.Paste")
		)
		(pad "11" smd oval
			(at 4.5 1.905 90)
			(size 0.6 2)
			(layers "F.Cu" "F.Mask" "F.Paste")
		)
		(pad "12" smd oval
			(at 4.5 0.635 90)
			(size 0.6 2)
			(layers "F.Cu" "F.Mask" "F.Paste")
		)
		(pad "13" smd oval
			(at 4.5 -0.635 90)
			(size 0.6 2)
			(layers "F.Cu" "F.Mask" "F.Paste")
			(net "GND")
		)
		(pad "14" smd oval
			(at 4.5 -1.905 90)
			(size 0.6 2)
			(layers "F.Cu" "F.Mask" "F.Paste")
			(net "NetBT1_2")
		)
		(pad "15" smd oval
			(at 4.5 -3.175 90)
			(size 0.6 2)
			(layers "F.Cu" "F.Mask" "F.Paste")
			(net "SDA")
		)
		(pad "16" smd oval
			(at 4.5 -4.445 90)
			(size 0.6 2)
			(layers "F.Cu" "F.Mask" "F.Paste")
			(net "SCL")
		)
	)
	(footprint "Miscellaneous Devices:J1-0603"
		(layer "F.Cu")
		(at 190.288595 55.0786 180)
		(property "Reference" "R36"
			(at -2.854 -0.126931 0)
			(unlocked yes)
			(layer "F.SilkS")
			(effects
				(font
					(size 0.762 0.762)
					(thickness 0.254)
				)
			)
		)
		(property "Value" "ERJ-3EKF1001V"
			(at -4.10075 -2.835402 0)
			(unlocked yes)
			(layer "F.SilkS")
			(hide yes)
			(effects
				(font
					(size 1.524 1.524)
					(thickness 0.254)
				)
			)
		)
		(sheetname "USER_IO")
		(sheetfile "USER_IO.kicad_sch")
		(duplicate_pad_numbers_are_jumpers no)
		(fp_line
			(start 0.2 0.35)
			(end -0.2 0.35)
			(stroke
				(width 0.2)
				(type solid)
			)
			(layer "F.SilkS")
		)
		(fp_line
			(start 0.2 -0.35)
			(end -0.2 -0.35)
			(stroke
				(width 0.2)
				(type solid)
			)
			(layer "F.SilkS")
		)
		(pad "1" smd rect
			(at -0.75 0 270)
			(size 0.9 0.7)
			(layers "F.Cu" "F.Mask" "F.Paste")
			(net "KEY2")
		)
		(pad "2" smd rect
			(at 0.75 0 270)
			(size 0.9 0.7)
			(layers "F.Cu" "F.Mask" "F.Paste")
			(net "NetR34_1")
		)
	)
	(footprint "Resistors:RESC1608X50N"
		(layer "F.Cu")
		(at 214.008795 98.0676 90)
		(property "Reference" "R5"
			(at 1.639 0.398145 90)
			(unlocked yes)
			(layer "F.SilkS")
			(effects
				(font
					(size 0.762 0.762)
					(thickness 0.2286)
				)
				(justify left bottom)
			)
		)
		(property "Value" "ERJ-3EKF2612V"
			(at -3.17119 -1.0033 0)
			(unlocked yes)
			(layer "F.SilkS")
			(hide yes)
			(effects
				(font
					(size 1.524 1.524)
					(thickness 0.254)
				)
				(justify left bottom)
			)
		)
		(sheetname "POWER")
		(sheetfile "POWER.kicad_sch")
		(duplicate_pad_numbers_are_jumpers no)
		(fp_line
			(start 0 -0.5)
			(end 0 0.5)
			(stroke
				(width 0.1524)
				(type solid)
			)
			(layer "F.SilkS")
		)
		(pad "1" smd rect
			(at -0.69 0 180)
			(size 1 0.72)
			(layers "F.Cu" "F.Mask" "F.Paste")
			(net "NetR5_1")
		)
		(pad "2" smd rect
			(at 0.69 0 180)
			(size 1 0.72)
			(layers "F.Cu" "F.Mask" "F.Paste")
			(net "+3.3V")
		)
	)
	(footprint "Capacitors:CAPC2012X14N"
		(layer "F.Cu")
		(at 105.169795 51.9666)
		(property "Reference" "C91"
			(at 3.331655 1.33307 90)
			(unlocked yes)
			(layer "F.SilkS")
			(effects
				(font
					(size 0.762 0.762)
					(thickness 0.2286)
				)
				(justify left bottom)
			)
		)
		(property "Value" "CAP_0805_1UF_25V"
			(at -1.5875 3.52679 0)
			(unlocked yes)
			(layer "F.SilkS")
			(hide yes)
			(effects
				(font
					(size 1.524 1.524)
					(thickness 0.254)
				)
				(justify left bottom)
			)
		)
		(sheetname "GPS_IMU_SENSORS")
		(sheetfile "GPS_IMU_SENSORS.kicad_sch")
		(duplicate_pad_numbers_are_jumpers no)
		(fp_line
			(start -0.762 -0.9652)
			(end 0.762 -0.9652)
			(stroke
				(width 0.1524)
				(type solid)
			)
			(layer "F.SilkS")
		)
		(fp_line
			(start -0.762 0.9652)
			(end 0.762 0.9652)
			(stroke
				(width 0.1524)
				(type solid)
			)
			(layer "F.SilkS")
		)
		(pad "1" smd rect
			(at -0.9 0 90)
			(size 1.45 1.15)
			(layers "F.Cu" "F.Mask" "F.Paste")
			(net "GND")
		)
		(pad "2" smd rect
			(at 0.9 0 90)
			(size 1.45 1.15)
			(layers "F.Cu" "F.Mask" "F.Paste")
			(net "+5.0V")
		)
	)
	(footprint "Miscellaneous Devices:J1-0603"
		(layer "F.Cu")
		(at 114.688595 57.8286 -90)
		(property "Reference" "R13"
			(at 0.2786 -5.873079 270)
			(unlocked yes)
			(layer "F.SilkS")
			(effects
				(font
					(size 0.762 0.762)
					(thickness 0.2286)
				)
			)
		)
		(property "Value" "MACRX"
			(at 2.835402 -4.96595 0)
			(unlocked yes)
			(layer "F.SilkS")
			(hide yes)
			(effects
				(font
					(size 1.524 1.524)
					(thickness 0.254)
				)
			)
		)
		(sheetname "GPS_IMU_SENSORS")
		(sheetfile "GPS_IMU_SENSORS.kicad_sch")
		(duplicate_pad_numbers_are_jumpers no)
		(fp_line
			(start 0.2 0.35)
			(end -0.2 0.35)
			(stroke
				(width 0.2)
				(type solid)
			)
			(layer "F.SilkS")
		)
		(fp_line
			(start 0.2 -0.35)
			(end -0.2 -0.35)
			(stroke
				(width 0.2)
				(type solid)
			)
			(layer "F.SilkS")
		)
		(pad "1" smd rect
			(at -0.75 0)
			(size 0.9 0.7)
			(layers "F.Cu" "F.Mask" "F.Paste")
			(net "MAC_RX")
		)
		(pad "2" smd rect
			(at 0.75 0)
			(size 0.9 0.7)
			(layers "F.Cu" "F.Mask" "F.Paste")
			(net "NetJP2_3")
		)
	)
	(footprint "Vault:RESC1608X50X30NL20T20"
		(layer "F.Cu")
		(at 152.083595 62.5076 180)
		(property "Reference" "R25"
			(at 1.34571 0.656145 0)
			(unlocked yes)
			(layer "F.SilkS")
			(effects
				(font
					(size 0.762 0.762)
					(thickness 0.2286)
				)
				(justify left bottom)
			)
		)
		(property "Value" "499 OHM"
			(at 0.2413 -3.42519 0)
			(unlocked yes)
			(layer "F.SilkS")
			(hide yes)
			(effects
				(font
					(size 1.524 1.524)
					(thickness 0.254)
				)
				(justify left bottom)
			)
		)
		(sheetname "UART")
		(sheetfile "UART.kicad_sch")
		(duplicate_pad_numbers_are_jumpers no)
		(pad "1" smd rect
			(at -0.65 0 270)
			(size 1 0.9)
			(layers "F.Cu" "F.Mask" "F.Paste")
			(net "UART1_RXD")
		)
		(pad "2" smd rect
			(at 0.65 0 270)
			(size 1 0.9)
			(layers "F.Cu" "F.Mask" "F.Paste")
			(net "NetD9_1")
		)
	)
	(footprint "Vault:TECO-1909763-1_V"
		(layer "F.Cu")
		(at 75.088595 124.1786 90)
		(property "Reference" "J9"
			(at -3.026931 2.028605 0)
			(unlocked yes)
			(layer "F.SilkS")
			(effects
				(font
					(size 0.762 0.762)
					(thickness 0.2286)
				)
			)
		)
		(property "Value" "1909763-1"
			(at 4.608085 3.749802 90)
			(unlocked yes)
			(layer "F.SilkS")
			(hide yes)
			(effects
				(font
					(size 1.524 1.524)
					(thickness 0.254)
				)
			)
		)
		(sheetname "USER_IO")
		(sheetfile "USER_IO.kicad_sch")
		(duplicate_pad_numbers_are_jumpers no)
		(fp_line
			(start -0.55 -1.3)
			(end 0.55 -1.3)
			(stroke
				(width 0.2)
				(type solid)
			)
			(layer "F.SilkS")
		)
		(fp_circle
			(center -1.778 1.65)
			(end -1.653 1.65)
			(stroke
				(width 0.25)
				(type solid)
			)
			(fill no)
			(layer "F.SilkS")
		)
		(pad "1" smd rect
			(at -1.475 0 90)
			(size 1.05 2.2)
			(layers "F.Cu" "F.Mask" "F.Paste")
			(net "GND")
		)
		(pad "2" smd rect
			(at 0 1.525 90)
			(size 1 1.05)
			(layers "F.Cu" "F.Mask" "F.Paste")
			(net "ANT3")
		)
		(pad "3" smd rect
			(at 1.475 0 90)
			(size 1.05 2.2)
			(layers "F.Cu" "F.Mask" "F.Paste")
			(net "GND")
		)
	)
	(footprint "Capacitors:CAPC2012X14N"
		(layer "F.Cu")
		(at 159.068595 89.0506 90)
		(property "Reference" "C74"
			(at -0.664655 -4.87631 0)
			(unlocked yes)
			(layer "F.SilkS")
			(effects
				(font
					(size 0.762 0.762)
					(thickness 0.2286)
				)
				(justify left bottom)
			)
		)
		(property "Value" "CAP_0805_22UF_16V"
			(at -3.52679 -1.5875 0)
			(unlocked yes)
			(layer "F.SilkS")
			(hide yes)
			(effects
				(font
					(size 1.524 1.524)
					(thickness 0.254)
				)
				(justify left bottom)
			)
		)
		(sheetname "MAC")
		(sheetfile "MAC.kicad_sch")
		(duplicate_pad_numbers_are_jumpers no)
		(fp_line
			(start -0.762 -0.9652)
			(end 0.762 -0.9652)
			(stroke
				(width 0.1524)
				(type solid)
			)
			(layer "F.SilkS")
		)
		(fp_line
			(start -0.762 0.9652)
			(end 0.762 0.9652)
			(stroke
				(width 0.1524)
				(type solid)
			)
			(layer "F.SilkS")
		)
		(pad "1" smd rect
			(at -0.9 0 180)
			(size 1.45 1.15)
			(layers "F.Cu" "F.Mask" "F.Paste")
			(net "GND")
		)
		(pad "2" smd rect
			(at 0.9 0 180)
			(size 1.45 1.15)
			(layers "F.Cu" "F.Mask" "F.Paste")
			(net "+3.3V_CLEAN")
		)
	)
	(footprint "Passives:DIOM1608X06N"
		(layer "F.Cu")
		(at 79.989925 53.2366 90)
		(property "Reference" "D12"
			(at -1.45369 -1.231865 90)
			(unlocked yes)
			(layer "F.SilkS")
			(effects
				(font
					(size 0.762 0.762)
					(thickness 0.2286)
				)
				(justify left bottom)
			)
		)
		(property "Value" "RED"
			(at -4.13639 -0.5715 0)
			(unlocked yes)
			(layer "F.SilkS")
			(hide yes)
			(effects
				(font
					(size 1.524 1.524)
					(thickness 0.254)
				)
				(justify left bottom)
			)
		)
		(sheetname "USER_IO")
		(sheetfile "USER_IO.kicad_sch")
		(duplicate_pad_numbers_are_jumpers no)
		(fp_circle
			(center -1.275 -0.725)
			(end -1.225 -0.725)
			(stroke
				(width 0.1)
				(type solid)
			)
			(fill no)
			(layer "F.SilkS")
		)
		(pad "1" smd rect
			(at -0.725 0 180)
			(size 0.85 1)
			(layers "F.Cu" "F.Mask" "F.Paste")
			(net "NetD12_1")
		)
		(pad "2" smd rect
			(at 0.725 0 180)
			(size 0.85 1)
			(layers "F.Cu" "F.Mask" "F.Paste")
			(net "+3.3V")
		)
	)
	(footprint "Capacitors:CAPC1608X10N"
		(layer "F.Cu")
		(at 222.822595 102.8936 90)
		(property "Reference" "C3"
			(at -3.16 0.509345 90)
			(unlocked yes)
			(layer "F.SilkS")
			(effects
				(font
					(size 0.762 0.762)
					(thickness 0.2286)
				)
				(justify left bottom)
			)
		)
		(property "Value" "CAP_0603_0.01UF_50V"
			(at 12.98321 3.9751 0)
			(unlocked yes)
			(layer "F.SilkS")
			(hide yes)
			(effects
				(font
					(size 1.524 1.524)
					(thickness 0.254)
				)
				(justify left bottom)
			)
		)
		(sheetname "POWER")
		(sheetfile "POWER.kicad_sch")
		(duplicate_pad_numbers_are_jumpers no)
		(fp_line
			(start -0.635 -0.7112)
			(end 0.635 -0.7112)
			(stroke
				(width 0.1524)
				(type solid)
			)
			(layer "F.SilkS")
		)
		(fp_line
			(start -0.635 0.7112)
			(end 0.635 0.7112)
			(stroke
				(width 0.1524)
				(type solid)
			)
			(layer "F.SilkS")
		)
		(pad "1" smd rect
			(at -0.8 0 180)
			(size 0.95 1)
			(layers "F.Cu" "F.Mask" "F.Paste")
			(net "NetC3_1")
		)
		(pad "2" smd rect
			(at 0.8 0 180)
			(size 0.95 1)
			(layers "F.Cu" "F.Mask" "F.Paste")
			(net "NetC3_2")
		)
	)
	(footprint "Passives:SODFL370X135-2N"
		(layer "F.Cu")
		(at 217.742595 66.5716)
		(property "Reference" "D3"
			(at 3.439345 0.507 90)
			(unlocked yes)
			(layer "F.SilkS")
			(effects
				(font
					(size 0.762 0.762)
					(thickness 0.2286)
				)
				(justify left bottom)
			)
		)
		(property "Value" "DFLZ39-TP"
			(at -2.0955 3.62839 0)
			(unlocked yes)
			(layer "F.SilkS")
			(hide yes)
			(effects
				(font
					(size 1.524 1.524)
					(thickness 0.254)
				)
				(justify left bottom)
			)
		)
		(sheetname "POWER")
		(sheetfile "POWER.kicad_sch")
		(duplicate_pad_numbers_are_jumpers no)
		(fp_line
			(start -1.55 -0.95)
			(end 1.55 -0.95)
			(stroke
				(width 0.2)
				(type solid)
			)
			(layer "F.SilkS")
		)
		(fp_line
			(start -1.55 -0.825)
			(end -1.55 -0.95)
			(stroke
				(width 0.2)
				(type solid)
			)
			(layer "F.SilkS")
		)
		(fp_line
			(start -1.55 0.95)
			(end -1.55 0.825)
			(stroke
				(width 0.2)
				(type solid)
			)
			(layer "F.SilkS")
		)
		(fp_line
			(start -1.55 0.95)
			(end 1.55 0.95)
			(stroke
				(width 0.2)
				(type solid)
			)
			(layer "F.SilkS")
		)
		(fp_line
			(start 1.55 -0.825)
			(end 1.55 -0.95)
			(stroke
				(width 0.2)
				(type solid)
			)
			(layer "F.SilkS")
		)
		(fp_line
			(start 1.55 0.95)
			(end 1.55 0.825)
			(stroke
				(width 0.2)
				(type solid)
			)
			(layer "F.SilkS")
		)
		(fp_circle
			(center -2.05 -0.825)
			(end -2.05 -0.875)
			(stroke
				(width 0.1)
				(type solid)
			)
			(fill no)
			(layer "F.SilkS")
		)
		(pad "1" smd rect
			(at -1.825 0 90)
			(size 1.05 0.65)
			(layers "F.Cu" "F.Mask" "F.Paste")
			(net "NetD2_1")
		)
		(pad "2" smd rect
			(at 1.825 0 90)
			(size 1.05 0.65)
			(layers "F.Cu" "F.Mask" "F.Paste")
			(net "+12V_PCIE")
		)
	)
	(footprint "Connectors:USB_47346-1001"
		(layer "F.Cu")
		(at 119.035795 54.652 180)
		(property "Reference" "J4"
			(at -3.34281 -0.392255 0)
			(unlocked yes)
			(layer "F.SilkS")
			(effects
				(font
					(size 0.762 0.762)
					(thickness 0.2286)
				)
				(justify left bottom)
			)
		)
		(property "Value" "473461001"
			(at 3.1067 -2.01679 0)
			(unlocked yes)
			(layer "F.SilkS")
			(hide yes)
			(effects
				(font
					(size 1.524 1.524)
					(thickness 0.254)
				)
				(justify left bottom)
			)
		)
		(sheetname "GPS_IMU_SENSORS")
		(sheetfile "GPS_IMU_SENSORS.kicad_sch")
		(duplicate_pad_numbers_are_jumpers no)
		(fp_line
			(start 5.364 -0.254)
			(end 5.364 1.651)
			(stroke
				(width 0.1524)
				(type solid)
			)
			(layer "F.SilkS")
		)
		(fp_line
			(start -2.764 -0.254)
			(end -2.764 1.651)
			(stroke
				(width 0.1524)
				(type solid)
			)
			(layer "F.SilkS")
		)
		(fp_text user "1"
			(at -0.29131 -1.11 270)
			(unlocked yes)
			(layer "F.SilkS")
			(effects
				(font
					(size 1.524 1.524)
					(thickness 0.254)
				)
				(justify left bottom)
			)
		)
		(pad "0" smd rect
			(at -2.075 2.66 180)
			(size 1.65 1.3)
			(layers "F.Cu" "F.Mask" "F.Paste")
		)
		(pad "0" smd rect
			(at -1.2 0.085 180)
			(size 1.42 1.55)
			(layers "F.Cu" "F.Mask" "F.Paste")
		)
		(pad "0" smd rect
			(at 0.15 2.66 180)
			(size 1.8 1.9)
			(layers "F.Cu" "F.Mask" "F.Paste")
		)
		(pad "0" smd rect
			(at 2.85 2.66 180)
			(size 1 1.9)
			(layers "F.Cu" "F.Mask" "F.Paste")
		)
		(pad "0" smd rect
			(at 3.8 0.085 180)
			(size 1.42 1.55)
			(layers "F.Cu" "F.Mask" "F.Paste")
		)
		(pad "0" smd rect
			(at 4.675 2.66 180)
			(size 1.65 1.3)
			(layers "F.Cu" "F.Mask" "F.Paste")
		)
		(pad "1" smd rect
			(at 0 0 180)
			(size 0.45 1.38)
			(layers "F.Cu" "F.Mask" "F.Paste")
		)
		(pad "2" smd rect
			(at 0.65 0 180)
			(size 0.45 1.38)
			(layers "F.Cu" "F.Mask" "F.Paste")
			(net "NetJ4_2")
		)
		(pad "3" smd rect
			(at 1.3 0 180)
			(size 0.45 1.38)
			(layers "F.Cu" "F.Mask" "F.Paste")
			(net "NetJ4_3")
		)
		(pad "4" smd rect
			(at 1.95 0 180)
			(size 0.45 1.38)
			(layers "F.Cu" "F.Mask" "F.Paste")
		)
		(pad "5" smd rect
			(at 2.6 0 180)
			(size 0.45 1.38)
			(layers "F.Cu" "F.Mask" "F.Paste")
			(net "GND")
		)
	)
	(footprint "Resistors:RESC1608X50N"
		(layer "F.Cu")
		(at 236.288595 112.1786 90)
		(property "Reference" "R8"
			(at 1.5 0.393345 90)
			(unlocked yes)
			(layer "F.SilkS")
			(effects
				(font
					(size 0.762 0.762)
					(thickness 0.2286)
				)
				(justify left bottom)
			)
		)
		(property "Value" "ERJ-3EKF2201V"
			(at -3.04419 -4.4323 0)
			(unlocked yes)
			(layer "F.SilkS")
			(hide yes)
			(effects
				(font
					(size 1.524 1.524)
					(thickness 0.254)
				)
				(justify left bottom)
			)
		)
		(sheetname "POWER")
		(sheetfile "POWER.kicad_sch")
		(duplicate_pad_numbers_are_jumpers no)
		(fp_line
			(start 0 -0.5)
			(end 0 0.5)
			(stroke
				(width 0.1524)
				(type solid)
			)
			(layer "F.SilkS")
		)
		(pad "1" smd rect
			(at -0.69 0 180)
			(size 1 0.72)
			(layers "F.Cu" "F.Mask" "F.Paste")
			(net "GND")
		)
		(pad "2" smd rect
			(at 0.69 0 180)
			(size 1 0.72)
			(layers "F.Cu" "F.Mask" "F.Paste")
			(net "NetC20_1")
		)
	)
	(footprint "Connectors:AMPHENOL-901-143-6RFX"
		(layer "F.Cu")
		(at 63.564595 137.5646 180)
		(property "Reference" "AN4"
			(at -5.20749 -4.601655 0)
			(unlocked yes)
			(layer "F.SilkS")
			(effects
				(font
					(size 0.762 0.762)
					(thickness 0.2286)
				)
				(justify left bottom)
			)
		)
		(property "Value" "RF-901-143-6FRX"
			(at 4.6101 -12.21359 0)
			(unlocked yes)
			(layer "F.SilkS")
			(hide yes)
			(effects
				(font
					(size 1.524 1.524)
					(thickness 0.254)
				)
				(justify left bottom)
			)
		)
		(sheetfile ".kicad_sch")
		(duplicate_pad_numbers_are_jumpers no)
		(fp_line
			(start 4.318 3.556)
			(end 3.302 4.572)
			(stroke
				(width 0.1778)
				(type solid)
			)
			(layer "F.SilkS")
		)
		(fp_line
			(start 4.318 -3.556)
			(end 3.302 -4.572)
			(stroke
				(width 0.1778)
				(type solid)
			)
			(layer "F.SilkS")
		)
		(fp_line
			(start 3.302 4.572)
			(end 2.54 4.572)
			(stroke
				(width 0.1778)
				(type solid)
			)
			(layer "F.SilkS")
		)
		(fp_line
			(start 3.302 -4.572)
			(end 2.54 -4.572)
			(stroke
				(width 0.1778)
				(type solid)
			)
			(layer "F.SilkS")
		)
		(fp_line
			(start 2.54 4.572)
			(end -4.572 4.572)
			(stroke
				(width 0.1778)
				(type solid)
			)
			(layer "F.SilkS")
		)
		(fp_line
			(start 2.54 -4.572)
			(end -4.572 -4.572)
			(stroke
				(width 0.1778)
				(type solid)
			)
			(layer "F.SilkS")
		)
		(fp_line
			(start -4.572 2.54)
			(end -4.572 4.572)
			(stroke
				(width 0.1778)
				(type solid)
			)
			(layer "F.SilkS")
		)
		(fp_line
			(start -4.572 -4.572)
			(end -4.572 -2.54)
			(stroke
				(width 0.1778)
				(type solid)
			)
			(layer "F.SilkS")
		)
		(pad "1" thru_hole circle
			(at 0 0 180)
			(size 2.8448 2.8448)
			(drill 1.524)
			(layers "*.Cu" "*.Mask")
			(remove_unused_layers no)
			(net "ANT4")
			(thermal_bridge_angle 90)
		)
		(pad "2" thru_hole circle
			(at -2.54 2.54 180)
			(size 3.048 3.048)
			(drill 1.7272)
			(layers "*.Cu" "*.Mask")
			(remove_unused_layers no)
			(net "GND")
			(thermal_bridge_angle 90)
		)
		(pad "3" thru_hole circle
			(at -2.54 -2.54 180)
			(size 3.048 3.048)
			(drill 1.7272)
			(layers "*.Cu" "*.Mask")
			(remove_unused_layers no)
			(net "GND")
			(thermal_bridge_angle 90)
		)
		(pad "4" thru_hole circle
			(at 2.54 -2.54 180)
			(size 3.048 3.048)
			(drill 1.7272)
			(layers "*.Cu" "*.Mask")
			(remove_unused_layers no)
			(net "GND")
			(thermal_bridge_angle 90)
		)
		(pad "5" thru_hole circle
			(at 2.54 2.54 180)
			(size 3.048 3.048)
			(drill 1.7272)
			(layers "*.Cu" "*.Mask")
			(remove_unused_layers no)
			(net "GND")
			(thermal_bridge_angle 90)
		)
	)
	(footprint "Vault:RESC1608X55X30NL15T15"
		(layer "F.Cu")
		(at 74.788595 56.9786 90)
		(property "Reference" "R16"
			(at 0.154 -1.673069 90)
			(unlocked yes)
			(layer "F.SilkS")
			(effects
				(font
					(size 0.762 0.762)
					(thickness 0.254)
				)
			)
		)
		(property "Value" "200 OHM"
			(at -2.085402 4.85075 0)
			(unlocked yes)
			(layer "F.SilkS")
			(hide yes)
			(effects
				(font
					(size 1.524 1.524)
					(thickness 0.254)
				)
			)
		)
		(sheetname "USER_IO")
		(sheetfile "USER_IO.kicad_sch")
		(duplicate_pad_numbers_are_jumpers no)
		(pad "1" smd rect
			(at -0.675 0 180)
			(size 0.95 0.8)
			(layers "F.Cu" "F.Mask" "F.Paste")
			(net "LED1")
		)
		(pad "2" smd rect
			(at 0.675 0 180)
			(size 0.95 0.8)
			(layers "F.Cu" "F.Mask" "F.Paste")
			(net "NetD11_1")
		)
	)
	(footprint "Resistors:RESC1608X50N"
		(layer "F.Cu")
		(at 232.982595 114.4506)
		(property "Reference" "R4"
			(at -0.619 1.771345 0)
			(unlocked yes)
			(layer "F.SilkS")
			(effects
				(font
					(size 0.762 0.762)
					(thickness 0.2286)
				)
				(justify left bottom)
			)
		)
		(property "Value" "ERJ-3EKF4702V"
			(at -4.4323 3.04419 0)
			(unlocked yes)
			(layer "F.SilkS")
			(hide yes)
			(effects
				(font
					(size 1.524 1.524)
					(thickness 0.254)
				)
				(justify left bottom)
			)
		)
		(sheetname "POWER")
		(sheetfile "POWER.kicad_sch")
		(duplicate_pad_numbers_are_jumpers no)
		(fp_line
			(start 0 0.5)
			(end 0 -0.5)
			(stroke
				(width 0.1524)
				(type solid)
			)
			(layer "F.SilkS")
		)
		(pad "1" smd rect
			(at -0.69 0 90)
			(size 1 0.72)
			(layers "F.Cu" "F.Mask" "F.Paste")
			(net "+5.0V")
		)
		(pad "2" smd rect
			(at 0.69 0 90)
			(size 1 0.72)
			(layers "F.Cu" "F.Mask" "F.Paste")
			(net "NetR4_2")
		)
	)
	(footprint "Passives:SODFL370X135-2N"
		(layer "F.Cu")
		(at 209.868595 66.5716)
		(property "Reference" "D1"
			(at 3.413345 0.407 90)
			(unlocked yes)
			(layer "F.SilkS")
			(effects
				(font
					(size 0.762 0.762)
					(thickness 0.2286)
				)
				(justify left bottom)
			)
		)
		(property "Value" "DFLZ39-TP"
			(at -2.0955 3.62839 0)
			(unlocked yes)
			(layer "F.SilkS")
			(hide yes)
			(effects
				(font
					(size 1.524 1.524)
					(thickness 0.254)
				)
				(justify left bottom)
			)
		)
		(sheetname "POWER")
		(sheetfile "POWER.kicad_sch")
		(duplicate_pad_numbers_are_jumpers no)
		(fp_line
			(start -1.55 -0.95)
			(end 1.55 -0.95)
			(stroke
				(width 0.2)
				(type solid)
			)
			(layer "F.SilkS")
		)
		(fp_line
			(start -1.55 -0.825)
			(end -1.55 -0.95)
			(stroke
				(width 0.2)
				(type solid)
			)
			(layer "F.SilkS")
		)
		(fp_line
			(start -1.55 0.95)
			(end -1.55 0.825)
			(stroke
				(width 0.2)
				(type solid)
			)
			(layer "F.SilkS")
		)
		(fp_line
			(start -1.55 0.95)
			(end 1.55 0.95)
			(stroke
				(width 0.2)
				(type solid)
			)
			(layer "F.SilkS")
		)
		(fp_line
			(start 1.55 -0.825)
			(end 1.55 -0.95)
			(stroke
				(width 0.2)
				(type solid)
			)
			(layer "F.SilkS")
		)
		(fp_line
			(start 1.55 0.95)
			(end 1.55 0.825)
			(stroke
				(width 0.2)
				(type solid)
			)
			(layer "F.SilkS")
		)
		(fp_circle
			(center -2.05 -0.825)
			(end -2.05 -0.875)
			(stroke
				(width 0.1)
				(type solid)
			)
			(fill no)
			(layer "F.SilkS")
		)
		(pad "1" smd rect
			(at -1.825 0 90)
			(size 1.05 0.65)
			(layers "F.Cu" "F.Mask" "F.Paste")
			(net "NetD1_1")
		)
		(pad "2" smd rect
			(at 1.825 0 90)
			(size 1.05 0.65)
			(layers "F.Cu" "F.Mask" "F.Paste")
			(net "NetD1_2")
		)
	)
	(footprint "Passives:SOT65P210X110-3N"
		(layer "F.Cu")
		(at 127.572595 66.4446 -90)
		(property "Reference" "D6"
			(at -2.865945 0.36799 0)
			(unlocked yes)
			(layer "F.SilkS")
			(effects
				(font
					(size 0.762 0.762)
					(thickness 0.2286)
				)
				(justify left bottom)
			)
		)
		(property "Value" "BAT54SW"
			(at 3.88239 1.5875 0)
			(unlocked yes)
			(layer "F.SilkS")
			(hide yes)
			(effects
				(font
					(size 1.524 1.524)
					(thickness 0.254)
				)
				(justify left bottom)
			)
		)
		(sheetname "PCIe_JTAG")
		(sheetfile "PCIe_JTAG.kicad_sch")
		(duplicate_pad_numbers_are_jumpers no)
		(fp_line
			(start 0.675 1.1)
			(end -0.325 1.1)
			(stroke
				(width 0.2)
				(type solid)
			)
			(layer "F.SilkS")
		)
		(fp_line
			(start 0.675 1.1)
			(end 0.675 0.65)
			(stroke
				(width 0.2)
				(type solid)
			)
			(layer "F.SilkS")
		)
		(fp_line
			(start 0.675 -0.65)
			(end 0.675 -1.1)
			(stroke
				(width 0.2)
				(type solid)
			)
			(layer "F.SilkS")
		)
		(fp_line
			(start 0.675 -1.1)
			(end -0.325 -1.1)
			(stroke
				(width 0.2)
				(type solid)
			)
			(layer "F.SilkS")
		)
		(fp_circle
			(center -1.125 -1.45)
			(end -1.25 -1.45)
			(stroke
				(width 0.25)
				(type solid)
			)
			(fill no)
			(layer "F.SilkS")
		)
		(pad "1" smd rect
			(at -1.125 -0.65)
			(size 0.5 0.9)
			(layers "F.Cu" "F.Mask" "F.Paste")
			(net "GND")
		)
		(pad "2" smd rect
			(at -1.125 0.65)
			(size 0.5 0.9)
			(layers "F.Cu" "F.Mask" "F.Paste")
			(net "+3.3V")
		)
		(pad "3" smd rect
			(at 1.125 0)
			(size 0.5 0.9)
			(layers "F.Cu" "F.Mask" "F.Paste")
			(net "FPGA_TDO")
		)
	)
	(footprint "Vault:CAPC1608X87X45ML20T05"
		(layer "F.Cu")
		(at 162.878595 82.8276 -90)
		(property "Reference" "C77"
			(at -3.249 1.771655 90)
			(unlocked yes)
			(layer "F.SilkS")
			(effects
				(font
					(size 0.762 0.762)
					(thickness 0.2286)
				)
				(justify left bottom)
			)
		)
		(property "Value" "0.1uF"
			(at 3.47599 0.2921 0)
			(unlocked yes)
			(layer "F.SilkS")
			(hide yes)
			(effects
				(font
					(size 1.524 1.524)
					(thickness 0.254)
				)
				(justify left bottom)
			)
		)
		(sheetname "MAC")
		(sheetfile "MAC.kicad_sch")
		(duplicate_pad_numbers_are_jumpers no)
		(pad "1" smd rect
			(at -0.7 0)
			(size 1.1 1.05)
			(layers "F.Cu" "F.Mask" "F.Paste")
			(net "GND")
		)
		(pad "2" smd rect
			(at 0.7 0)
			(size 1.1 1.05)
			(layers "F.Cu" "F.Mask" "F.Paste")
			(net "+3.3V_CLEAN")
		)
	)
	(footprint "Vault:CAPC1608X87X45ML20T05"
		(layer "F.Cu")
		(at 233.109595 107.3386 180)
		(property "Reference" "C19"
			(at 1.046 1.141655 0)
			(unlocked yes)
			(layer "F.SilkS")
			(effects
				(font
					(size 0.762 0.762)
					(thickness 0.2286)
				)
				(justify left bottom)
			)
		)
		(property "Value" "0.1uF"
			(at 3.9751 -3.95859 0)
			(unlocked yes)
			(layer "F.SilkS")
			(hide yes)
			(effects
				(font
					(size 1.524 1.524)
					(thickness 0.254)
				)
				(justify left bottom)
			)
		)
		(sheetname "POWER")
		(sheetfile "POWER.kicad_sch")
		(duplicate_pad_numbers_are_jumpers no)
		(pad "1" smd rect
			(at -0.7 0 270)
			(size 1.1 1.05)
			(layers "F.Cu" "F.Mask" "F.Paste")
			(net "GND")
		)
		(pad "2" smd rect
			(at 0.7 0 270)
			(size 1.1 1.05)
			(layers "F.Cu" "F.Mask" "F.Paste")
			(net "NetC19_2")
		)
	)
	(footprint "Vault:CAPC1608X87X45ML20T05"
		(layer "F.Cu")
		(at 227.648595 116.8636)
		(property "Reference" "C17"
			(at 1.74 0.708345 0)
			(unlocked yes)
			(layer "F.SilkS")
			(effects
				(font
					(size 0.762 0.762)
					(thickness 0.2286)
				)
				(justify left bottom)
			)
		)
		(property "Value" "0.1uF"
			(at 1.6129 8.42899 0)
			(unlocked yes)
			(layer "F.SilkS")
			(hide yes)
			(effects
				(font
					(size 1.524 1.524)
					(thickness 0.254)
				)
				(justify left bottom)
			)
		)
		(sheetname "POWER")
		(sheetfile "POWER.kicad_sch")
		(duplicate_pad_numbers_are_jumpers no)
		(pad "1" smd rect
			(at -0.7 0 90)
			(size 1.1 1.05)
			(layers "F.Cu" "F.Mask" "F.Paste")
			(net "GND")
		)
		(pad "2" smd rect
			(at 0.7 0 90)
			(size 1.1 1.05)
			(layers "F.Cu" "F.Mask" "F.Paste")
			(net "+5.0V")
		)
	)
	(footprint "Miscellaneous:SIT5721"
		(layer "F.Cu")
		(at 146.149595 76.7406 -90)
		(property "Reference" "U11"
			(at -2.189145 7.41965 0)
			(unlocked yes)
			(layer "F.SilkS")
			(effects
				(font
					(size 0.762 0.762)
					(thickness 0.2286)
				)
				(justify left bottom)
			)
		)
		(property "Value" "SiT5721AI-KWA33-T-10.000000"
			(at 5.60959 1.61298 0)
			(unlocked yes)
			(layer "F.SilkS")
			(hide yes)
			(effects
				(font
					(size 1.524 1.524)
					(thickness 0.254)
				)
				(justify left bottom)
			)
		)
		(sheetname "MAC")
		(sheetfile "MAC.kicad_sch")
		(duplicate_pad_numbers_are_jumpers no)
		(fp_line
			(start -3.5 4.5)
			(end -3.5 3.5)
			(stroke
				(width 0.2032)
				(type solid)
			)
			(layer "F.SilkS")
		)
		(fp_line
			(start -2.5 4.5)
			(end -3.5 4.5)
			(stroke
				(width 0.2032)
				(type solid)
			)
			(layer "F.SilkS")
		)
		(fp_line
			(start 3.5 4.5)
			(end 2.5 4.5)
			(stroke
				(width 0.2032)
				(type solid)
			)
			(layer "F.SilkS")
		)
		(fp_line
			(start 3.5 4.5)
			(end 3.5 3.5)
			(stroke
				(width 0.2032)
				(type solid)
			)
			(layer "F.SilkS")
		)
		(fp_line
			(start -3.5 -1.45426)
			(end -3.5 -4.5)
			(stroke
				(width 0.2032)
				(type solid)
			)
			(layer "F.SilkS")
		)
		(fp_line
			(start 3.5 -3.5)
			(end 3.5 -4.5)
			(stroke
				(width 0.2032)
				(type solid)
			)
			(layer "F.SilkS")
		)
		(fp_line
			(start -0.66154 -4.5)
			(end -3.5 -4.5)
			(stroke
				(width 0.2032)
				(type solid)
			)
			(layer "F.SilkS")
		)
		(fp_line
			(start 3.5 -4.5)
			(end 2.5 -4.5)
			(stroke
				(width 0.2032)
				(type solid)
			)
			(layer "F.SilkS")
		)
		(pad "1" smd rect
			(at -2.15 -3 270)
			(size 2.3 1)
			(layers "F.Cu" "F.Mask" "F.Paste")
		)
		(pad "2" smd rect
			(at -2.4 -1.5 270)
			(size 1.8 1)
			(layers "F.Cu" "F.Mask" "F.Paste")
			(net "5721_STATUS")
		)
		(pad "3" smd rect
			(at -2.4 0 270)
			(size 1.8 1)
			(layers "F.Cu" "F.Mask" "F.Paste")
			(net "SCL")
		)
		(pad "4" smd rect
			(at -2.4 1.5 270)
			(size 1.8 1)
			(layers "F.Cu" "F.Mask" "F.Paste")
			(net "SDA")
		)
		(pad "5" smd rect
			(at -2.4 3 90)
			(size 1.8 1)
			(layers "F.Cu" "F.Mask" "F.Paste")
			(net "GND")
		)
		(pad "6" smd rect
			(at 2.4 3 270)
			(size 1.8 1)
			(layers "F.Cu" "F.Mask" "F.Paste")
			(net "DCXO2")
		)
		(pad "7" smd rect
			(at 2.4 1.5 270)
			(size 1.8 1)
			(layers "F.Cu" "F.Mask" "F.Paste")
		)
		(pad "8" smd rect
			(at 2.4 0 270)
			(size 1.8 1)
			(layers "F.Cu" "F.Mask" "F.Paste")
		)
		(pad "9" smd rect
			(at 2.4 -1.5 270)
			(size 1.8 1)
			(layers "F.Cu" "F.Mask" "F.Paste")
		)
		(pad "10" smd rect
			(at 2.4 -3 90)
			(size 1.8 1)
			(layers "F.Cu" "F.Mask" "F.Paste")
			(net "+3.3V_CLEAN")
		)
	)
	(footprint "Miscellaneous Devices:J1-0603"
		(layer "F.Cu")
		(at 82.113595 116.2036 180)
		(property "Reference" "R14"
			(at -2.829 -0.001931 0)
			(unlocked yes)
			(layer "F.SilkS")
			(effects
				(font
					(size 0.762 0.762)
					(thickness 0.254)
				)
			)
		)
		(property "Value" "MACPPSO"
			(at -4.73554 -2.835402 0)
			(unlocked yes)
			(layer "F.SilkS")
			(hide yes)
			(effects
				(font
					(size 1.524 1.524)
					(thickness 0.254)
				)
			)
		)
		(sheetname "USER_IO")
		(sheetfile "USER_IO.kicad_sch")
		(duplicate_pad_numbers_are_jumpers no)
		(fp_line
			(start 0.2 0.35)
			(end -0.2 0.35)
			(stroke
				(width 0.2)
				(type solid)
			)
			(layer "F.SilkS")
		)
		(fp_line
			(start 0.2 -0.35)
			(end -0.2 -0.35)
			(stroke
				(width 0.2)
				(type solid)
			)
			(layer "F.SilkS")
		)
		(pad "1" smd rect
			(at -0.75 0 270)
			(size 0.9 0.7)
			(layers "F.Cu" "F.Mask" "F.Paste")
			(net "MAC_PPS_OUT+")
		)
		(pad "2" smd rect
			(at 0.75 0 270)
			(size 0.9 0.7)
			(layers "F.Cu" "F.Mask" "F.Paste")
			(net "ANT2")
		)
	)
	(footprint "Connectors:PCIE_4LANE_EDGE"
		(layer "F.Cu")
		(at 120.638465 154.3547)
		(property "Reference" "P2"
			(at -12.64987 -0.282755 0)
			(unlocked yes)
			(layer "F.SilkS")
			(hide yes)
			(effects
				(font
					(size 0.762 0.762)
					(thickness 0.2286)
				)
				(justify left bottom)
			)
		)
		(property "Value" "PCIex4"
			(at -5.44907 18.65122 0)
			(unlocked yes)
			(layer "F.SilkS")
			(hide yes)
			(effects
				(font
					(size 1.524 1.524)
					(thickness 0.254)
				)
				(justify left bottom)
			)
		)
		(sheetname "PCIe_JTAG")
		(sheetfile "PCIe_JTAG.kicad_sch")
		(duplicate_pad_numbers_are_jumpers no)
		(pad "A1" smd rect
			(at -16.49984 2.2286)
			(size 0.7112 3.2004)
			(layers "B.Cu" "B.Mask" "B.Paste")
			(net "PRSNT")
		)
		(pad "A2" smd rect
			(at -15.49985 2.7239)
			(size 0.7112 4.191)
			(layers "B.Cu" "B.Mask" "B.Paste")
			(net "+12V_PCIE")
		)
		(pad "A3" smd rect
			(at -14.49985 2.7239)
			(size 0.7112 4.191)
			(layers "B.Cu" "B.Mask" "B.Paste")
			(net "+12V_PCIE")
		)
		(pad "A4" smd rect
			(at -13.49985 2.7239)
			(size 0.7112 4.191)
			(layers "B.Cu" "B.Mask" "B.Paste")
			(net "GND")
		)
		(pad "A5" smd rect
			(at -12.49985 2.7239)
			(size 0.7112 4.191)
			(layers "B.Cu" "B.Mask" "B.Paste")
		)
		(pad "A6" smd rect
			(at -11.49985 2.7239)
			(size 0.7112 4.191)
			(layers "B.Cu" "B.Mask" "B.Paste")
		)
		(pad "A7" smd rect
			(at -10.49986 2.7239)
			(size 0.7112 4.191)
			(layers "B.Cu" "B.Mask" "B.Paste")
		)
		(pad "A8" smd rect
			(at -9.49986 2.7239)
			(size 0.7112 4.191)
			(layers "B.Cu" "B.Mask" "B.Paste")
		)
		(pad "A9" smd rect
			(at -8.49986 2.7239)
			(size 0.7112 4.191)
			(layers "B.Cu" "B.Mask" "B.Paste")
			(net "+3.3V_PCIE")
		)
		(pad "A10" smd rect
			(at -7.49986 2.7239)
			(size 0.7112 4.191)
			(layers "B.Cu" "B.Mask" "B.Paste")
			(net "+3.3V_PCIE")
		)
		(pad "A11" smd rect
			(at -6.49986 2.7239)
			(size 0.7112 4.191)
			(layers "B.Cu" "B.Mask" "B.Paste")
			(net "PCIE_PERST")
		)
		(pad "A12" smd rect
			(at -3.49987 2.7239)
			(size 0.7112 4.191)
			(layers "B.Cu" "B.Mask" "B.Paste")
			(net "GND")
		)
		(pad "A13" smd rect
			(at -2.49987 2.7239)
			(size 0.7112 4.191)
			(layers "B.Cu" "B.Mask" "B.Paste")
			(net "NetC44_1")
		)
		(pad "A14" smd rect
			(at -1.49987 2.7239)
			(size 0.7112 4.191)
			(layers "B.Cu" "B.Mask" "B.Paste")
			(net "NetC45_1")
		)
		(pad "A15" smd rect
			(at -0.49988 2.7239)
			(size 0.7112 4.191)
			(layers "B.Cu" "B.Mask" "B.Paste")
			(net "GND")
		)
		(pad "A16" smd rect
			(at 0.50012 2.7239)
			(size 0.7112 4.191)
			(layers "B.Cu" "B.Mask" "B.Paste")
			(net "NetC46_1")
		)
		(pad "A17" smd rect
			(at 1.50012 2.7239)
			(size 0.7112 4.191)
			(layers "B.Cu" "B.Mask" "B.Paste")
			(net "NetC47_1")
		)
		(pad "A18" smd rect
			(at 2.50012 2.7239)
			(size 0.7112 4.191)
			(layers "B.Cu" "B.Mask" "B.Paste")
			(net "GND")
		)
		(pad "A19" smd rect
			(at 3.50012 2.7239)
			(size 0.7112 4.191)
			(layers "B.Cu" "B.Mask" "B.Paste")
		)
		(pad "A20" smd rect
			(at 4.50011 2.7239)
			(size 0.7112 4.191)
			(layers "B.Cu" "B.Mask" "B.Paste")
			(net "GND")
		)
		(pad "A21" smd rect
			(at 5.50011 2.7239)
			(size 0.7112 4.191)
			(layers "B.Cu" "B.Mask" "B.Paste")
			(net "NetC48_1")
		)
		(pad "A22" smd rect
			(at 6.50011 2.7239)
			(size 0.7112 4.191)
			(layers "B.Cu" "B.Mask" "B.Paste")
			(net "NetC49_1")
		)
		(pad "A23" smd rect
			(at 7.50011 2.7239)
			(size 0.7112 4.191)
			(layers "B.Cu" "B.Mask" "B.Paste")
			(net "GND")
		)
		(pad "A24" smd rect
			(at 8.50011 2.7239)
			(size 0.7112 4.191)
			(layers "B.Cu" "B.Mask" "B.Paste")
			(net "GND")
		)
		(pad "A25" smd rect
			(at 9.5001 2.7239)
			(size 0.7112 4.191)
			(layers "B.Cu" "B.Mask" "B.Paste")
			(net "NetC50_1")
		)
		(pad "A26" smd rect
			(at 10.5001 2.7239)
			(size 0.7112 4.191)
			(layers "B.Cu" "B.Mask" "B.Paste")
			(net "NetC51_1")
		)
		(pad "A27" smd rect
			(at 11.5001 2.7239)
			(size 0.7112 4.191)
			(layers "B.Cu" "B.Mask" "B.Paste")
			(net "GND")
		)
		(pad "A28" smd rect
			(at 12.5001 2.7239)
			(size 0.7112 4.191)
			(layers "B.Cu" "B.Mask" "B.Paste")
			(net "GND")
		)
		(pad "A29" smd rect
			(at 13.5001 2.7239)
			(size 0.7112 4.191)
			(layers "B.Cu" "B.Mask" "B.Paste")
			(net "NetC52_1")
		)
		(pad "A30" smd rect
			(at 14.50009 2.7239)
			(size 0.7112 4.191)
			(layers "B.Cu" "B.Mask" "B.Paste")
			(net "NetC53_1")
		)
		(pad "A31" smd rect
			(at 15.50009 2.7239)
			(size 0.7112 4.191)
			(layers "B.Cu" "B.Mask" "B.Paste")
			(net "GND")
		)
		(pad "A32" smd rect
			(at 16.50009 2.7239)
			(size 0.7112 4.191)
			(layers "B.Cu" "B.Mask" "B.Paste")
		)
		(pad "B1" smd rect
			(at -16.49984 2.7239)
			(size 0.7112 4.191)
			(layers "F.Cu" "F.Mask" "F.Paste")
			(net "+12V_PCIE")
		)
		(pad "B2" smd rect
			(at -15.49985 2.7239)
			(size 0.7112 4.191)
			(layers "F.Cu" "F.Mask" "F.Paste")
			(net "+12V_PCIE")
		)
		(pad "B3" smd rect
			(at -14.49985 2.7239)
			(size 0.7112 4.191)
			(layers "F.Cu" "F.Mask" "F.Paste")
			(net "+12V_PCIE")
		)
		(pad "B4" smd rect
			(at -13.49985 2.7239)
			(size 0.7112 4.191)
			(layers "F.Cu" "F.Mask" "F.Paste")
			(net "GND")
		)
		(pad "B5" smd rect
			(at -12.49985 2.7239)
			(size 0.7112 4.191)
			(layers "F.Cu" "F.Mask" "F.Paste")
		)
		(pad "B6" smd rect
			(at -11.49985 2.7239)
			(size 0.7112 4.191)
			(layers "F.Cu" "F.Mask" "F.Paste")
		)
		(pad "B7" smd rect
			(at -10.49986 2.7239)
			(size 0.7112 4.191)
			(layers "F.Cu" "F.Mask" "F.Paste")
			(net "GND")
		)
		(pad "B8" smd rect
			(at -9.49986 2.7239)
			(size 0.7112 4.191)
			(layers "F.Cu" "F.Mask" "F.Paste")
			(net "+3.3V_PCIE")
		)
		(pad "B9" smd rect
			(at -8.49986 2.7239)
			(size 0.7112 4.191)
			(layers "F.Cu" "F.Mask" "F.Paste")
		)
		(pad "B10" smd rect
			(at -7.49986 2.7239)
			(size 0.7112 4.191)
			(layers "F.Cu" "F.Mask" "F.Paste")
		)
		(pad "B11" smd rect
			(at -6.49986 2.7239)
			(size 0.7112 4.191)
			(layers "F.Cu" "F.Mask" "F.Paste")
		)
		(pad "B12" smd rect
			(at -3.49987 2.7239)
			(size 0.7112 4.191)
			(layers "F.Cu" "F.Mask" "F.Paste")
		)
		(pad "B13" smd rect
			(at -2.49987 2.7239)
			(size 0.7112 4.191)
			(layers "F.Cu" "F.Mask" "F.Paste")
			(net "GND")
		)
		(pad "B14" smd rect
			(at -1.49987 2.7239)
			(size 0.7112 4.191)
			(layers "F.Cu" "F.Mask" "F.Paste")
			(net "PCIE_RX0_P")
		)
		(pad "B15" smd rect
			(at -0.49988 2.7239)
			(size 0.7112 4.191)
			(layers "F.Cu" "F.Mask" "F.Paste")
			(net "PCIE_RX0_N")
		)
		(pad "B16" smd rect
			(at 0.50012 2.7239)
			(size 0.7112 4.191)
			(layers "F.Cu" "F.Mask" "F.Paste")
			(net "GND")
		)
		(pad "B17" smd rect
			(at 1.50012 2.7239)
			(size 0.7112 4.191)
			(layers "F.Cu" "F.Mask" "F.Paste")
			(net "NetP2_B17")
		)
		(pad "B18" smd rect
			(at 2.50012 2.7239)
			(size 0.7112 4.191)
			(layers "F.Cu" "F.Mask" "F.Paste")
			(net "GND")
		)
		(pad "B19" smd rect
			(at 3.50012 2.7239)
			(size 0.7112 4.191)
			(layers "F.Cu" "F.Mask" "F.Paste")
			(net "PCIE_RX1_P")
		)
		(pad "B20" smd rect
			(at 4.50011 2.7239)
			(size 0.7112 4.191)
			(layers "F.Cu" "F.Mask" "F.Paste")
			(net "PCIE_RX1_N")
		)
		(pad "B21" smd rect
			(at 5.50011 2.7239)
			(size 0.7112 4.191)
			(layers "F.Cu" "F.Mask" "F.Paste")
			(net "GND")
		)
		(pad "B22" smd rect
			(at 6.50011 2.7239)
			(size 0.7112 4.191)
			(layers "F.Cu" "F.Mask" "F.Paste")
			(net "GND")
		)
		(pad "B23" smd rect
			(at 7.50011 2.7239)
			(size 0.7112 4.191)
			(layers "F.Cu" "F.Mask" "F.Paste")
			(net "PCIE_RX2_P")
		)
		(pad "B24" smd rect
			(at 8.50011 2.7239)
			(size 0.7112 4.191)
			(layers "F.Cu" "F.Mask" "F.Paste")
			(net "PCIE_RX2_N")
		)
		(pad "B25" smd rect
			(at 9.5001 2.7239)
			(size 0.7112 4.191)
			(layers "F.Cu" "F.Mask" "F.Paste")
			(net "GND")
		)
		(pad "B26" smd rect
			(at 10.5001 2.7239)
			(size 0.7112 4.191)
			(layers "F.Cu" "F.Mask" "F.Paste")
			(net "GND")
		)
		(pad "B27" smd rect
			(at 11.5001 2.7239)
			(size 0.7112 4.191)
			(layers "F.Cu" "F.Mask" "F.Paste")
			(net "PCIE_RX3_P")
		)
		(pad "B28" smd rect
			(at 12.5001 2.7239)
			(size 0.7112 4.191)
			(layers "F.Cu" "F.Mask" "F.Paste")
			(net "PCIE_RX3_N")
		)
		(pad "B29" smd rect
			(at 13.5001 2.7239)
			(size 0.7112 4.191)
			(layers "F.Cu" "F.Mask" "F.Paste")
			(net "GND")
		)
		(pad "B30" smd rect
			(at 14.50009 2.7239)
			(size 0.7112 4.191)
			(layers "F.Cu" "F.Mask" "F.Paste")
		)
		(pad "B31" smd rect
			(at 15.50009 2.2286)
			(size 0.7112 3.2004)
			(layers "F.Cu" "F.Mask" "F.Paste")
			(net "NetP2_B31")
		)
		(pad "B32" smd rect
			(at 16.50009 2.7239)
			(size 0.7112 4.191)
			(layers "F.Cu" "F.Mask" "F.Paste")
			(net "GND")
		)
	)
	(footprint "Passives:DIOM1608X06N"
		(layer "F.Cu")
		(at 85.112255 53.2366 90)
		(property "Reference" "D13"
			(at -1.55529 -1.375795 90)
			(unlocked yes)
			(layer "F.SilkS")
			(effects
				(font
					(size 0.762 0.762)
					(thickness 0.2286)
				)
				(justify left bottom)
			)
		)
		(property "Value" "RED"
			(at -4.13639 -0.5715 0)
			(unlocked yes)
			(layer "F.SilkS")
			(hide yes)
			(effects
				(font
					(size 1.524 1.524)
					(thickness 0.254)
				)
				(justify left bottom)
			)
		)
		(sheetname "USER_IO")
		(sheetfile "USER_IO.kicad_sch")
		(duplicate_pad_numbers_are_jumpers no)
		(fp_circle
			(center -1.275 -0.725)
			(end -1.225 -0.725)
			(stroke
				(width 0.1)
				(type solid)
			)
			(fill no)
			(layer "F.SilkS")
		)
		(pad "1" smd rect
			(at -0.725 0 180)
			(size 0.85 1)
			(layers "F.Cu" "F.Mask" "F.Paste")
			(net "NetD13_1")
		)
		(pad "2" smd rect
			(at 0.725 0 180)
			(size 0.85 1)
			(layers "F.Cu" "F.Mask" "F.Paste")
			(net "+3.3V")
		)
	)
	(footprint "Resistors:RESC1608X50N"
		(layer "F.Cu")
		(at 176.988595 53.7786)
		(property "Reference" "R33"
			(at 1.7 0.393345 0)
			(unlocked yes)
			(layer "F.SilkS")
			(effects
				(font
					(size 0.762 0.762)
					(thickness 0.2286)
				)
				(justify left bottom)
			)
		)
		(property "Value" "ERJ-3EKF1002V"
			(at -0.4445 3.72999 0)
			(unlocked yes)
			(layer "F.SilkS")
			(hide yes)
			(effects
				(font
					(size 1.524 1.524)
					(thickness 0.254)
				)
				(justify left bottom)
			)
		)
		(sheetname "USER_IO")
		(sheetfile "USER_IO.kicad_sch")
		(duplicate_pad_numbers_are_jumpers no)
		(fp_line
			(start 0 0.5)
			(end 0 -0.5)
			(stroke
				(width 0.1524)
				(type solid)
			)
			(layer "F.SilkS")
		)
		(pad "1" smd rect
			(at -0.69 0 90)
			(size 1 0.72)
			(layers "F.Cu" "F.Mask" "F.Paste")
			(net "NetR33_1")
		)
		(pad "2" smd rect
			(at 0.69 0 90)
			(size 1 0.72)
			(layers "F.Cu" "F.Mask" "F.Paste")
			(net "+3.3V")
		)
	)
	(footprint "Capacitors:CAPC2012X14N"
		(layer "F.Cu")
		(at 161.735595 89.0506 90)
		(property "Reference" "C75"
			(at 2.332545 -2.10771 0)
			(unlocked yes)
			(layer "F.SilkS")
			(effects
				(font
					(size 0.762 0.762)
					(thickness 0.2286)
				)
				(justify left bottom)
			)
		)
		(property "Value" "CAP_0805_22UF_16V"
			(at -3.52679 -1.5875 0)
			(unlocked yes)
			(layer "F.SilkS")
			(hide yes)
			(effects
				(font
					(size 1.524 1.524)
					(thickness 0.254)
				)
				(justify left bottom)
			)
		)
		(sheetname "MAC")
		(sheetfile "MAC.kicad_sch")
		(duplicate_pad_numbers_are_jumpers no)
		(fp_line
			(start -0.762 -0.9652)
			(end 0.762 -0.9652)
			(stroke
				(width 0.1524)
				(type solid)
			)
			(layer "F.SilkS")
		)
		(fp_line
			(start -0.762 0.9652)
			(end 0.762 0.9652)
			(stroke
				(width 0.1524)
				(type solid)
			)
			(layer "F.SilkS")
		)
		(pad "1" smd rect
			(at -0.9 0 180)
			(size 1.45 1.15)
			(layers "F.Cu" "F.Mask" "F.Paste")
			(net "GND")
		)
		(pad "2" smd rect
			(at 0.9 0 180)
			(size 1.45 1.15)
			(layers "F.Cu" "F.Mask" "F.Paste")
			(net "+3.3V_CLEAN")
		)
	)
	(footprint "Miscellaneous Devices:J1-0603"
		(layer "F.Cu")
		(at 82.288595 142.2786 180)
		(property "Reference" "R32"
			(at -1.6 -0.393345 0)
			(unlocked yes)
			(layer "F.SilkS")
			(effects
				(font
					(size 0.762 0.762)
					(thickness 0.2286)
				)
				(justify left bottom)
			)
		)
		(property "Value" "GPS1"
			(at 0.4445 -3.72999 0)
			(unlocked yes)
			(layer "F.SilkS")
			(hide yes)
			(effects
				(font
					(size 1.524 1.524)
					(thickness 0.254)
				)
				(justify left bottom)
			)
		)
		(sheetname "USER_IO")
		(sheetfile "USER_IO.kicad_sch")
		(duplicate_pad_numbers_are_jumpers no)
		(fp_line
			(start 0.2 0.35)
			(end -0.2 0.35)
			(stroke
				(width 0.2)
				(type solid)
			)
			(layer "F.SilkS")
		)
		(fp_line
			(start 0.2 -0.35)
			(end -0.2 -0.35)
			(stroke
				(width 0.2)
				(type solid)
			)
			(layer "F.SilkS")
		)
		(pad "1" smd rect
			(at -0.75 0 270)
			(size 0.9 0.7)
			(layers "F.Cu" "F.Mask" "F.Paste")
			(net "GPS1_TP1")
		)
		(pad "2" smd rect
			(at 0.75 0 270)
			(size 0.9 0.7)
			(layers "F.Cu" "F.Mask" "F.Paste")
			(net "ANT4")
		)
	)
	(footprint "Passives:IND_PM124SH"
		(layer "F.Cu")
		(at 219.012595 118.6416 90)
		(property "Reference" "L1"
			(at 5.456745 -8.78815 0)
			(unlocked yes)
			(layer "F.SilkS")
			(effects
				(font
					(size 0.762 0.762)
					(thickness 0.2286)
				)
				(justify left bottom)
			)
		)
		(property "Value" "PM124SH-100M-RC"
			(at -10.00379 -10.8331 0)
			(unlocked yes)
			(layer "F.SilkS")
			(hide yes)
			(effects
				(font
					(size 1.524 1.524)
					(thickness 0.254)
				)
				(justify left bottom)
			)
		)
		(sheetname "POWER")
		(sheetfile "POWER.kicad_sch")
		(duplicate_pad_numbers_are_jumpers no)
		(fp_line
			(start 6.681 -6.4)
			(end 6.681 6.4)
			(stroke
				(width 0.254)
				(type solid)
			)
			(layer "F.SilkS")
		)
		(fp_line
			(start -6.681 -6.4)
			(end 6.681 -6.4)
			(stroke
				(width 0.254)
				(type solid)
			)
			(layer "F.SilkS")
		)
		(fp_line
			(start -6.681 -6.4)
			(end -6.681 6.4)
			(stroke
				(width 0.254)
				(type solid)
			)
			(layer "F.SilkS")
		)
		(fp_line
			(start -6.681 6.4)
			(end 6.681 6.4)
			(stroke
				(width 0.254)
				(type solid)
			)
			(layer "F.SilkS")
		)
		(pad "1" smd rect
			(at -4.85 0 90)
			(size 2.9 5.4)
			(layers "F.Cu" "F.Mask" "F.Paste")
			(net "+5.0V")
		)
		(pad "2" smd rect
			(at 4.85 0 90)
			(size 2.9 5.4)
			(layers "F.Cu" "F.Mask" "F.Paste")
			(net "NetC4_2")
		)
	)
	(footprint "Vault:RESC1608X55X30NL15T15"
		(layer "F.Cu")
		(at 79.988595 56.9786 90)
		(property "Reference" "R28"
			(at -1.2 -1.206655 90)
			(unlocked yes)
			(layer "F.SilkS")
			(effects
				(font
					(size 0.762 0.762)
					(thickness 0.2286)
				)
				(justify left bottom)
			)
		)
		(property "Value" "200 OHM"
			(at -3.72999 -0.4445 0)
			(unlocked yes)
			(layer "F.SilkS")
			(hide yes)
			(effects
				(font
					(size 1.524 1.524)
					(thickness 0.254)
				)
				(justify left bottom)
			)
		)
		(sheetname "USER_IO")
		(sheetfile "USER_IO.kicad_sch")
		(duplicate_pad_numbers_are_jumpers no)
		(pad "1" smd rect
			(at -0.675 0 180)
			(size 0.95 0.8)
			(layers "F.Cu" "F.Mask" "F.Paste")
			(net "LED2")
		)
		(pad "2" smd rect
			(at 0.675 0 180)
			(size 0.95 0.8)
			(layers "F.Cu" "F.Mask" "F.Paste")
			(net "NetD12_1")
		)
	)
	(footprint "Connectors:3PINV-100"
		(layer "F.Cu")
		(at 95.513595 52.5286 -90)
		(property "Reference" "JP1"
			(at -0.981655 3.35 0)
			(unlocked yes)
			(layer "F.SilkS")
			(effects
				(font
					(size 0.762 0.762)
					(thickness 0.2286)
				)
				(justify left bottom)
			)
		)
		(property "Value" "JUMPER_3PIN"
			(at 9.49579 1.7145 0)
			(unlocked yes)
			(layer "F.SilkS")
			(hide yes)
			(effects
				(font
					(size 1.524 1.524)
					(thickness 0.254)
				)
				(justify left bottom)
			)
		)
		(sheetname "GPS_IMU_SENSORS")
		(sheetfile "GPS_IMU_SENSORS.kicad_sch")
		(duplicate_pad_numbers_are_jumpers no)
		(fp_line
			(start -1.27 1.27)
			(end -1.27 -1.27)
			(stroke
				(width 0.1524)
				(type solid)
			)
			(layer "F.SilkS")
		)
		(fp_line
			(start 6.35 1.27)
			(end -1.27 1.27)
			(stroke
				(width 0.1524)
				(type solid)
			)
			(layer "F.SilkS")
		)
		(fp_line
			(start 6.35 1.27)
			(end 6.35 -1.27)
			(stroke
				(width 0.1524)
				(type solid)
			)
			(layer "F.SilkS")
		)
		(fp_line
			(start 6.35 -1.27)
			(end -1.27 -1.27)
			(stroke
				(width 0.1524)
				(type solid)
			)
			(layer "F.SilkS")
		)
		(pad "1" thru_hole rect
			(at 0 0 270)
			(size 1.397 1.397)
			(drill 0.762)
			(layers "*.Cu" "*.Mask")
			(remove_unused_layers no)
			(net "GPS1_TX")
		)
		(pad "2" thru_hole circle
			(at 2.54 0 270)
			(size 1.397 1.397)
			(drill 0.762)
			(layers "*.Cu" "*.Mask")
			(remove_unused_layers no)
			(net "NetJP1_2")
			(thermal_bridge_angle 90)
		)
		(pad "3" thru_hole circle
			(at 5.08 0 270)
			(size 1.397 1.397)
			(drill 0.762)
			(layers "*.Cu" "*.Mask")
			(remove_unused_layers no)
			(net "NetJP1_3")
			(thermal_bridge_angle 90)
		)
	)
	(footprint "Capacitors:CAPC2012X14N"
		(layer "F.Cu")
		(at 152.337595 142.1366 180)
		(property "Reference" "C62"
			(at 4.849 -0.335345 0)
			(unlocked yes)
			(layer "F.SilkS")
			(effects
				(font
					(size 0.762 0.762)
					(thickness 0.2286)
				)
				(justify left bottom)
			)
		)
		(property "Value" "CAP_0805_10UF_25V"
			(at 1.5875 -3.52679 0)
			(unlocked yes)
			(layer "F.SilkS")
			(hide yes)
			(effects
				(font
					(size 1.524 1.524)
					(thickness 0.254)
				)
				(justify left bottom)
			)
		)
		(sheetname "MAC")
		(sheetfile "MAC.kicad_sch")
		(duplicate_pad_numbers_are_jumpers no)
		(fp_line
			(start 0.762 0.9652)
			(end -0.762 0.9652)
			(stroke
				(width 0.1524)
				(type solid)
			)
			(layer "F.SilkS")
		)
		(fp_line
			(start 0.762 -0.9652)
			(end -0.762 -0.9652)
			(stroke
				(width 0.1524)
				(type solid)
			)
			(layer "F.SilkS")
		)
		(pad "1" smd rect
			(at -0.9 0 270)
			(size 1.45 1.15)
			(layers "F.Cu" "F.Mask" "F.Paste")
			(net "+5.0V")
		)
		(pad "2" smd rect
			(at 0.9 0 270)
			(size 1.45 1.15)
			(layers "F.Cu" "F.Mask" "F.Paste")
			(net "GND")
		)
	)
	(footprint "Miscellaneous Devices:J1-0603"
		(layer "F.Cu")
		(at 113.138595 57.8286 -90)
		(property "Reference" "R12"
			(at 0.2786 -6.123079 270)
			(unlocked yes)
			(layer "F.SilkS")
			(effects
				(font
					(size 0.762 0.762)
					(thickness 0.2286)
				)
			)
		)
		(property "Value" "GPS2RX"
			(at 4.335402 -4.227705 0)
			(unlocked yes)
			(layer "F.SilkS")
			(hide yes)
			(effects
				(font
					(size 1.524 1.524)
					(thickness 0.254)
				)
			)
		)
		(sheetname "GPS_IMU_SENSORS")
		(sheetfile "GPS_IMU_SENSORS.kicad_sch")
		(duplicate_pad_numbers_are_jumpers no)
		(fp_line
			(start 0.2 0.35)
			(end -0.2 0.35)
			(stroke
				(width 0.2)
				(type solid)
			)
			(layer "F.SilkS")
		)
		(fp_line
			(start 0.2 -0.35)
			(end -0.2 -0.35)
			(stroke
				(width 0.2)
				(type solid)
			)
			(layer "F.SilkS")
		)
		(pad "1" smd rect
			(at -0.75 0)
			(size 0.9 0.7)
			(layers "F.Cu" "F.Mask" "F.Paste")
			(net "GPS2_RX")
		)
		(pad "2" smd rect
			(at 0.75 0)
			(size 0.9 0.7)
			(layers "F.Cu" "F.Mask" "F.Paste")
			(net "NetJP2_3")
		)
	)
	(footprint "Vault:CAPC1608X87X45ML20T05"
		(layer "F.Cu")
		(at 167.069595 82.8276 -90)
		(property "Reference" "C80"
			(at -3.799 -2.362345 90)
			(unlocked yes)
			(layer "F.SilkS")
			(effects
				(font
					(size 0.762 0.762)
					(thickness 0.2286)
				)
				(justify left bottom)
			)
		)
		(property "Value" "0.1uF"
			(at 3.47599 0.2921 0)
			(unlocked yes)
			(layer "F.SilkS")
			(hide yes)
			(effects
				(font
					(size 1.524 1.524)
					(thickness 0.254)
				)
				(justify left bottom)
			)
		)
		(sheetname "MAC")
		(sheetfile "MAC.kicad_sch")
		(duplicate_pad_numbers_are_jumpers no)
		(pad "1" smd rect
			(at -0.7 0)
			(size 1.1 1.05)
			(layers "F.Cu" "F.Mask" "F.Paste")
			(net "GND")
		)
		(pad "2" smd rect
			(at 0.7 0)
			(size 1.1 1.05)
			(layers "F.Cu" "F.Mask" "F.Paste")
			(net "+3.3V_CLEAN")
		)
	)
	(footprint "Connectors:SAMTEC_HTST-105-01-L-DV-A"
		(layer "F.Cu")
		(at 138.367595 56.7916)
		(property "Reference" "U5"
			(at -13.09339 -3.347545 0)
			(unlocked yes)
			(layer "F.SilkS")
			(effects
				(font
					(size 0.762 0.762)
					(thickness 0.2286)
				)
				(justify left bottom)
			)
		)
		(property "Value" "HTST-105-01-L-DV-A"
			(at -4.3317 21.99359 0)
			(unlocked yes)
			(layer "F.SilkS")
			(hide yes)
			(effects
				(font
					(size 1.524 1.524)
					(thickness 0.254)
				)
				(justify left bottom)
			)
		)
		(sheetname "PCIe_JTAG")
		(sheetfile "PCIe_JTAG.kicad_sch")
		(duplicate_pad_numbers_are_jumpers no)
		(fp_line
			(start -10.16 -4.635)
			(end -6.065 -4.635)
			(stroke
				(width 0.2)
				(type solid)
			)
			(layer "F.SilkS")
		)
		(fp_line
			(start -10.16 4.635)
			(end -10.16 -4.635)
			(stroke
				(width 0.2)
				(type solid)
			)
			(layer "F.SilkS")
		)
		(fp_line
			(start -10.16 4.635)
			(end -6.065 4.635)
			(stroke
				(width 0.2)
				(type solid)
			)
			(layer "F.SilkS")
		)
		(fp_line
			(start 6.065 -4.635)
			(end 10.16 -4.635)
			(stroke
				(width 0.2)
				(type solid)
			)
			(layer "F.SilkS")
		)
		(fp_line
			(start 6.065 4.635)
			(end 10.16 4.635)
			(stroke
				(width 0.2)
				(type solid)
			)
			(layer "F.SilkS")
		)
		(fp_line
			(start 10.16 4.635)
			(end 10.16 -4.635)
			(stroke
				(width 0.2)
				(type solid)
			)
			(layer "F.SilkS")
		)
		(fp_circle
			(center -7.62 5.715)
			(end -7.62 5.08)
			(stroke
				(width 0.2)
				(type solid)
			)
			(fill no)
			(layer "F.SilkS")
		)
		(pad "" np_thru_hole circle
			(at -3.81 0)
			(size 1.676 1.676)
			(drill 1.676)
			(layers "*.Cu" "*.Mask")
			(thermal_bridge_angle 90)
		)
		(pad "" np_thru_hole circle
			(at 3.81 0)
			(size 1.676 1.676)
			(drill 1.676)
			(layers "*.Cu" "*.Mask")
			(thermal_bridge_angle 90)
		)
		(pad "1" smd rect
			(at -5.08 3.43)
			(size 1.27 5.08)
			(layers "F.Cu" "F.Mask" "F.Paste")
			(net "NetR18_2")
		)
		(pad "2" smd rect
			(at -5.08 -3.43)
			(size 1.27 5.08)
			(layers "F.Cu" "F.Mask" "F.Paste")
			(net "GND")
		)
		(pad "3" smd rect
			(at -2.54 3.43)
			(size 1.27 5.08)
			(layers "F.Cu" "F.Mask" "F.Paste")
			(net "NetR19_2")
		)
		(pad "4" smd rect
			(at -2.54 -3.43)
			(size 1.27 5.08)
			(layers "F.Cu" "F.Mask" "F.Paste")
			(net "+3.3V")
		)
		(pad "5" smd rect
			(at 0 3.43)
			(size 1.27 5.08)
			(layers "F.Cu" "F.Mask" "F.Paste")
			(net "NetR20_2")
		)
		(pad "6" smd rect
			(at 0 -3.43)
			(size 1.27 5.08)
			(layers "F.Cu" "F.Mask" "F.Paste")
			(net "+3.3V")
		)
		(pad "7" smd rect
			(at 2.54 3.43)
			(size 1.27 5.08)
			(layers "F.Cu" "F.Mask" "F.Paste")
		)
		(pad "8" smd rect
			(at 2.54 -3.43)
			(size 1.27 5.08)
			(layers "F.Cu" "F.Mask" "F.Paste")
		)
		(pad "9" smd rect
			(at 5.08 3.43)
			(size 1.27 5.08)
			(layers "F.Cu" "F.Mask" "F.Paste")
			(net "NetR21_2")
		)
		(pad "10" smd rect
			(at 5.08 -3.43)
			(size 1.27 5.08)
			(layers "F.Cu" "F.Mask" "F.Paste")
			(net "GND")
		)
	)
	(footprint "Capacitors:CAPC1608X10N"
		(layer "F.Cu")
		(at 165.037595 63.9046 -90)
		(property "Reference" "C55"
			(at -2.926 -0.844345 90)
			(unlocked yes)
			(layer "F.SilkS")
			(effects
				(font
					(size 0.762 0.762)
					(thickness 0.2286)
				)
				(justify left bottom)
			)
		)
		(property "Value" "GRT188R61E106ME13D"
			(at 4.08559 0.5461 0)
			(unlocked yes)
			(layer "F.SilkS")
			(hide yes)
			(effects
				(font
					(size 1.524 1.524)
					(thickness 0.254)
				)
				(justify left bottom)
			)
		)
		(sheetname "UART")
		(sheetfile "UART.kicad_sch")
		(duplicate_pad_numbers_are_jumpers no)
		(fp_line
			(start 0.635 0.7112)
			(end -0.635 0.7112)
			(stroke
				(width 0.1524)
				(type solid)
			)
			(layer "F.SilkS")
		)
		(fp_line
			(start 0.635 -0.7112)
			(end -0.635 -0.7112)
			(stroke
				(width 0.1524)
				(type solid)
			)
			(layer "F.SilkS")
		)
		(pad "1" smd rect
			(at -0.8 0)
			(size 0.95 1)
			(layers "F.Cu" "F.Mask" "F.Paste")
			(net "GND")
		)
		(pad "2" smd rect
			(at 0.8 0)
			(size 0.95 1)
			(layers "F.Cu" "F.Mask" "F.Paste")
			(net "NetC54_2")
		)
	)
	(footprint "Capacitors:CAPC2012X14N"
		(layer "F.Cu")
		(at 227.775595 121.6896 180)
		(property "Reference" "C14"
			(at -1.97531 -1.604455 0)
			(unlocked yes)
			(layer "F.SilkS")
			(effects
				(font
					(size 0.762 0.762)
					(thickness 0.2286)
				)
				(justify left bottom)
			)
		)
		(property "Value" "CAP_0805_10UF_25V"
			(at 4.6355 -3.78079 0)
			(unlocked yes)
			(layer "F.SilkS")
			(hide yes)
			(effects
				(font
					(size 1.524 1.524)
					(thickness 0.254)
				)
				(justify left bottom)
			)
		)
		(sheetname "POWER")
		(sheetfile "POWER.kicad_sch")
		(duplicate_pad_numbers_are_jumpers no)
		(fp_line
			(start 0.762 0.9652)
			(end -0.762 0.9652)
			(stroke
				(width 0.1524)
				(type solid)
			)
			(layer "F.SilkS")
		)
		(fp_line
			(start 0.762 -0.9652)
			(end -0.762 -0.9652)
			(stroke
				(width 0.1524)
				(type solid)
			)
			(layer "F.SilkS")
		)
		(pad "1" smd rect
			(at -0.9 0 270)
			(size 1.45 1.15)
			(layers "F.Cu" "F.Mask" "F.Paste")
			(net "+5.0V")
		)
		(pad "2" smd rect
			(at 0.9 0 270)
			(size 1.45 1.15)
			(layers "F.Cu" "F.Mask" "F.Paste")
			(net "GND")
		)
	)
	(footprint "Capacitors:CAPC1608X10N"
		(layer "F.Cu")
		(at 224.092595 110.1326 -90)
		(property "Reference" "C4"
			(at -2.029 -0.364345 90)
			(unlocked yes)
			(layer "F.SilkS")
			(effects
				(font
					(size 0.762 0.762)
					(thickness 0.2286)
				)
				(justify left bottom)
			)
		)
		(property "Value" "CAP_0603_0.01UF_50V"
			(at 3.14579 4.7879 0)
			(unlocked yes)
			(layer "F.SilkS")
			(hide yes)
			(effects
				(font
					(size 1.524 1.524)
					(thickness 0.254)
				)
				(justify left bottom)
			)
		)
		(sheetname "POWER")
		(sheetfile "POWER.kicad_sch")
		(duplicate_pad_numbers_are_jumpers no)
		(fp_line
			(start 0.635 0.7112)
			(end -0.635 0.7112)
			(stroke
				(width 0.1524)
				(type solid)
			)
			(layer "F.SilkS")
		)
		(fp_line
			(start 0.635 -0.7112)
			(end -0.635 -0.7112)
			(stroke
				(width 0.1524)
				(type solid)
			)
			(layer "F.SilkS")
		)
		(pad "1" smd rect
			(at -0.8 0)
			(size 0.95 1)
			(layers "F.Cu" "F.Mask" "F.Paste")
			(net "NetC4_1")
		)
		(pad "2" smd rect
			(at 0.8 0)
			(size 0.95 1)
			(layers "F.Cu" "F.Mask" "F.Paste")
			(net "NetC4_2")
		)
	)
	(footprint "Resistors:RESC1608X50N"
		(layer "F.Cu")
		(at 216.853595 105.8146 -90)
		(property "Reference" "R3"
			(at 2.864 -0.428345 90)
			(unlocked yes)
			(layer "F.SilkS")
			(effects
				(font
					(size 0.762 0.762)
					(thickness 0.2286)
				)
				(justify left bottom)
			)
		)
		(property "Value" "ERJ-3EKF4702V"
			(at -18.92681 -16.2687 0)
			(unlocked yes)
			(layer "F.SilkS")
			(hide yes)
			(effects
				(font
					(size 1.524 1.524)
					(thickness 0.254)
				)
				(justify left bottom)
			)
		)
		(sheetname "POWER")
		(sheetfile "POWER.kicad_sch")
		(duplicate_pad_numbers_are_jumpers no)
		(fp_line
			(start 0 0.5)
			(end 0 -0.5)
			(stroke
				(width 0.1524)
				(type solid)
			)
			(layer "F.SilkS")
		)
		(pad "1" smd rect
			(at -0.69 0)
			(size 1 0.72)
			(layers "F.Cu" "F.Mask" "F.Paste")
			(net "NetR3_1")
		)
		(pad "2" smd rect
			(at 0.69 0)
			(size 1 0.72)
			(layers "F.Cu" "F.Mask" "F.Paste")
			(net "+12V")
		)
	)
	(footprint "Vault:TECO-1909763-1_V"
		(layer "F.Cu")
		(at 75.088595 137.5786 90)
		(property "Reference" "J10"
			(at -3.026921 2.4286 0)
			(unlocked yes)
			(layer "F.SilkS")
			(effects
				(font
					(size 0.762 0.762)
					(thickness 0.2286)
				)
			)
		)
		(property "Value" "1909763-1"
			(at 4.608085 3.749802 90)
			(unlocked yes)
			(layer "F.SilkS")
			(hide yes)
			(effects
				(font
					(size 1.524 1.524)
					(thickness 0.254)
				)
			)
		)
		(sheetname "USER_IO")
		(sheetfile "USER_IO.kicad_sch")
		(duplicate_pad_numbers_are_jumpers no)
		(fp_line
			(start -0.55 -1.3)
			(end 0.55 -1.3)
			(stroke
				(width 0.2)
				(type solid)
			)
			(layer "F.SilkS")
		)
		(fp_circle
			(center -1.778 1.65)
			(end -1.653 1.65)
			(stroke
				(width 0.25)
				(type solid)
			)
			(fill no)
			(layer "F.SilkS")
		)
		(pad "1" smd rect
			(at -1.475 0 90)
			(size 1.05 2.2)
			(layers "F.Cu" "F.Mask" "F.Paste")
			(net "GND")
		)
		(pad "2" smd rect
			(at 0 1.525 90)
			(size 1 1.05)
			(layers "F.Cu" "F.Mask" "F.Paste")
			(net "ANT4")
		)
		(pad "3" smd rect
			(at 1.475 0 90)
			(size 1.05 2.2)
			(layers "F.Cu" "F.Mask" "F.Paste")
			(net "GND")
		)
	)
	(footprint "Modules:LGA-28"
		(layer "F.Cu")
		(at 222.314595 78.2556 -90)
		(property "Reference" "U8"
			(at -3.564255 2.0574 0)
			(unlocked yes)
			(layer "F.SilkS")
			(effects
				(font
					(size 0.762 0.762)
					(thickness 0.2286)
				)
				(justify left bottom)
			)
		)
		(property "Value" "BNO080"
			(at 5.76199 -16.1163 0)
			(unlocked yes)
			(layer "F.SilkS")
			(hide yes)
			(effects
				(font
					(size 1.524 1.524)
					(thickness 0.254)
				)
				(justify left bottom)
			)
		)
		(sheetname "GPS_IMU_SENSORS")
		(sheetfile "GPS_IMU_SENSORS.kicad_sch")
		(duplicate_pad_numbers_are_jumpers no)
		(fp_line
			(start -2.794 2.159)
			(end -2.794 -2.154)
			(stroke
				(width 0.254)
				(type solid)
			)
			(layer "F.SilkS")
		)
		(fp_line
			(start 2.794 2.159)
			(end -2.794 2.159)
			(stroke
				(width 0.254)
				(type solid)
			)
			(layer "F.SilkS")
		)
		(fp_line
			(start 2.794 2.159)
			(end 2.794 -2.154)
			(stroke
				(width 0.254)
				(type solid)
			)
			(layer "F.SilkS")
		)
		(fp_line
			(start 2.794 -2.154)
			(end -2.794 -2.154)
			(stroke
				(width 0.254)
				(type solid)
			)
			(layer "F.SilkS")
		)
		(fp_rect
			(start 2.159 -2.413)
			(end 2.413 -3.048)
			(stroke
				(width 0)
				(type default)
			)
			(fill yes)
			(layer "F.SilkS")
		)
		(pad "1" smd rect
			(at 2.25 -1.5625 90)
			(size 0.25 0.675)
			(layers "F.Cu" "F.Mask" "F.Paste")
		)
		(pad "2" smd rect
			(at 2.3125 -0.75 270)
			(size 0.575 0.25)
			(layers "F.Cu" "F.Mask" "F.Paste")
			(net "GND")
		)
		(pad "3" smd rect
			(at 2.3125 -0.254 270)
			(size 0.575 0.25)
			(layers "F.Cu" "F.Mask" "F.Paste")
			(net "+3.3V")
		)
		(pad "4" smd rect
			(at 2.3125 0.25 270)
			(size 0.575 0.25)
			(layers "F.Cu" "F.Mask" "F.Paste")
			(net "IMU_BOOT")
		)
		(pad "5" smd rect
			(at 2.3125 0.75 270)
			(size 0.575 0.25)
			(layers "F.Cu" "F.Mask" "F.Paste")
			(net "IMU_PS1")
		)
		(pad "6" smd rect
			(at 2.25 1.5625 90)
			(size 0.25 0.675)
			(layers "F.Cu" "F.Mask" "F.Paste")
			(net "IMU_PS0")
		)
		(pad "7" smd rect
			(at 1.75 1.5625 90)
			(size 0.25 0.675)
			(layers "F.Cu" "F.Mask" "F.Paste")
		)
		(pad "8" smd rect
			(at 1.25 1.5625 90)
			(size 0.25 0.675)
			(layers "F.Cu" "F.Mask" "F.Paste")
		)
		(pad "9" smd rect
			(at 0.75 1.5625 90)
			(size 0.25 0.675)
			(layers "F.Cu" "F.Mask" "F.Paste")
		)
		(pad "10" smd rect
			(at 0.25 1.5625 90)
			(size 0.25 0.675)
			(layers "F.Cu" "F.Mask" "F.Paste")
			(net "IMU_CLKSEL0")
		)
		(pad "11" smd rect
			(at -0.25 1.5625 90)
			(size 0.25 0.675)
			(layers "F.Cu" "F.Mask" "F.Paste")
			(net "IMU_NRST")
		)
		(pad "12" smd rect
			(at -0.75 1.5625 90)
			(size 0.25 0.675)
			(layers "F.Cu" "F.Mask" "F.Paste")
		)
		(pad "13" smd rect
			(at -1.25 1.5625 90)
			(size 0.25 0.675)
			(layers "F.Cu" "F.Mask" "F.Paste")
		)
		(pad "14" smd rect
			(at -1.75 1.5625 90)
			(size 0.25 0.675)
			(layers "F.Cu" "F.Mask" "F.Paste")
			(net "IMU_INT")
		)
		(pad "15" smd rect
			(at -2.25 1.5625 90)
			(size 0.25 0.675)
			(layers "F.Cu" "F.Mask" "F.Paste")
			(net "IMU_ENV_SCL")
		)
		(pad "16" smd rect
			(at -2.3125 0.75 90)
			(size 0.575 0.25)
			(layers "F.Cu" "F.Mask" "F.Paste")
			(net "IMU_ENV_SDA")
		)
		(pad "17" smd rect
			(at -2.3125 0.25 90)
			(size 0.575 0.25)
			(layers "F.Cu" "F.Mask" "F.Paste")
			(net "MOSI")
		)
		(pad "18" smd rect
			(at -2.3125 -0.25 90)
			(size 0.575 0.25)
			(layers "F.Cu" "F.Mask" "F.Paste")
			(net "CSN")
		)
		(pad "19" smd rect
			(at -2.3125 -0.75 90)
			(size 0.575 0.25)
			(layers "F.Cu" "F.Mask" "F.Paste")
			(net "SCK")
		)
		(pad "20" smd rect
			(at -2.25 -1.5625 90)
			(size 0.25 0.675)
			(layers "F.Cu" "F.Mask" "F.Paste")
			(net "MISO")
		)
		(pad "21" smd rect
			(at -1.75 -1.5625 90)
			(size 0.25 0.675)
			(layers "F.Cu" "F.Mask" "F.Paste")
		)
		(pad "22" smd rect
			(at -1.25 -1.5625 90)
			(size 0.25 0.675)
			(layers "F.Cu" "F.Mask" "F.Paste")
		)
		(pad "23" smd rect
			(at -0.75 -1.5625 90)
			(size 0.25 0.675)
			(layers "F.Cu" "F.Mask" "F.Paste")
		)
		(pad "24" smd rect
			(at -0.25 -1.5625 90)
			(size 0.25 0.675)
			(layers "F.Cu" "F.Mask" "F.Paste")
		)
		(pad "25" smd rect
			(at 0.25 -1.5625 90)
			(size 0.25 0.675)
			(layers "F.Cu" "F.Mask" "F.Paste")
			(net "GND")
		)
		(pad "26" smd rect
			(at 0.75 -1.5625 90)
			(size 0.25 0.675)
			(layers "F.Cu" "F.Mask" "F.Paste")
			(net "NetC86_2")
		)
		(pad "27" smd rect
			(at 1.25 -1.5625 90)
			(size 0.25 0.675)
			(layers "F.Cu" "F.Mask" "F.Paste")
			(net "NetC85_2")
		)
		(pad "28" smd rect
			(at 1.75 -1.5625 90)
			(size 0.25 0.675)
			(layers "F.Cu" "F.Mask" "F.Paste")
			(net "+3.3V")
		)
	)
	(footprint "Passives:DIOM6959X26N"
		(layer "F.Cu")
		(at 85.027595 110.8946 180)
		(property "Reference" "D15"
			(at 4.1402 4.097655 0)
			(unlocked yes)
			(layer "F.SilkS")
			(effects
				(font
					(size 0.762 0.762)
					(thickness 0.2286)
				)
				(justify left bottom)
			)
		)
		(property "Value" "SMCJ6.5CA"
			(at 4.2545 -5.91439 0)
			(unlocked yes)
			(layer "F.SilkS")
			(hide yes)
			(effects
				(font
					(size 1.524 1.524)
					(thickness 0.254)
				)
				(justify left bottom)
			)
		)
		(sheetname "USER_IO")
		(sheetfile "USER_IO.kicad_sch")
		(duplicate_pad_numbers_are_jumpers no)
		(fp_line
			(start 3.6 3.15)
			(end -3.6 3.15)
			(stroke
				(width 0.2)
				(type solid)
			)
			(layer "F.SilkS")
		)
		(fp_line
			(start 3.6 1.975)
			(end 3.6 3.15)
			(stroke
				(width 0.2)
				(type solid)
			)
			(layer "F.SilkS")
		)
		(fp_line
			(start 3.6 -3.15)
			(end 3.6 -1.975)
			(stroke
				(width 0.2)
				(type solid)
			)
			(layer "F.SilkS")
		)
		(fp_line
			(start 3.6 -3.15)
			(end -3.6 -3.15)
			(stroke
				(width 0.2)
				(type solid)
			)
			(layer "F.SilkS")
		)
		(fp_line
			(start -3.6 1.975)
			(end -3.6 3.15)
			(stroke
				(width 0.2)
				(type solid)
			)
			(layer "F.SilkS")
		)
		(fp_line
			(start -3.6 -3.15)
			(end -3.6 -1.975)
			(stroke
				(width 0.2)
				(type solid)
			)
			(layer "F.SilkS")
		)
		(fp_circle
			(center -4.25 -2.125)
			(end -4.25 -2)
			(stroke
				(width 0.25)
				(type solid)
			)
			(fill no)
			(layer "F.SilkS")
		)
		(pad "A" smd rect
			(at 2.85 0 270)
			(size 3.15 2.45)
			(layers "F.Cu" "F.Mask" "F.Paste")
			(net "ANT2")
		)
		(pad "K" smd rect
			(at -2.85 0 270)
			(size 3.15 2.45)
			(layers "F.Cu" "F.Mask" "F.Paste")
			(net "GND")
		)
	)
	(footprint "Capacitors:CAPC1608X10N"
		(layer "F.Cu")
		(at 161.100595 82.8276 -90)
		(property "Reference" "C76"
			(at -3.249 1.368655 90)
			(unlocked yes)
			(layer "F.SilkS")
			(effects
				(font
					(size 0.762 0.762)
					(thickness 0.2286)
				)
				(justify left bottom)
			)
		)
		(property "Value" "CAP_0603_0.01UF_50V"
			(at 4.08559 0.5461 0)
			(unlocked yes)
			(layer "F.SilkS")
			(hide yes)
			(effects
				(font
					(size 1.524 1.524)
					(thickness 0.254)
				)
				(justify left bottom)
			)
		)
		(sheetname "MAC")
		(sheetfile "MAC.kicad_sch")
		(duplicate_pad_numbers_are_jumpers no)
		(fp_line
			(start 0.635 0.7112)
			(end -0.635 0.7112)
			(stroke
				(width 0.1524)
				(type solid)
			)
			(layer "F.SilkS")
		)
		(fp_line
			(start 0.635 -0.7112)
			(end -0.635 -0.7112)
			(stroke
				(width 0.1524)
				(type solid)
			)
			(layer "F.SilkS")
		)
		(pad "1" smd rect
			(at -0.8 0)
			(size 0.95 1)
			(layers "F.Cu" "F.Mask" "F.Paste")
			(net "GND")
		)
		(pad "2" smd rect
			(at 0.8 0)
			(size 0.95 1)
			(layers "F.Cu" "F.Mask" "F.Paste")
			(net "+3.3V_CLEAN")
		)
	)
	(footprint "Modules:MAC-SA5X"
		(layer "F.Cu")
		(at 154.473665 92.25689 -90)
		(property "Reference" "U10"
			(at -0.535035 -47.59124 0)
			(unlocked yes)
			(layer "F.SilkS")
			(effects
				(font
					(size 0.762 0.762)
					(thickness 0.2286)
				)
				(justify left bottom)
			)
		)
		(property "Value" "MAC-SA5X"
			(at 27.98699 25.2857 0)
			(unlocked yes)
			(layer "F.SilkS")
			(hide yes)
			(effects
				(font
					(size 1.524 1.524)
					(thickness 0.254)
				)
				(justify left bottom)
			)
		)
		(sheetname "MAC")
		(sheetfile "MAC.kicad_sch")
		(duplicate_pad_numbers_are_jumpers no)
		(fp_line
			(start 0 0)
			(end 0 -50.8)
			(stroke
				(width 0.254)
				(type solid)
			)
			(layer "F.SilkS")
		)
		(fp_line
			(start 50.8 0)
			(end 0 0)
			(stroke
				(width 0.254)
				(type solid)
			)
			(layer "F.SilkS")
		)
		(fp_line
			(start 50.8 0)
			(end 50.8 -50.8)
			(stroke
				(width 0.254)
				(type solid)
			)
			(layer "F.SilkS")
		)
		(fp_line
			(start 50.8 -50.8)
			(end 0 -50.8)
			(stroke
				(width 0.254)
				(type solid)
			)
			(layer "F.SilkS")
		)
		(fp_circle
			(center 27.69128 -8.78503)
			(end 27.56428 -8.78503)
			(stroke
				(width 0.254)
				(type solid)
			)
			(fill no)
			(layer "F.SilkS")
		)
		(pad "1" smd rect
			(at 27.69128 -7.36503 90)
			(size 0.25 1.8)
			(layers "F.Cu" "F.Mask" "F.Paste")
			(net "MAC_PPS_IN1+")
		)
		(pad "2" smd rect
			(at 27.69128 -3.36503 90)
			(size 0.25 1.8)
			(layers "F.Cu" "F.Mask" "F.Paste")
			(net "MAC_USB+")
		)
		(pad "3" smd rect
			(at 27.18328 -7.36503 90)
			(size 0.25 1.8)
			(layers "F.Cu" "F.Mask" "F.Paste")
			(net "MAC_PPS_IN1-")
		)
		(pad "4" smd rect
			(at 27.18328 -3.36503 90)
			(size 0.25 1.8)
			(layers "F.Cu" "F.Mask" "F.Paste")
			(net "MAC_USB-")
		)
		(pad "5" smd rect
			(at 26.67528 -7.36503 90)
			(size 0.25 1.8)
			(layers "F.Cu" "F.Mask" "F.Paste")
			(net "MAC_PPS_IN0+")
		)
		(pad "6" smd rect
			(at 26.67528 -3.36503 90)
			(size 0.25 1.8)
			(layers "F.Cu" "F.Mask" "F.Paste")
			(net "MAC_USB_PWR")
		)
		(pad "7" smd rect
			(at 26.16728 -7.36503 90)
			(size 0.25 1.8)
			(layers "F.Cu" "F.Mask" "F.Paste")
			(net "MAC_PPS_IN0-")
		)
		(pad "8" smd rect
			(at 26.16728 -3.36503 90)
			(size 0.25 1.8)
			(layers "F.Cu" "F.Mask" "F.Paste")
			(net "GND")
		)
		(pad "9" smd rect
			(at 25.65928 -7.36503 90)
			(size 0.25 1.8)
			(layers "F.Cu" "F.Mask" "F.Paste")
			(net "GND")
		)
		(pad "10" smd rect
			(at 25.65928 -3.36503 90)
			(size 0.25 1.8)
			(layers "F.Cu" "F.Mask" "F.Paste")
		)
		(pad "11" smd rect
			(at 25.15128 -7.36503 90)
			(size 0.25 1.8)
			(layers "F.Cu" "F.Mask" "F.Paste")
		)
		(pad "12" smd rect
			(at 25.15128 -3.36503 90)
			(size 0.25 1.8)
			(layers "F.Cu" "F.Mask" "F.Paste")
		)
		(pad "13" smd rect
			(at 24.64328 -7.36503 90)
			(size 0.25 1.8)
			(layers "F.Cu" "F.Mask" "F.Paste")
		)
		(pad "14" smd rect
			(at 24.64328 -3.36503 90)
			(size 0.25 1.8)
			(layers "F.Cu" "F.Mask" "F.Paste")
		)
		(pad "15" smd rect
			(at 24.13528 -7.36503 90)
			(size 0.25 1.8)
			(layers "F.Cu" "F.Mask" "F.Paste")
			(net "GND")
		)
		(pad "16" smd rect
			(at 24.13528 -3.36503 90)
			(size 0.25 1.8)
			(layers "F.Cu" "F.Mask" "F.Paste")
		)
		(pad "17" smd rect
			(at 23.62728 -7.36503 90)
			(size 0.25 1.8)
			(layers "F.Cu" "F.Mask" "F.Paste")
			(net "MAC_PPS_OUT+")
		)
		(pad "18" smd rect
			(at 23.62728 -3.36503 90)
			(size 0.25 1.8)
			(layers "F.Cu" "F.Mask" "F.Paste")
		)
		(pad "19" smd rect
			(at 23.11928 -7.36503 90)
			(size 0.25 1.8)
			(layers "F.Cu" "F.Mask" "F.Paste")
			(net "MAC_PPS_OUT-")
		)
		(pad "20" smd rect
			(at 23.11928 -3.36503 90)
			(size 0.25 1.8)
			(layers "F.Cu" "F.Mask" "F.Paste")
			(net "MAC_ALARM")
		)
		(pad "P1" thru_hole circle
			(at 45.7 -45.7 270)
			(size 1.905 1.905)
			(drill 1.27)
			(layers "*.Cu" "*.Mask")
			(remove_unused_layers no)
			(net "MAC_10Mout")
			(thermal_bridge_angle 90)
		)
		(pad "P2" thru_hole circle
			(at 25.4 -45.7 270)
			(size 1.905 1.905)
			(drill 1.27)
			(layers "*.Cu" "*.Mask")
			(remove_unused_layers no)
			(net "GND")
			(thermal_bridge_angle 90)
		)
		(pad "P3" thru_hole circle
			(at 5.1 -45.7 270)
			(size 1.905 1.905)
			(drill 1.27)
			(layers "*.Cu" "*.Mask")
			(remove_unused_layers no)
			(net "MAC_10Mout")
			(thermal_bridge_angle 90)
		)
		(pad "P4" thru_hole circle
			(at 5.1 -5.1 270)
			(size 1.905 1.905)
			(drill 1.27)
			(layers "*.Cu" "*.Mask")
			(remove_unused_layers no)
			(net "GND")
			(thermal_bridge_angle 90)
		)
		(pad "P5" thru_hole circle
			(at 45.7 -5.1 270)
			(size 1.905 1.905)
			(drill 1.27)
			(layers "*.Cu" "*.Mask")
			(remove_unused_layers no)
			(net "+5.0V")
			(thermal_bridge_angle 90)
		)
		(pad "P6" thru_hole circle
			(at 2.4 -7.2 270)
			(size 1.905 1.905)
			(drill 1.27)
			(layers "*.Cu" "*.Mask")
			(remove_unused_layers no)
			(net "MAC_BITE")
			(thermal_bridge_angle 90)
		)
		(pad "P7" thru_hole circle
			(at 2.4 -10.2 270)
			(size 1.905 1.905)
			(drill 1.27)
			(layers "*.Cu" "*.Mask")
			(remove_unused_layers no)
			(net "MAC_RX")
			(thermal_bridge_angle 90)
		)
		(pad "P8" thru_hole circle
			(at 2.4 -13.2 270)
			(size 1.905 1.905)
			(drill 1.27)
			(layers "*.Cu" "*.Mask")
			(remove_unused_layers no)
			(net "MAC_TX")
			(thermal_bridge_angle 90)
		)
	)
	(footprint "Resistors:RESC1608X50N"
		(layer "F.Cu")
		(at 190.288595 53.6786)
		(property "Reference" "R34"
			(at 1.6 0.393345 0)
			(unlocked yes)
			(layer "F.SilkS")
			(effects
				(font
					(size 0.762 0.762)
					(thickness 0.2286)
				)
				(justify left bottom)
			)
		)
		(property "Value" "ERJ-3EKF1002V"
			(at -0.4445 3.72999 0)
			(unlocked yes)
			(layer "F.SilkS")
			(hide yes)
			(effects
				(font
					(size 1.524 1.524)
					(thickness 0.254)
				)
				(justify left bottom)
			)
		)
		(sheetname "USER_IO")
		(sheetfile "USER_IO.kicad_sch")
		(duplicate_pad_numbers_are_jumpers no)
		(fp_line
			(start 0 0.5)
			(end 0 -0.5)
			(stroke
				(width 0.1524)
				(type solid)
			)
			(layer "F.SilkS")
		)
		(pad "1" smd rect
			(at -0.69 0 90)
			(size 1 0.72)
			(layers "F.Cu" "F.Mask" "F.Paste")
			(net "NetR34_1")
		)
		(pad "2" smd rect
			(at 0.69 0 90)
			(size 1 0.72)
			(layers "F.Cu" "F.Mask" "F.Paste")
			(net "+3.3V")
		)
	)
	(footprint "Passives:DIOM6959X26N"
		(layer "F.Cu")
		(at 85.027595 124.2296 180)
		(property "Reference" "D17"
			(at 4.1402 4.097655 0)
			(unlocked yes)
			(layer "F.SilkS")
			(effects
				(font
					(size 0.762 0.762)
					(thickness 0.2286)
				)
				(justify left bottom)
			)
		)
		(property "Value" "SMCJ6.5CA"
			(at 4.2545 -5.91439 0)
			(unlocked yes)
			(layer "F.SilkS")
			(hide yes)
			(effects
				(font
					(size 1.524 1.524)
					(thickness 0.254)
				)
				(justify left bottom)
			)
		)
		(sheetname "USER_IO")
		(sheetfile "USER_IO.kicad_sch")
		(duplicate_pad_numbers_are_jumpers no)
		(fp_line
			(start 3.6 3.15)
			(end -3.6 3.15)
			(stroke
				(width 0.2)
				(type solid)
			)
			(layer "F.SilkS")
		)
		(fp_line
			(start 3.6 1.975)
			(end 3.6 3.15)
			(stroke
				(width 0.2)
				(type solid)
			)
			(layer "F.SilkS")
		)
		(fp_line
			(start 3.6 -3.15)
			(end 3.6 -1.975)
			(stroke
				(width 0.2)
				(type solid)
			)
			(layer "F.SilkS")
		)
		(fp_line
			(start 3.6 -3.15)
			(end -3.6 -3.15)
			(stroke
				(width 0.2)
				(type solid)
			)
			(layer "F.SilkS")
		)
		(fp_line
			(start -3.6 1.975)
			(end -3.6 3.15)
			(stroke
				(width 0.2)
				(type solid)
			)
			(layer "F.SilkS")
		)
		(fp_line
			(start -3.6 -3.15)
			(end -3.6 -1.975)
			(stroke
				(width 0.2)
				(type solid)
			)
			(layer "F.SilkS")
		)
		(fp_circle
			(center -4.25 -2.125)
			(end -4.25 -2)
			(stroke
				(width 0.25)
				(type solid)
			)
			(fill no)
			(layer "F.SilkS")
		)
		(pad "A" smd rect
			(at 2.85 0 270)
			(size 3.15 2.45)
			(layers "F.Cu" "F.Mask" "F.Paste")
			(net "ANT3")
		)
		(pad "K" smd rect
			(at -2.85 0 270)
			(size 3.15 2.45)
			(layers "F.Cu" "F.Mask" "F.Paste")
			(net "GND")
		)
	)
	(footprint "Resistors:RESC1608X50N"
		(layer "F.Cu")
		(at 147.511595 89.5332)
		(property "Reference" "R42"
			(at -1.47271 2.696655 0)
			(unlocked yes)
			(layer "F.SilkS")
			(effects
				(font
					(size 0.762 0.762)
					(thickness 0.2286)
				)
				(justify left bottom)
			)
		)
		(property "Value" "ERJ-3EKF1002V"
			(at -0.4445 3.72999 0)
			(unlocked yes)
			(layer "F.SilkS")
			(hide yes)
			(effects
				(font
					(size 1.524 1.524)
					(thickness 0.254)
				)
				(justify left bottom)
			)
		)
		(sheetname "MAC")
		(sheetfile "MAC.kicad_sch")
		(duplicate_pad_numbers_are_jumpers no)
		(fp_line
			(start 0 0.5)
			(end 0 -0.5)
			(stroke
				(width 0.1524)
				(type solid)
			)
			(layer "F.SilkS")
		)
		(pad "1" smd rect
			(at -0.69 0 90)
			(size 1 0.72)
			(layers "F.Cu" "F.Mask" "F.Paste")
			(net "NetR42_1")
		)
		(pad "2" smd rect
			(at 0.69 0 90)
			(size 1 0.72)
			(layers "F.Cu" "F.Mask" "F.Paste")
			(net "+3.3V_CLEAN")
		)
	)
	(footprint "Vault:CAPC1608X87X45ML20T05"
		(layer "F.Cu")
		(at 112.840595 67.0796 -90)
		(property "Reference" "C59"
			(at -2.001 -0.441345 90)
			(unlocked yes)
			(layer "F.SilkS")
			(effects
				(font
					(size 0.762 0.762)
					(thickness 0.2286)
				)
				(justify left bottom)
			)
		)
		(property "Value" "0.1uF"
			(at 3.47599 0.2921 0)
			(unlocked yes)
			(layer "F.SilkS")
			(hide yes)
			(effects
				(font
					(size 1.524 1.524)
					(thickness 0.254)
				)
				(justify left bottom)
			)
		)
		(sheetname "GPS_IMU_SENSORS")
		(sheetfile "GPS_IMU_SENSORS.kicad_sch")
		(duplicate_pad_numbers_are_jumpers no)
		(pad "1" smd rect
			(at -0.7 0)
			(size 1.1 1.05)
			(layers "F.Cu" "F.Mask" "F.Paste")
			(net "GND")
		)
		(pad "2" smd rect
			(at 0.7 0)
			(size 1.1 1.05)
			(layers "F.Cu" "F.Mask" "F.Paste")
			(net "+3.3V")
		)
	)
	(footprint "Connectors:3PINV-100"
		(layer "F.Cu")
		(at 110.388595 52.4286 -90)
		(property "Reference" "JP2"
			(at 6.925 1.431655 90)
			(unlocked yes)
			(layer "F.SilkS")
			(effects
				(font
					(size 0.762 0.762)
					(thickness 0.2286)
				)
				(justify left bottom)
			)
		)
		(property "Value" "JUMPER_3PIN"
			(at 9.49579 1.7145 0)
			(unlocked yes)
			(layer "F.SilkS")
			(hide yes)
			(effects
				(font
					(size 1.524 1.524)
					(thickness 0.254)
				)
				(justify left bottom)
			)
		)
		(sheetname "GPS_IMU_SENSORS")
		(sheetfile "GPS_IMU_SENSORS.kicad_sch")
		(duplicate_pad_numbers_are_jumpers no)
		(fp_line
			(start -1.27 1.27)
			(end -1.27 -1.27)
			(stroke
				(width 0.1524)
				(type solid)
			)
			(layer "F.SilkS")
		)
		(fp_line
			(start 6.35 1.27)
			(end -1.27 1.27)
			(stroke
				(width 0.1524)
				(type solid)
			)
			(layer "F.SilkS")
		)
		(fp_line
			(start 6.35 1.27)
			(end 6.35 -1.27)
			(stroke
				(width 0.1524)
				(type solid)
			)
			(layer "F.SilkS")
		)
		(fp_line
			(start 6.35 -1.27)
			(end -1.27 -1.27)
			(stroke
				(width 0.1524)
				(type solid)
			)
			(layer "F.SilkS")
		)
		(pad "1" thru_hole rect
			(at 0 0 270)
			(size 1.397 1.397)
			(drill 0.762)
			(layers "*.Cu" "*.Mask")
			(remove_unused_layers no)
			(net "GPS1_RX")
		)
		(pad "2" thru_hole circle
			(at 2.54 0 270)
			(size 1.397 1.397)
			(drill 0.762)
			(layers "*.Cu" "*.Mask")
			(remove_unused_layers no)
			(net "NetJP2_2")
			(thermal_bridge_angle 90)
		)
		(pad "3" thru_hole circle
			(at 5.08 0 270)
			(size 1.397 1.397)
			(drill 0.762)
			(layers "*.Cu" "*.Mask")
			(remove_unused_layers no)
			(net "NetJP2_3")
			(thermal_bridge_angle 90)
		)
	)
	(footprint "Vault:RESC1608X55X30NL15T15"
		(layer "F.Cu")
		(at 85.088595 56.9786 90)
		(property "Reference" "R29"
			(at -1.2 -1.206655 90)
			(unlocked yes)
			(layer "F.SilkS")
			(effects
				(font
					(size 0.762 0.762)
					(thickness 0.2286)
				)
				(justify left bottom)
			)
		)
		(property "Value" "200 OHM"
			(at -3.72999 -0.4445 0)
			(unlocked yes)
			(layer "F.SilkS")
			(hide yes)
			(effects
				(font
					(size 1.524 1.524)
					(thickness 0.254)
				)
				(justify left bottom)
			)
		)
		(sheetname "USER_IO")
		(sheetfile "USER_IO.kicad_sch")
		(duplicate_pad_numbers_are_jumpers no)
		(pad "1" smd rect
			(at -0.675 0 180)
			(size 0.95 0.8)
			(layers "F.Cu" "F.Mask" "F.Paste")
			(net "LED3")
		)
		(pad "2" smd rect
			(at 0.675 0 180)
			(size 0.95 0.8)
			(layers "F.Cu" "F.Mask" "F.Paste")
			(net "NetD13_1")
		)
	)
	(footprint "Miscellaneous:OMRON-B3U-1000P"
		(layer "F.Cu")
		(at 186.119595 53.7446)
		(property "Reference" "S6"
			(at -2.3622 -2.218055 0)
			(unlocked yes)
			(layer "F.SilkS")
			(effects
				(font
					(size 0.762 0.762)
					(thickness 0.2286)
				)
				(justify left bottom)
			)
		)
		(property "Value" "B3U-1000P"
			(at -2.3241 4.03479 0)
			(unlocked yes)
			(layer "F.SilkS")
			(hide yes)
			(effects
				(font
					(size 1.524 1.524)
					(thickness 0.254)
				)
				(justify left bottom)
			)
		)
		(sheetname "USER_IO")
		(sheetfile "USER_IO.kicad_sch")
		(duplicate_pad_numbers_are_jumpers no)
		(fp_line
			(start -2.286 -1.397)
			(end 2.286 -1.397)
			(stroke
				(width 0.2032)
				(type solid)
			)
			(layer "F.SilkS")
		)
		(fp_line
			(start -2.286 -1.143)
			(end -2.286 -1.397)
			(stroke
				(width 0.2032)
				(type solid)
			)
			(layer "F.SilkS")
		)
		(fp_line
			(start -2.286 1.397)
			(end -2.286 1.143)
			(stroke
				(width 0.2032)
				(type solid)
			)
			(layer "F.SilkS")
		)
		(fp_line
			(start -2.286 1.397)
			(end 2.286 1.397)
			(stroke
				(width 0.2032)
				(type solid)
			)
			(layer "F.SilkS")
		)
		(fp_line
			(start 2.286 -1.143)
			(end 2.286 -1.397)
			(stroke
				(width 0.2032)
				(type solid)
			)
			(layer "F.SilkS")
		)
		(fp_line
			(start 2.286 1.397)
			(end 2.286 1.143)
			(stroke
				(width 0.2032)
				(type solid)
			)
			(layer "F.SilkS")
		)
		(pad "1" smd rect
			(at -1.7 0)
			(size 0.8 1.7)
			(layers "F.Cu" "F.Mask" "F.Paste")
			(net "GND")
		)
		(pad "2" smd rect
			(at 1.7 0)
			(size 0.8 1.7)
			(layers "F.Cu" "F.Mask" "F.Paste")
			(net "NetR34_1")
		)
	)
	(footprint "Miscellaneous Devices:J1-0603"
		(layer "F.Cu")
		(at 119.138595 86.1786 -90)
		(property "Reference" "R17"
			(at -2.358749 -0.85179 0)
			(unlocked yes)
			(layer "F.SilkS")
			(effects
				(font
					(size 0.762 0.762)
					(thickness 0.254)
				)
			)
		)
		(property "Value" "MACPPS"
			(at 2.835402 -4.227705 0)
			(unlocked yes)
			(layer "F.SilkS")
			(hide yes)
			(effects
				(font
					(size 1.524 1.524)
					(thickness 0.254)
				)
			)
		)
		(sheetname "MAC")
		(sheetfile "MAC.kicad_sch")
		(duplicate_pad_numbers_are_jumpers no)
		(fp_line
			(start 0.2 0.35)
			(end -0.2 0.35)
			(stroke
				(width 0.2)
				(type solid)
			)
			(layer "F.SilkS")
		)
		(fp_line
			(start 0.2 -0.35)
			(end -0.2 -0.35)
			(stroke
				(width 0.2)
				(type solid)
			)
			(layer "F.SilkS")
		)
		(pad "1" smd rect
			(at -0.75 0)
			(size 0.9 0.7)
			(layers "F.Cu" "F.Mask" "F.Paste")
			(net "GPS1_TP1")
		)
		(pad "2" smd rect
			(at 0.75 0)
			(size 0.9 0.7)
			(layers "F.Cu" "F.Mask" "F.Paste")
			(net "MAC_PPS_IN0+")
		)
	)
	(footprint "Capacitors:CAPC2012X14N"
		(layer "F.Cu")
		(at 114.618595 67.0796 90)
		(property "Reference" "C58"
			(at 2.08329 0.664665 90)
			(unlocked yes)
			(layer "F.SilkS")
			(effects
				(font
					(size 0.762 0.762)
					(thickness 0.2286)
				)
				(justify left bottom)
			)
		)
		(property "Value" "CAP_0805_10UF_25V"
			(at -3.52679 -1.5875 0)
			(unlocked yes)
			(layer "F.SilkS")
			(hide yes)
			(effects
				(font
					(size 1.524 1.524)
					(thickness 0.254)
				)
				(justify left bottom)
			)
		)
		(sheetname "GPS_IMU_SENSORS")
		(sheetfile "GPS_IMU_SENSORS.kicad_sch")
		(duplicate_pad_numbers_are_jumpers no)
		(fp_line
			(start -0.762 -0.9652)
			(end 0.762 -0.9652)
			(stroke
				(width 0.1524)
				(type solid)
			)
			(layer "F.SilkS")
		)
		(fp_line
			(start -0.762 0.9652)
			(end 0.762 0.9652)
			(stroke
				(width 0.1524)
				(type solid)
			)
			(layer "F.SilkS")
		)
		(pad "1" smd rect
			(at -0.9 0 180)
			(size 1.45 1.15)
			(layers "F.Cu" "F.Mask" "F.Paste")
			(net "+3.3V")
		)
		(pad "2" smd rect
			(at 0.9 0 180)
			(size 1.45 1.15)
			(layers "F.Cu" "F.Mask" "F.Paste")
			(net "GND")
		)
	)
	(footprint "Resistors:RESC1608X50N"
		(layer "F.Cu")
		(at 113.018395 93.2162 90)
		(property "Reference" "R22"
			(at -0.9624 -1.036455 90)
			(unlocked yes)
			(layer "F.SilkS")
			(effects
				(font
					(size 0.762 0.762)
					(thickness 0.2286)
				)
				(justify left bottom)
			)
		)
		(property "Value" "ERJ-3EKF4701V"
			(at -3.72999 -0.4445 0)
			(unlocked yes)
			(layer "F.SilkS")
			(hide yes)
			(effects
				(font
					(size 1.524 1.524)
					(thickness 0.254)
				)
				(justify left bottom)
			)
		)
		(sheetname "PCIe_JTAG")
		(sheetfile "PCIe_JTAG.kicad_sch")
		(duplicate_pad_numbers_are_jumpers no)
		(fp_line
			(start 0 -0.5)
			(end 0 0.5)
			(stroke
				(width 0.1524)
				(type solid)
			)
			(layer "F.SilkS")
		)
		(pad "1" smd rect
			(at -0.69 0 180)
			(size 1 0.72)
			(layers "F.Cu" "F.Mask" "F.Paste")
			(net "PCIE_PERST")
		)
		(pad "2" smd rect
			(at 0.69 0 180)
			(size 1 0.72)
			(layers "F.Cu" "F.Mask" "F.Paste")
			(net "+3.3V")
		)
	)
	(footprint "Resistors:RESC1608X50N"
		(layer "F.Cu")
		(at 229.934595 106.8306 90)
		(property "Reference" "R2"
			(at 1.477 0.522345 90)
			(unlocked yes)
			(layer "F.SilkS")
			(effects
				(font
					(size 0.762 0.762)
					(thickness 0.2286)
				)
				(justify left bottom)
			)
		)
		(property "Value" "ERJ-3EKF4702V"
			(at -3.04419 -4.4323 0)
			(unlocked yes)
			(layer "F.SilkS")
			(hide yes)
			(effects
				(font
					(size 1.524 1.524)
					(thickness 0.254)
				)
				(justify left bottom)
			)
		)
		(sheetname "POWER")
		(sheetfile "POWER.kicad_sch")
		(duplicate_pad_numbers_are_jumpers no)
		(fp_line
			(start 0 -0.5)
			(end 0 0.5)
			(stroke
				(width 0.1524)
				(type solid)
			)
			(layer "F.SilkS")
		)
		(pad "1" smd rect
			(at -0.69 0 180)
			(size 1 0.72)
			(layers "F.Cu" "F.Mask" "F.Paste")
			(net "NetR2_1")
		)
		(pad "2" smd rect
			(at 0.69 0 180)
			(size 1 0.72)
			(layers "F.Cu" "F.Mask" "F.Paste")
			(net "+12V")
		)
	)
	(footprint "IntegratedCircuits:SOP64P600X170-16N"
		(layer "F.Cu")
		(at 102.655195 56.1322)
		(property "Reference" "U16"
			(at -4.161335 2.19029 90)
			(unlocked yes)
			(layer "F.SilkS")
			(effects
				(font
					(size 0.762 0.762)
					(thickness 0.2286)
				)
				(justify left bottom)
			)
		)
		(property "Value" "FT230XS-R"
			(at -3.4671 5.25399 0)
			(unlocked yes)
			(layer "F.SilkS")
			(hide yes)
			(effects
				(font
					(size 1.524 1.524)
					(thickness 0.254)
				)
				(justify left bottom)
			)
		)
		(sheetname "GPS_IMU_SENSORS")
		(sheetfile "GPS_IMU_SENSORS.kicad_sch")
		(duplicate_pad_numbers_are_jumpers no)
		(fp_line
			(start -1.6 -2.5)
			(end 1.6 -2.5)
			(stroke
				(width 0.2)
				(type solid)
			)
			(layer "F.SilkS")
		)
		(fp_line
			(start -1.6 2.5)
			(end -1.6 -2.5)
			(stroke
				(width 0.2)
				(type solid)
			)
			(layer "F.SilkS")
		)
		(fp_line
			(start -1.6 2.5)
			(end 1.6 2.5)
			(stroke
				(width 0.2)
				(type solid)
			)
			(layer "F.SilkS")
		)
		(fp_line
			(start 1.6 2.5)
			(end 1.6 -2.5)
			(stroke
				(width 0.2)
				(type solid)
			)
			(layer "F.SilkS")
		)
		(fp_circle
			(center -2.725 -2.9975)
			(end -2.725 -3.1225)
			(stroke
				(width 0.25)
				(type solid)
			)
			(fill no)
			(layer "F.SilkS")
		)
		(fp_circle
			(center -0.6 -1.5)
			(end -0.6 -1.8)
			(stroke
				(width 0.6)
				(type solid)
			)
			(fill no)
			(layer "F.SilkS")
		)
		(pad "1" smd oval
			(at -2.725 -2.2225 90)
			(size 0.45 1.45)
			(layers "F.Cu" "F.Mask" "F.Paste")
			(net "NetJP2_2")
		)
		(pad "2" smd oval
			(at -2.725 -1.5875 90)
			(size 0.45 1.45)
			(layers "F.Cu" "F.Mask" "F.Paste")
		)
		(pad "3" smd oval
			(at -2.725 -0.9525 90)
			(size 0.45 1.45)
			(layers "F.Cu" "F.Mask" "F.Paste")
			(net "NetU16_3")
		)
		(pad "4" smd oval
			(at -2.725 -0.3175 90)
			(size 0.45 1.45)
			(layers "F.Cu" "F.Mask" "F.Paste")
			(net "NetJP1_2")
		)
		(pad "5" smd oval
			(at -2.725 0.3175 90)
			(size 0.45 1.45)
			(layers "F.Cu" "F.Mask" "F.Paste")
			(net "GND")
		)
		(pad "6" smd oval
			(at -2.725 0.9525 90)
			(size 0.45 1.45)
			(layers "F.Cu" "F.Mask" "F.Paste")
		)
		(pad "7" smd oval
			(at -2.725 1.5875 90)
			(size 0.45 1.45)
			(layers "F.Cu" "F.Mask" "F.Paste")
		)
		(pad "8" smd oval
			(at -2.725 2.2225 90)
			(size 0.45 1.45)
			(layers "F.Cu" "F.Mask" "F.Paste")
			(net "NetJ4_3")
		)
		(pad "9" smd oval
			(at 2.725 2.2225 90)
			(size 0.45 1.45)
			(layers "F.Cu" "F.Mask" "F.Paste")
			(net "NetJ4_2")
		)
		(pad "10" smd oval
			(at 2.725 1.5875 90)
			(size 0.45 1.45)
			(layers "F.Cu" "F.Mask" "F.Paste")
			(net "NetU16_3")
		)
		(pad "11" smd oval
			(at 2.725 0.9525 90)
			(size 0.45 1.45)
			(layers "F.Cu" "F.Mask" "F.Paste")
			(net "NetR43_2")
		)
		(pad "12" smd oval
			(at 2.725 0.3175 90)
			(size 0.45 1.45)
			(layers "F.Cu" "F.Mask" "F.Paste")
			(net "+5.0V")
		)
		(pad "13" smd oval
			(at 2.725 -0.3175 90)
			(size 0.45 1.45)
			(layers "F.Cu" "F.Mask" "F.Paste")
			(net "GND")
		)
		(pad "14" smd oval
			(at 2.725 -0.9525 90)
			(size 0.45 1.45)
			(layers "F.Cu" "F.Mask" "F.Paste")
		)
		(pad "15" smd oval
			(at 2.725 -1.5875 90)
			(size 0.45 1.45)
			(layers "F.Cu" "F.Mask" "F.Paste")
		)
		(pad "16" smd oval
			(at 2.725 -2.2225 90)
			(size 0.45 1.45)
			(layers "F.Cu" "F.Mask" "F.Paste")
		)
	)
	(footprint "Passives:IND_PM124SH"
		(layer "F.Cu")
		(at 228.156595 94.2576 -90)
		(property "Reference" "L2"
			(at -7.488745 -4.73741 0)
			(unlocked yes)
			(layer "F.SilkS")
			(effects
				(font
					(size 0.762 0.762)
					(thickness 0.2286)
				)
				(justify left bottom)
			)
		)
		(property "Value" "PM124SH-100M-RC"
			(at 11.14679 12.7381 0)
			(unlocked yes)
			(layer "F.SilkS")
			(hide yes)
			(effects
				(font
					(size 1.524 1.524)
					(thickness 0.254)
				)
				(justify left bottom)
			)
		)
		(sheetname "POWER")
		(sheetfile "POWER.kicad_sch")
		(duplicate_pad_numbers_are_jumpers no)
		(fp_line
			(start -6.681 6.4)
			(end -6.681 -6.4)
			(stroke
				(width 0.254)
				(type solid)
			)
			(layer "F.SilkS")
		)
		(fp_line
			(start 6.681 6.4)
			(end -6.681 6.4)
			(stroke
				(width 0.254)
				(type solid)
			)
			(layer "F.SilkS")
		)
		(fp_line
			(start 6.681 6.4)
			(end 6.681 -6.4)
			(stroke
				(width 0.254)
				(type solid)
			)
			(layer "F.SilkS")
		)
		(fp_line
			(start 6.681 -6.4)
			(end -6.681 -6.4)
			(stroke
				(width 0.254)
				(type solid)
			)
			(layer "F.SilkS")
		)
		(pad "1" smd rect
			(at -4.85 0 270)
			(size 2.9 5.4)
			(layers "F.Cu" "F.Mask" "F.Paste")
			(net "+3.3V")
		)
		(pad "2" smd rect
			(at 4.85 0 270)
			(size 2.9 5.4)
			(layers "F.Cu" "F.Mask" "F.Paste")
			(net "NetC3_2")
		)
	)
	(footprint "Capacitors:CAPC2012X14N"
		(layer "F.Cu")
		(at 217.888595 87.9786 90)
		(property "Reference" "C7"
			(at 3 0.393345 90)
			(unlocked yes)
			(layer "F.SilkS")
			(effects
				(font
					(size 0.762 0.762)
					(thickness 0.2286)
				)
				(justify left bottom)
			)
		)
		(property "Value" "CAP_0805_10UF_25V"
			(at -15.71879 10.0965 0)
			(unlocked yes)
			(layer "F.SilkS")
			(hide yes)
			(effects
				(font
					(size 1.524 1.524)
					(thickness 0.254)
				)
				(justify left bottom)
			)
		)
		(sheetname "POWER")
		(sheetfile "POWER.kicad_sch")
		(duplicate_pad_numbers_are_jumpers no)
		(fp_line
			(start -0.762 -0.9652)
			(end 0.762 -0.9652)
			(stroke
				(width 0.1524)
				(type solid)
			)
			(layer "F.SilkS")
		)
		(fp_line
			(start -0.762 0.9652)
			(end 0.762 0.9652)
			(stroke
				(width 0.1524)
				(type solid)
			)
			(layer "F.SilkS")
		)
		(pad "1" smd rect
			(at -0.9 0 180)
			(size 1.45 1.15)
			(layers "F.Cu" "F.Mask" "F.Paste")
			(net "+3.3V")
		)
		(pad "2" smd rect
			(at 0.9 0 180)
			(size 1.45 1.15)
			(layers "F.Cu" "F.Mask" "F.Paste")
			(net "GND")
		)
	)
	(footprint "Miscellaneous:SM8"
		(layer "F.Cu")
		(at 232.093595 78.5096)
		(property "Reference" "X1"
			(at 2.97205 -3.221545 0)
			(unlocked yes)
			(layer "F.SilkS")
			(effects
				(font
					(size 0.762 0.762)
					(thickness 0.2286)
				)
				(justify left bottom)
			)
		)
		(property "Value" "MC306"
			(at -3.5941 7.59079 0)
			(unlocked yes)
			(layer "F.SilkS")
			(hide yes)
			(effects
				(font
					(size 1.524 1.524)
					(thickness 0.254)
				)
				(justify left bottom)
			)
		)
		(sheetname "GPS_IMU_SENSORS")
		(sheetfile "GPS_IMU_SENSORS.kicad_sch")
		(duplicate_pad_numbers_are_jumpers no)
		(fp_line
			(start -4.445 -1.905)
			(end -4.064 -1.905)
			(stroke
				(width 0.1524)
				(type solid)
			)
			(layer "F.SilkS")
		)
		(fp_line
			(start -4.445 1.905)
			(end -4.445 -1.905)
			(stroke
				(width 0.1524)
				(type solid)
			)
			(layer "F.SilkS")
		)
		(fp_line
			(start -4.445 1.905)
			(end -4.064 1.905)
			(stroke
				(width 0.1524)
				(type solid)
			)
			(layer "F.SilkS")
		)
		(fp_line
			(start -3.81 1.27)
			(end -3.81 -1.27)
			(stroke
				(width 0.1524)
				(type solid)
			)
			(layer "F.SilkS")
		)
		(fp_line
			(start -1.397 -1.905)
			(end 1.397 -1.905)
			(stroke
				(width 0.1524)
				(type solid)
			)
			(layer "F.SilkS")
		)
		(fp_line
			(start -1.397 1.905)
			(end 1.397 1.905)
			(stroke
				(width 0.1524)
				(type solid)
			)
			(layer "F.SilkS")
		)
		(fp_line
			(start 4.064 -1.905)
			(end 4.445 -1.905)
			(stroke
				(width 0.1524)
				(type solid)
			)
			(layer "F.SilkS")
		)
		(fp_line
			(start 4.064 1.905)
			(end 4.445 1.905)
			(stroke
				(width 0.1524)
				(type solid)
			)
			(layer "F.SilkS")
		)
		(fp_line
			(start 4.445 -1.651)
			(end 4.445 -1.905)
			(stroke
				(width 0.1524)
				(type solid)
			)
			(layer "F.SilkS")
		)
		(fp_line
			(start 4.445 1.651)
			(end 4.445 -1.651)
			(stroke
				(width 0.1524)
				(type solid)
			)
			(layer "F.SilkS")
		)
		(fp_line
			(start 4.445 1.905)
			(end 4.445 1.651)
			(stroke
				(width 0.1524)
				(type solid)
			)
			(layer "F.SilkS")
		)
		(fp_circle
			(center -4.064 2.54)
			(end -4.064 2.413)
			(stroke
				(width 0.254)
				(type solid)
			)
			(fill no)
			(layer "F.SilkS")
		)
		(pad "1" smd rect
			(at -2.75 1.6 90)
			(size 1.9 1.3)
			(layers "F.Cu" "F.Mask" "F.Paste")
			(net "NetC85_2")
		)
		(pad "2" smd rect
			(at 2.75 1.6 90)
			(size 1.9 1.3)
			(layers "F.Cu" "F.Mask" "F.Paste")
		)
		(pad "3" smd rect
			(at 2.75 -1.6 90)
			(size 1.9 1.3)
			(layers "F.Cu" "F.Mask" "F.Paste")
		)
		(pad "4" smd rect
			(at -2.75 -1.6 90)
			(size 1.9 1.3)
			(layers "F.Cu" "F.Mask" "F.Paste")
			(net "NetC86_2")
		)
	)
	(footprint "Passives:INDC1608X09N"
		(layer "F.Cu")
		(at 163.894595 89.0506 90)
		(property "Reference" "FB3"
			(at 1.80389 0.715465 90)
			(unlocked yes)
			(layer "F.SilkS")
			(effects
				(font
					(size 0.762 0.762)
					(thickness 0.2286)
				)
				(justify left bottom)
			)
		)
		(property "Value" "MPZ1608_220OHM_0603"
			(at -3.88239 -0.5461 0)
			(unlocked yes)
			(layer "F.SilkS")
			(hide yes)
			(effects
				(font
					(size 1.524 1.524)
					(thickness 0.254)
				)
				(justify left bottom)
			)
		)
		(sheetname "MAC")
		(sheetfile "MAC.kicad_sch")
		(duplicate_pad_numbers_are_jumpers no)
		(pad "1" smd rect
			(at -0.665 0 180)
			(size 0.98 0.87)
			(layers "F.Cu" "F.Mask" "F.Paste")
			(net "NetC72_2")
		)
		(pad "2" smd rect
			(at 0.665 0 180)
			(size 0.98 0.87)
			(layers "F.Cu" "F.Mask" "F.Paste")
			(net "+3.3V_CLEAN")
		)
	)
	(footprint "Vault:CAPC1608X87X45ML20T05"
		(layer "F.Cu")
		(at 165.672595 82.8276 -90)
		(property "Reference" "C79"
			(at -3.224 1.665655 90)
			(unlocked yes)
			(layer "F.SilkS")
			(effects
				(font
					(size 0.762 0.762)
					(thickness 0.2286)
				)
				(justify left bottom)
			)
		)
		(property "Value" "0.1uF"
			(at 3.47599 0.2921 0)
			(unlocked yes)
			(layer "F.SilkS")
			(hide yes)
			(effects
				(font
					(size 1.524 1.524)
					(thickness 0.254)
				)
				(justify left bottom)
			)
		)
		(sheetname "MAC")
		(sheetfile "MAC.kicad_sch")
		(duplicate_pad_numbers_are_jumpers no)
		(pad "1" smd rect
			(at -0.7 0)
			(size 1.1 1.05)
			(layers "F.Cu" "F.Mask" "F.Paste")
			(net "GND")
		)
		(pad "2" smd rect
			(at 0.7 0)
			(size 1.1 1.05)
			(layers "F.Cu" "F.Mask" "F.Paste")
			(net "+3.3V_CLEAN")
		)
	)
	(footprint "Vault:CAPC1608X87X45ML20T05"
		(layer "F.Cu")
		(at 227.648595 118.1336)
		(property "Reference" "C16"
			(at 1.74 0.638345 0)
			(unlocked yes)
			(layer "F.SilkS")
			(effects
				(font
					(size 0.762 0.762)
					(thickness 0.2286)
				)
				(justify left bottom)
			)
		)
		(property "Value" "0.1uF"
			(at 0.3429 7.15899 0)
			(unlocked yes)
			(layer "F.SilkS")
			(hide yes)
			(effects
				(font
					(size 1.524 1.524)
					(thickness 0.254)
				)
				(justify left bottom)
			)
		)
		(sheetname "POWER")
		(sheetfile "POWER.kicad_sch")
		(duplicate_pad_numbers_are_jumpers no)
		(pad "1" smd rect
			(at -0.7 0 90)
			(size 1.1 1.05)
			(layers "F.Cu" "F.Mask" "F.Paste")
			(net "GND")
		)
		(pad "2" smd rect
			(at 0.7 0 90)
			(size 1.1 1.05)
			(layers "F.Cu" "F.Mask" "F.Paste")
			(net "+5.0V")
		)
	)
	(footprint "Resistors:RESC1608X50N"
		(layer "F.Cu")
		(at 176.988595 55.1786 180)
		(property "Reference" "R35"
			(at -1.7 -0.393345 0)
			(unlocked yes)
			(layer "F.SilkS")
			(effects
				(font
					(size 0.762 0.762)
					(thickness 0.2286)
				)
				(justify left bottom)
			)
		)
		(property "Value" "ERJ-3EKF1001V"
			(at 0.4445 -3.72999 0)
			(unlocked yes)
			(layer "F.SilkS")
			(hide yes)
			(effects
				(font
					(size 1.524 1.524)
					(thickness 0.254)
				)
				(justify left bottom)
			)
		)
		(sheetname "USER_IO")
		(sheetfile "USER_IO.kicad_sch")
		(duplicate_pad_numbers_are_jumpers no)
		(fp_line
			(start 0 -0.5)
			(end 0 0.5)
			(stroke
				(width 0.1524)
				(type solid)
			)
			(layer "F.SilkS")
		)
		(pad "1" smd rect
			(at -0.69 0 270)
			(size 1 0.72)
			(layers "F.Cu" "F.Mask" "F.Paste")
			(net "KEY1")
		)
		(pad "2" smd rect
			(at 0.69 0 270)
			(size 1 0.72)
			(layers "F.Cu" "F.Mask" "F.Paste")
			(net "NetR33_1")
		)
	)
	(footprint "Capacitors:CAPC2012X14N"
		(layer "F.Cu")
		(at 166.307595 78.1286)
		(property "Reference" "C84"
			(at -1.6256 -1.684655 0)
			(unlocked yes)
			(layer "F.SilkS")
			(effects
				(font
					(size 0.762 0.762)
					(thickness 0.2286)
				)
				(justify left bottom)
			)
		)
		(property "Value" "CAP_0805_1UF_50V"
			(at -1.5875 3.52679 0)
			(unlocked yes)
			(layer "F.SilkS")
			(hide yes)
			(effects
				(font
					(size 1.524 1.524)
					(thickness 0.254)
				)
				(justify left bottom)
			)
		)
		(sheetname "MAC")
		(sheetfile "MAC.kicad_sch")
		(duplicate_pad_numbers_are_jumpers no)
		(fp_line
			(start -0.762 -0.9652)
			(end 0.762 -0.9652)
			(stroke
				(width 0.1524)
				(type solid)
			)
			(layer "F.SilkS")
		)
		(fp_line
			(start -0.762 0.9652)
			(end 0.762 0.9652)
			(stroke
				(width 0.1524)
				(type solid)
			)
			(layer "F.SilkS")
		)
		(pad "1" smd rect
			(at -0.9 0 90)
			(size 1.45 1.15)
			(layers "F.Cu" "F.Mask" "F.Paste")
			(net "GND")
		)
		(pad "2" smd rect
			(at 0.9 0 90)
			(size 1.45 1.15)
			(layers "F.Cu" "F.Mask" "F.Paste")
			(net "+3.3V_CLEAN")
		)
	)
	(footprint "Miscellaneous:SiT5155"
		(layer "F.Cu")
		(at 147.003595 85.0882)
		(property "Reference" "U13"
			(at 2.63571 2.950655 0)
			(unlocked yes)
			(layer "F.SilkS")
			(effects
				(font
					(size 0.762 0.762)
					(thickness 0.2286)
				)
				(justify left bottom)
			)
		)
		(property "Value" "SiT5356AI-FQA33-IT-10.000000"
			(at -2.37473 5.60959 0)
			(unlocked yes)
			(layer "F.SilkS")
			(hide yes)
			(effects
				(font
					(size 1.524 1.524)
					(thickness 0.254)
				)
				(justify left bottom)
			)
		)
		(sheetname "MAC")
		(sheetfile "MAC.kicad_sch")
		(duplicate_pad_numbers_are_jumpers no)
		(fp_line
			(start -2.032 -3.048)
			(end -0.66154 -3.048)
			(stroke
				(width 0.2032)
				(type solid)
			)
			(layer "F.SilkS")
		)
		(fp_line
			(start -2.032 -1.45426)
			(end -2.032 -3.048)
			(stroke
				(width 0.2032)
				(type solid)
			)
			(layer "F.SilkS")
		)
		(fp_line
			(start -2.032 3.048)
			(end -2.032 2.54)
			(stroke
				(width 0.2032)
				(type solid)
			)
			(layer "F.SilkS")
		)
		(fp_line
			(start -2.032 3.048)
			(end -1.524 3.048)
			(stroke
				(width 0.2032)
				(type solid)
			)
			(layer "F.SilkS")
		)
		(fp_line
			(start 1.524 -3.048)
			(end 2.032 -3.048)
			(stroke
				(width 0.2032)
				(type solid)
			)
			(layer "F.SilkS")
		)
		(fp_line
			(start 1.524 3.048)
			(end 2.032 3.048)
			(stroke
				(width 0.2032)
				(type solid)
			)
			(layer "F.SilkS")
		)
		(fp_line
			(start 2.032 -2.54)
			(end 2.032 -3.048)
			(stroke
				(width 0.2032)
				(type solid)
			)
			(layer "F.SilkS")
		)
		(fp_line
			(start 2.032 3.048)
			(end 2.032 2.54)
			(stroke
				(width 0.2032)
				(type solid)
			)
			(layer "F.SilkS")
		)
		(pad "1" smd rect
			(at -1.175 -2.025)
			(size 1.05 1.15)
			(layers "F.Cu" "F.Mask" "F.Paste")
			(net "OE_5356")
		)
		(pad "2" smd rect
			(at -1.025 -0.6)
			(size 1.35 0.7)
			(layers "F.Cu" "F.Mask" "F.Paste")
			(net "SCL")
		)
		(pad "3" smd rect
			(at -1.025 0.6)
			(size 1.35 0.7)
			(layers "F.Cu" "F.Mask" "F.Paste")
		)
		(pad "4" smd rect
			(at -1.175 2.025)
			(size 1.05 1.15)
			(layers "F.Cu" "F.Mask" "F.Paste")
			(net "GND")
		)
		(pad "5" smd rect
			(at 0 2.025 90)
			(size 1.15 0.7)
			(layers "F.Cu" "F.Mask" "F.Paste")
			(net "NetR42_1")
		)
		(pad "6" smd rect
			(at 1.175 2.025)
			(size 1.05 1.15)
			(layers "F.Cu" "F.Mask" "F.Paste")
			(net "DCXO1")
		)
		(pad "7" smd rect
			(at 1.025 0.6)
			(size 1.35 0.7)
			(layers "F.Cu" "F.Mask" "F.Paste")
		)
		(pad "8" smd rect
			(at 1.025 -0.6)
			(size 1.35 0.7)
			(layers "F.Cu" "F.Mask" "F.Paste")
		)
		(pad "9" smd rect
			(at 1.175 -2.025)
			(size 1.05 1.15)
			(layers "F.Cu" "F.Mask" "F.Paste")
			(net "+3.3V_CLEAN")
		)
		(pad "10" smd rect
			(at 0 -2.025 90)
			(size 1.15 0.7)
			(layers "F.Cu" "F.Mask" "F.Paste")
			(net "SDA")
		)
	)
	(footprint "Capacitors:CAPC2012X14N"
		(layer "F.Cu")
		(at 222.949595 82.5736 180)
		(property "Reference" "C56"
			(at 4.261 -0.498345 0)
			(unlocked yes)
			(layer "F.SilkS")
			(effects
				(font
					(size 0.762 0.762)
					(thickness 0.2286)
				)
				(justify left bottom)
			)
		)
		(property "Value" "CAP_0805_10UF_25V"
			(at -15.9385 4.09321 0)
			(unlocked yes)
			(layer "F.SilkS")
			(hide yes)
			(effects
				(font
					(size 1.524 1.524)
					(thickness 0.254)
				)
				(justify left bottom)
			)
		)
		(sheetname "GPS_IMU_SENSORS")
		(sheetfile "GPS_IMU_SENSORS.kicad_sch")
		(duplicate_pad_numbers_are_jumpers no)
		(fp_line
			(start 0.762 0.9652)
			(end -0.762 0.9652)
			(stroke
				(width 0.1524)
				(type solid)
			)
			(layer "F.SilkS")
		)
		(fp_line
			(start 0.762 -0.9652)
			(end -0.762 -0.9652)
			(stroke
				(width 0.1524)
				(type solid)
			)
			(layer "F.SilkS")
		)
		(pad "1" smd rect
			(at -0.9 0 270)
			(size 1.45 1.15)
			(layers "F.Cu" "F.Mask" "F.Paste")
			(net "+3.3V")
		)
		(pad "2" smd rect
			(at 0.9 0 270)
			(size 1.45 1.15)
			(layers "F.Cu" "F.Mask" "F.Paste")
			(net "GND")
		)
	)
	(footprint "IntegratedCircuits:SOIC127P600X175-8N"
		(layer "F.Cu")
		(at 229.553595 110.8946)
		(property "Reference" "U1"
			(at -4.415 -2.972655 0)
			(unlocked yes)
			(layer "F.SilkS")
			(effects
				(font
					(size 0.762 0.762)
					(thickness 0.2286)
				)
				(justify left bottom)
			)
		)
		(property "Value" "MP1482DS-LF"
			(at -6.9469 5.15239 0)
			(unlocked yes)
			(layer "F.SilkS")
			(hide yes)
			(effects
				(font
					(size 1.524 1.524)
					(thickness 0.254)
				)
				(justify left bottom)
			)
		)
		(sheetname "POWER")
		(sheetfile "POWER.kicad_sch")
		(duplicate_pad_numbers_are_jumpers no)
		(fp_line
			(start -3.4 -2.5)
			(end 2 -2.5)
			(stroke
				(width 0.12)
				(type solid)
			)
			(layer "F.SilkS")
		)
		(fp_line
			(start -2 2.5)
			(end 2 2.5)
			(stroke
				(width 0.12)
				(type solid)
			)
			(layer "F.SilkS")
		)
		(pad "1" smd rect
			(at -2.475 -1.905)
			(size 1.97 0.57)
			(layers "F.Cu" "F.Mask" "F.Paste")
			(net "NetC4_1")
		)
		(pad "2" smd rect
			(at -2.475 -0.635)
			(size 1.97 0.57)
			(layers "F.Cu" "F.Mask" "F.Paste")
			(net "+12V")
		)
		(pad "3" smd rect
			(at -2.475 0.635)
			(size 1.97 0.57)
			(layers "F.Cu" "F.Mask" "F.Paste")
			(net "NetC4_2")
		)
		(pad "4" smd rect
			(at -2.475 1.905)
			(size 1.97 0.57)
			(layers "F.Cu" "F.Mask" "F.Paste")
			(net "GND")
		)
		(pad "5" smd rect
			(at 2.475 1.905)
			(size 1.97 0.57)
			(layers "F.Cu" "F.Mask" "F.Paste")
			(net "NetR4_2")
		)
		(pad "6" smd rect
			(at 2.475 0.635)
			(size 1.97 0.57)
			(layers "F.Cu" "F.Mask" "F.Paste")
			(net "NetC20_2")
		)
		(pad "7" smd rect
			(at 2.475 -0.635)
			(size 1.97 0.57)
			(layers "F.Cu" "F.Mask" "F.Paste")
			(net "NetR2_1")
		)
		(pad "8" smd rect
			(at 2.475 -1.905)
			(size 1.97 0.57)
			(layers "F.Cu" "F.Mask" "F.Paste")
			(net "NetC19_2")
		)
	)
	(footprint "Resistors:RESC1608X50N"
		(layer "F.Cu")
		(at 230.288595 114.3786)
		(property "Reference" "R6"
			(at -3.398 0.321345 0)
			(unlocked yes)
			(layer "F.SilkS")
			(effects
				(font
					(size 0.762 0.762)
					(thickness 0.2286)
				)
				(justify left bottom)
			)
		)
		(property "Value" "ERJ-3EKF1002V"
			(at -4.4323 3.04419 0)
			(unlocked yes)
			(layer "F.SilkS")
			(hide yes)
			(effects
				(font
					(size 1.524 1.524)
					(thickness 0.254)
				)
				(justify left bottom)
			)
		)
		(sheetname "POWER")
		(sheetfile "POWER.kicad_sch")
		(duplicate_pad_numbers_are_jumpers no)
		(fp_line
			(start 0 0.5)
			(end 0 -0.5)
			(stroke
				(width 0.1524)
				(type solid)
			)
			(layer "F.SilkS")
		)
		(pad "1" smd rect
			(at -0.69 0 90)
			(size 1 0.72)
			(layers "F.Cu" "F.Mask" "F.Paste")
			(net "GND")
		)
		(pad "2" smd rect
			(at 0.69 0 90)
			(size 1 0.72)
			(layers "F.Cu" "F.Mask" "F.Paste")
			(net "NetR4_2")
		)
	)
	(footprint "Resistors:RESC1608X50N"
		(layer "F.Cu")
		(at 219.488595 98.0786 180)
		(property "Reference" "R7"
			(at 3.982 -0.350345 0)
			(unlocked yes)
			(layer "F.SilkS")
			(effects
				(font
					(size 0.762 0.762)
					(thickness 0.2286)
				)
				(justify left bottom)
			)
		)
		(property "Value" "ERJ-3EKF1002V"
			(at -10.9347 3.94081 0)
			(unlocked yes)
			(layer "F.SilkS")
			(hide yes)
			(effects
				(font
					(size 1.524 1.524)
					(thickness 0.254)
				)
				(justify left bottom)
			)
		)
		(sheetname "POWER")
		(sheetfile "POWER.kicad_sch")
		(duplicate_pad_numbers_are_jumpers no)
		(fp_line
			(start 0 -0.5)
			(end 0 0.5)
			(stroke
				(width 0.1524)
				(type solid)
			)
			(layer "F.SilkS")
		)
		(pad "1" smd rect
			(at -0.69 0 270)
			(size 1 0.72)
			(layers "F.Cu" "F.Mask" "F.Paste")
			(net "GND")
		)
		(pad "2" smd rect
			(at 0.69 0 270)
			(size 1 0.72)
			(layers "F.Cu" "F.Mask" "F.Paste")
			(net "NetR5_1")
		)
	)
	(footprint "Resistors:RESC1608X50N"
		(layer "F.Cu")
		(at 164.603595 69.0536)
		(property "Reference" "R1"
			(at -3.215 0.418345 0)
			(unlocked yes)
			(layer "F.SilkS")
			(effects
				(font
					(size 0.762 0.762)
					(thickness 0.2286)
				)
				(justify left bottom)
			)
		)
		(property "Value" "ERJ-3EKF2000V"
			(at -1.0033 3.17119 0)
			(unlocked yes)
			(layer "F.SilkS")
			(hide yes)
			(effects
				(font
					(size 1.524 1.524)
					(thickness 0.254)
				)
				(justify left bottom)
			)
		)
		(sheetname "POWER")
		(sheetfile "POWER.kicad_sch")
		(duplicate_pad_numbers_are_jumpers no)
		(fp_line
			(start 0 0.5)
			(end 0 -0.5)
			(stroke
				(width 0.1524)
				(type solid)
			)
			(layer "F.SilkS")
		)
		(pad "1" smd rect
			(at -0.69 0 90)
			(size 1 0.72)
			(layers "F.Cu" "F.Mask" "F.Paste")
			(net "GND")
		)
		(pad "2" smd rect
			(at 0.69 0 90)
			(size 1 0.72)
			(layers "F.Cu" "F.Mask" "F.Paste")
			(net "NetD4_1")
		)
	)
	(footprint "Miscellaneous Devices:J1-0603"
		(layer "F.Cu")
		(at 82.388595 102.7786 180)
		(property "Reference" "R15"
			(at -3.054 0.073079 0)
			(unlocked yes)
			(layer "F.SilkS")
			(effects
				(font
					(size 0.762 0.762)
					(thickness 0.254)
				)
			)
		)
		(property "Value" "MACPPSI"
			(at -4.98946 -2.835402 0)
			(unlocked yes)
			(layer "F.SilkS")
			(hide yes)
			(effects
				(font
					(size 1.524 1.524)
					(thickness 0.254)
				)
			)
		)
		(sheetname "USER_IO")
		(sheetfile "USER_IO.kicad_sch")
		(duplicate_pad_numbers_are_jumpers no)
		(fp_line
			(start 0.2 0.35)
			(end -0.2 0.35)
			(stroke
				(width 0.2)
				(type solid)
			)
			(layer "F.SilkS")
		)
		(fp_line
			(start 0.2 -0.35)
			(end -0.2 -0.35)
			(stroke
				(width 0.2)
				(type solid)
			)
			(layer "F.SilkS")
		)
		(pad "1" smd rect
			(at -0.75 0 270)
			(size 0.9 0.7)
			(layers "F.Cu" "F.Mask" "F.Paste")
			(net "MAC_PPS_IN0+")
		)
		(pad "2" smd rect
			(at 0.75 0 270)
			(size 0.9 0.7)
			(layers "F.Cu" "F.Mask" "F.Paste")
			(net "ANT1")
		)
	)
	(footprint "Resistors:RESC2012X50N"
		(layer "F.Cu")
		(at 138.367595 66.4446 90)
		(property "Reference" "R20"
			(at -4.97791 0.690065 90)
			(unlocked yes)
			(layer "F.SilkS")
			(effects
				(font
					(size 0.762 0.762)
					(thickness 0.2286)
				)
				(justify left bottom)
			)
		)
		(property "Value" "CRCW080533R0FKEA"
			(at -3.52679 -1.5875 0)
			(unlocked yes)
			(layer "F.SilkS")
			(hide yes)
			(effects
				(font
					(size 1.524 1.524)
					(thickness 0.254)
				)
				(justify left bottom)
			)
		)
		(sheetname "PCIe_JTAG")
		(sheetfile "PCIe_JTAG.kicad_sch")
		(duplicate_pad_numbers_are_jumpers no)
		(fp_line
			(start 0 -0.762)
			(end 0 0.762)
			(stroke
				(width 0.1524)
				(type solid)
			)
			(layer "F.SilkS")
		)
		(pad "1" smd rect
			(at -1 0 180)
			(size 1.45 0.95)
			(layers "F.Cu" "F.Mask" "F.Paste")
			(net "FPGA_TMS")
		)
		(pad "2" smd rect
			(at 1 0 180)
			(size 1.45 0.95)
			(layers "F.Cu" "F.Mask" "F.Paste")
			(net "NetR20_2")
		)
	)
	(footprint "Vault:RESC1608X55X30NL15T15"
		(layer "F.Cu")
		(at 90.188595 56.9786 90)
		(property "Reference" "R30"
			(at -1.3 -1.206655 90)
			(unlocked yes)
			(layer "F.SilkS")
			(effects
				(font
					(size 0.762 0.762)
					(thickness 0.2286)
				)
				(justify left bottom)
			)
		)
		(property "Value" "200 OHM"
			(at -3.72999 -0.4445 0)
			(unlocked yes)
			(layer "F.SilkS")
			(hide yes)
			(effects
				(font
					(size 1.524 1.524)
					(thickness 0.254)
				)
				(justify left bottom)
			)
		)
		(sheetname "USER_IO")
		(sheetfile "USER_IO.kicad_sch")
		(duplicate_pad_numbers_are_jumpers no)
		(pad "1" smd rect
			(at -0.675 0 180)
			(size 0.95 0.8)
			(layers "F.Cu" "F.Mask" "F.Paste")
			(net "LED4")
		)
		(pad "2" smd rect
			(at 0.675 0 180)
			(size 0.95 0.8)
			(layers "F.Cu" "F.Mask" "F.Paste")
			(net "NetD14_1")
		)
	)
	(footprint "Resistors:RESC2012X50N"
		(layer "F.Cu")
		(at 133.287595 66.4446 90)
		(property "Reference" "R18"
			(at -4.88269 0.791665 90)
			(unlocked yes)
			(layer "F.SilkS")
			(effects
				(font
					(size 0.762 0.762)
					(thickness 0.2286)
				)
				(justify left bottom)
			)
		)
		(property "Value" "CRCW080533R0FKEA"
			(at -3.52679 -1.5875 0)
			(unlocked yes)
			(layer "F.SilkS")
			(hide yes)
			(effects
				(font
					(size 1.524 1.524)
					(thickness 0.254)
				)
				(justify left bottom)
			)
		)
		(sheetname "PCIe_JTAG")
		(sheetfile "PCIe_JTAG.kicad_sch")
		(duplicate_pad_numbers_are_jumpers no)
		(fp_line
			(start 0 -0.762)
			(end 0 0.762)
			(stroke
				(width 0.1524)
				(type solid)
			)
			(layer "F.SilkS")
		)
		(pad "1" smd rect
			(at -1 0 180)
			(size 1.45 0.95)
			(layers "F.Cu" "F.Mask" "F.Paste")
			(net "FPGA_TCK")
		)
		(pad "2" smd rect
			(at 1 0 180)
			(size 1.45 0.95)
			(layers "F.Cu" "F.Mask" "F.Paste")
			(net "NetR18_2")
		)
	)
	(footprint "Vault:CAPC1608X87X45ML20T05"
		(layer "F.Cu")
		(at 173.388595 63.5786 90)
		(property "Reference" "C25"
			(at 3.3286 0.026931 90)
			(unlocked yes)
			(layer "F.SilkS")
			(effects
				(font
					(size 0.762 0.762)
					(thickness 0.2286)
				)
			)
		)
		(property "Value" "0.1uF"
			(at 2.09443 2.657602 90)
			(unlocked yes)
			(layer "F.SilkS")
			(hide yes)
			(effects
				(font
					(size 1.524 1.524)
					(thickness 0.254)
				)
			)
		)
		(sheetname "GPS_IMU_SENSORS")
		(sheetfile "GPS_IMU_SENSORS.kicad_sch")
		(duplicate_pad_numbers_are_jumpers no)
		(pad "1" smd rect
			(at -0.7 0 180)
			(size 1.1 1.05)
			(layers "F.Cu" "F.Mask" "F.Paste")
			(net "GND")
		)
		(pad "2" smd rect
			(at 0.7 0 180)
			(size 1.1 1.05)
			(layers "F.Cu" "F.Mask" "F.Paste")
			(net "+3.3V")
		)
	)
	(footprint "Connectors:AMPHENOL-901-143-6RFX"
		(layer "F.Cu")
		(at 63.564595 124.2296 180)
		(property "Reference" "AN3"
			(at -5.25829 -4.627055 0)
			(unlocked yes)
			(layer "F.SilkS")
			(effects
				(font
					(size 0.762 0.762)
					(thickness 0.2286)
				)
				(justify left bottom)
			)
		)
		(property "Value" "RF-901-143-6FRX"
			(at 4.6101 -2.05359 0)
			(unlocked yes)
			(layer "F.SilkS")
			(hide yes)
			(effects
				(font
					(size 1.524 1.524)
					(thickness 0.254)
				)
				(justify left bottom)
			)
		)
		(sheetfile ".kicad_sch")
		(duplicate_pad_numbers_are_jumpers no)
		(fp_line
			(start 4.318 3.556)
			(end 3.302 4.572)
			(stroke
				(width 0.1778)
				(type solid)
			)
			(layer "F.SilkS")
		)
		(fp_line
			(start 4.318 -3.556)
			(end 3.302 -4.572)
			(stroke
				(width 0.1778)
				(type solid)
			)
			(layer "F.SilkS")
		)
		(fp_line
			(start 3.302 4.572)
			(end 2.54 4.572)
			(stroke
				(width 0.1778)
				(type solid)
			)
			(layer "F.SilkS")
		)
		(fp_line
			(start 3.302 -4.572)
			(end 2.54 -4.572)
			(stroke
				(width 0.1778)
				(type solid)
			)
			(layer "F.SilkS")
		)
		(fp_line
			(start 2.54 4.572)
			(end -4.572 4.572)
			(stroke
				(width 0.1778)
				(type solid)
			)
			(layer "F.SilkS")
		)
		(fp_line
			(start 2.54 -4.572)
			(end -4.572 -4.572)
			(stroke
				(width 0.1778)
				(type solid)
			)
			(layer "F.SilkS")
		)
		(fp_line
			(start -4.572 2.54)
			(end -4.572 4.572)
			(stroke
				(width 0.1778)
				(type solid)
			)
			(layer "F.SilkS")
		)
		(fp_line
			(start -4.572 -4.572)
			(end -4.572 -2.54)
			(stroke
				(width 0.1778)
				(type solid)
			)
			(layer "F.SilkS")
		)
		(pad "1" thru_hole circle
			(at 0 0 180)
			(size 2.8448 2.8448)
			(drill 1.524)
			(layers "*.Cu" "*.Mask")
			(remove_unused_layers no)
			(net "ANT3")
			(thermal_bridge_angle 90)
		)
		(pad "2" thru_hole circle
			(at -2.54 2.54 180)
			(size 3.048 3.048)
			(drill 1.7272)
			(layers "*.Cu" "*.Mask")
			(remove_unused_layers no)
			(net "GND")
			(thermal_bridge_angle 90)
		)
		(pad "3" thru_hole circle
			(at -2.54 -2.54 180)
			(size 3.048 3.048)
			(drill 1.7272)
			(layers "*.Cu" "*.Mask")
			(remove_unused_layers no)
			(net "GND")
			(thermal_bridge_angle 90)
		)
		(pad "4" thru_hole circle
			(at 2.54 -2.54 180)
			(size 3.048 3.048)
			(drill 1.7272)
			(layers "*.Cu" "*.Mask")
			(remove_unused_layers no)
			(net "GND")
			(thermal_bridge_angle 90)
		)
		(pad "5" thru_hole circle
			(at 2.54 2.54 180)
			(size 3.048 3.048)
			(drill 1.7272)
			(layers "*.Cu" "*.Mask")
			(remove_unused_layers no)
			(net "GND")
			(thermal_bridge_angle 90)
		)
	)
	(footprint "Vault:FP-BU2032SM-BT-GTR-MFG"
		(layer "F.Cu")
		(at 183.188595 74.6036 90)
		(property "Reference" "BT1"
			(at 15.498069 -6.645995 0)
			(unlocked yes)
			(layer "F.SilkS")
			(effects
				(font
					(size 0.762 0.762)
					(thickness 0.254)
				)
			)
		)
		(property "Value" "BU2032SM-BT-GTR"
			(at -19.269202 3.234885 0)
			(unlocked yes)
			(layer "F.SilkS")
			(hide yes)
			(effects
				(font
					(size 1.524 1.524)
					(thickness 0.254)
				)
			)
		)
		(sheetname "MAC")
		(sheetfile "MAC.kicad_sch")
		(duplicate_pad_numbers_are_jumpers no)
		(fp_line
			(start 14.55 -8.25)
			(end 14.55 -2.475)
			(stroke
				(width 0.2)
				(type solid)
			)
			(layer "F.SilkS")
		)
		(fp_line
			(start -14.55 -8.25)
			(end 14.55 -8.25)
			(stroke
				(width 0.2)
				(type solid)
			)
			(layer "F.SilkS")
		)
		(fp_line
			(start -14.55 -8.25)
			(end -14.55 -2.475)
			(stroke
				(width 0.2)
				(type solid)
			)
			(layer "F.SilkS")
		)
		(fp_line
			(start -17.3 -0.3)
			(end -17.3 0.3)
			(stroke
				(width 0.2)
				(type solid)
			)
			(layer "F.SilkS")
		)
		(fp_line
			(start -17.6 0)
			(end -17 0)
			(stroke
				(width 0.2)
				(type solid)
			)
			(layer "F.SilkS")
		)
		(fp_line
			(start 14.55 2.475)
			(end 14.55 8.25)
			(stroke
				(width 0.2)
				(type solid)
			)
			(layer "F.SilkS")
		)
		(fp_line
			(start -14.55 2.475)
			(end -14.55 8.25)
			(stroke
				(width 0.2)
				(type solid)
			)
			(layer "F.SilkS")
		)
		(fp_line
			(start -14.55 8.25)
			(end 14.55 8.25)
			(stroke
				(width 0.2)
				(type solid)
			)
			(layer "F.SilkS")
		)
		(fp_line
			(start 16.35 -8.35)
			(end 16.35 8.35)
			(stroke
				(width 0.2)
				(type solid)
			)
			(layer "F.CrtYd")
		)
		(fp_line
			(start -16.35 -8.35)
			(end 16.35 -8.35)
			(stroke
				(width 0.2)
				(type solid)
			)
			(layer "F.CrtYd")
		)
		(fp_line
			(start -16.35 -8.35)
			(end -16.35 8.35)
			(stroke
				(width 0.2)
				(type solid)
			)
			(layer "F.CrtYd")
		)
		(fp_line
			(start -16.35 8.35)
			(end 16.35 8.35)
			(stroke
				(width 0.2)
				(type solid)
			)
			(layer "F.CrtYd")
		)
		(fp_line
			(start 16.35 -8.35)
			(end 16.35 8.35)
			(stroke
				(width 0.2)
				(type solid)
			)
			(layer "F.Fab")
		)
		(fp_line
			(start -16.35 -8.35)
			(end 16.35 -8.35)
			(stroke
				(width 0.2)
				(type solid)
			)
			(layer "F.Fab")
		)
		(fp_line
			(start -16.35 -8.35)
			(end -16.35 8.35)
			(stroke
				(width 0.2)
				(type solid)
			)
			(layer "F.Fab")
		)
		(fp_line
			(start 0 -0.5)
			(end 0 0.5)
			(stroke
				(width 0.1)
				(type solid)
			)
			(layer "F.Fab")
		)
		(fp_line
			(start -0.5 0)
			(end 0.5 0)
			(stroke
				(width 0.1)
				(type solid)
			)
			(layer "F.Fab")
		)
		(fp_line
			(start -16.35 8.35)
			(end 16.35 8.35)
			(stroke
				(width 0.2)
				(type solid)
			)
			(layer "F.Fab")
		)
		(fp_text user "${REFERENCE}"
			(at 0 0.29535 90)
			(unlocked yes)
			(layer "F.Fab")
			(effects
				(font
					(face "Arial")
					(size 0.63 0.63)
					(thickness 0.1)
				)
				(justify left bottom)
			)
		)
		(pad "1" smd rect
			(at 14.65 0 90)
			(size 3.2 4.2)
			(layers "F.Cu" "F.Mask" "F.Paste")
			(net "GND")
			(solder_mask_margin 0)
			(solder_paste_margin 0)
		)
		(pad "2" smd rect
			(at -14.65 0 90)
			(size 3.2 4.2)
			(layers "F.Cu" "F.Mask" "F.Paste")
			(net "NetBT1_2")
			(solder_mask_margin 0)
			(solder_paste_margin 0)
		)
	)
	(footprint "Capacitors:CAPC1608X10N"
		(layer "F.Cu")
		(at 226.251595 80.2876 90)
		(property "Reference" "C85"
			(at 5.409 1.730345 90)
			(unlocked yes)
			(layer "F.SilkS")
			(effects
				(font
					(size 0.762 0.762)
					(thickness 0.2286)
				)
				(justify left bottom)
			)
		)
		(property "Value" "CAP_0603_22PF_50V"
			(at -1.03759 10.3759 0)
			(unlocked yes)
			(layer "F.SilkS")
			(hide yes)
			(effects
				(font
					(size 1.524 1.524)
					(thickness 0.254)
				)
				(justify left bottom)
			)
		)
		(sheetname "GPS_IMU_SENSORS")
		(sheetfile "GPS_IMU_SENSORS.kicad_sch")
		(duplicate_pad_numbers_are_jumpers no)
		(fp_line
			(start -0.635 -0.7112)
			(end 0.635 -0.7112)
			(stroke
				(width 0.1524)
				(type solid)
			)
			(layer "F.SilkS")
		)
		(fp_line
			(start -0.635 0.7112)
			(end 0.635 0.7112)
			(stroke
				(width 0.1524)
				(type solid)
			)
			(layer "F.SilkS")
		)
		(pad "1" smd rect
			(at -0.8 0 180)
			(size 0.95 1)
			(layers "F.Cu" "F.Mask" "F.Paste")
			(net "GND")
		)
		(pad "2" smd rect
			(at 0.8 0 180)
			(size 0.95 1)
			(layers "F.Cu" "F.Mask" "F.Paste")
			(net "NetC85_2")
		)
	)
	(footprint "Connectors:AMPHENOL-901-143-6RFX"
		(layer "F.Cu")
		(at 63.564595 97.5596 180)
		(property "Reference" "AN1"
			(at -5.24553 -4.652455 0)
			(unlocked yes)
			(layer "F.SilkS")
			(effects
				(font
					(size 0.762 0.762)
					(thickness 0.2286)
				)
				(justify left bottom)
			)
		)
		(property "Value" "RF-901-143-6FRX"
			(at 4.6101 -12.21359 0)
			(unlocked yes)
			(layer "F.SilkS")
			(hide yes)
			(effects
				(font
					(size 1.524 1.524)
					(thickness 0.254)
				)
				(justify left bottom)
			)
		)
		(sheetfile ".kicad_sch")
		(duplicate_pad_numbers_are_jumpers no)
		(fp_line
			(start 4.318 3.556)
			(end 3.302 4.572)
			(stroke
				(width 0.1778)
				(type solid)
			)
			(layer "F.SilkS")
		)
		(fp_line
			(start 4.318 -3.556)
			(end 3.302 -4.572)
			(stroke
				(width 0.1778)
				(type solid)
			)
			(layer "F.SilkS")
		)
		(fp_line
			(start 3.302 4.572)
			(end 2.54 4.572)
			(stroke
				(width 0.1778)
				(type solid)
			)
			(layer "F.SilkS")
		)
		(fp_line
			(start 3.302 -4.572)
			(end 2.54 -4.572)
			(stroke
				(width 0.1778)
				(type solid)
			)
			(layer "F.SilkS")
		)
		(fp_line
			(start 2.54 4.572)
			(end -4.572 4.572)
			(stroke
				(width 0.1778)
				(type solid)
			)
			(layer "F.SilkS")
		)
		(fp_line
			(start 2.54 -4.572)
			(end -4.572 -4.572)
			(stroke
				(width 0.1778)
				(type solid)
			)
			(layer "F.SilkS")
		)
		(fp_line
			(start -4.572 2.54)
			(end -4.572 4.572)
			(stroke
				(width 0.1778)
				(type solid)
			)
			(layer "F.SilkS")
		)
		(fp_line
			(start -4.572 -4.572)
			(end -4.572 -2.54)
			(stroke
				(width 0.1778)
				(type solid)
			)
			(layer "F.SilkS")
		)
		(pad "1" thru_hole circle
			(at 0 0 180)
			(size 2.8448 2.8448)
			(drill 1.524)
			(layers "*.Cu" "*.Mask")
			(remove_unused_layers no)
			(net "ANT1")
			(thermal_bridge_angle 90)
		)
		(pad "2" thru_hole circle
			(at -2.54 2.54 180)
			(size 3.048 3.048)
			(drill 1.7272)
			(layers "*.Cu" "*.Mask")
			(remove_unused_layers no)
			(net "GND")
			(thermal_bridge_angle 90)
		)
		(pad "3" thru_hole circle
			(at -2.54 -2.54 180)
			(size 3.048 3.048)
			(drill 1.7272)
			(layers "*.Cu" "*.Mask")
			(remove_unused_layers no)
			(net "GND")
			(thermal_bridge_angle 90)
		)
		(pad "4" thru_hole circle
			(at 2.54 -2.54 180)
			(size 3.048 3.048)
			(drill 1.7272)
			(layers "*.Cu" "*.Mask")
			(remove_unused_layers no)
			(net "GND")
			(thermal_bridge_angle 90)
		)
		(pad "5" thru_hole circle
			(at 2.54 2.54 180)
			(size 3.048 3.048)
			(drill 1.7272)
			(layers "*.Cu" "*.Mask")
			(remove_unused_layers no)
			(net "GND")
			(thermal_bridge_angle 90)
		)
	)
	(footprint "Vault:CAPC1608X87X45ML20T05"
		(layer "F.Cu")
		(at 219.588595 90.9786 180)
		(property "Reference" "C9"
			(at 4.2 -0.493345 0)
			(unlocked yes)
			(layer "F.SilkS")
			(effects
				(font
					(size 0.762 0.762)
					(thickness 0.2286)
				)
				(justify left bottom)
			)
		)
		(property "Value" "0.1uF"
			(at -10.9347 -6.32079 0)
			(unlocked yes)
			(layer "F.SilkS")
			(hide yes)
			(effects
				(font
					(size 1.524 1.524)
					(thickness 0.254)
				)
				(justify left bottom)
			)
		)
		(sheetname "POWER")
		(sheetfile "POWER.kicad_sch")
		(duplicate_pad_numbers_are_jumpers no)
		(pad "1" smd rect
			(at -0.7 0 270)
			(size 1.1 1.05)
			(layers "F.Cu" "F.Mask" "F.Paste")
			(net "GND")
		)
		(pad "2" smd rect
			(at 0.7 0 270)
			(size 1.1 1.05)
			(layers "F.Cu" "F.Mask" "F.Paste")
			(net "+3.3V")
		)
	)
	(footprint "Miscellaneous Devices:J1-0603"
		(layer "F.Cu")
		(at 82.288595 129.6786 180)
		(property "Reference" "R31"
			(at -1.6 -0.493345 0)
			(unlocked yes)
			(layer "F.SilkS")
			(effects
				(font
					(size 0.762 0.762)
					(thickness 0.2286)
				)
				(justify left bottom)
			)
		)
		(property "Value" "MAC10M"
			(at 0.4445 -3.72999 0)
			(unlocked yes)
			(layer "F.SilkS")
			(hide yes)
			(effects
				(font
					(size 1.524 1.524)
					(thickness 0.254)
				)
				(justify left bottom)
			)
		)
		(sheetname "USER_IO")
		(sheetfile "USER_IO.kicad_sch")
		(duplicate_pad_numbers_are_jumpers no)
		(fp_line
			(start 0.2 0.35)
			(end -0.2 0.35)
			(stroke
				(width 0.2)
				(type solid)
			)
			(layer "F.SilkS")
		)
		(fp_line
			(start 0.2 -0.35)
			(end -0.2 -0.35)
			(stroke
				(width 0.2)
				(type solid)
			)
			(layer "F.SilkS")
		)
		(pad "1" smd rect
			(at -0.75 0 270)
			(size 0.9 0.7)
			(layers "F.Cu" "F.Mask" "F.Paste")
			(net "MAC_10Mout")
		)
		(pad "2" smd rect
			(at 0.75 0 270)
			(size 0.9 0.7)
			(layers "F.Cu" "F.Mask" "F.Paste")
			(net "ANT3")
		)
	)
	(footprint "Vault:CAPC1608X87X45ML20T05"
		(layer "F.Cu")
		(at 127.588595 69.8786 90)
		(property "Reference" "C61"
			(at -4.8 1.893345 90)
			(unlocked yes)
			(layer "F.SilkS")
			(effects
				(font
					(size 0.762 0.762)
					(thickness 0.2286)
				)
				(justify left bottom)
			)
		)
		(property "Value" "0.1uF"
			(at -3.47599 -0.2921 0)
			(unlocked yes)
			(layer "F.SilkS")
			(hide yes)
			(effects
				(font
					(size 1.524 1.524)
					(thickness 0.254)
				)
				(justify left bottom)
			)
		)
		(sheetname "GPS_IMU_SENSORS")
		(sheetfile "GPS_IMU_SENSORS.kicad_sch")
		(duplicate_pad_numbers_are_jumpers no)
		(pad "1" smd rect
			(at -0.7 0 180)
			(size 1.1 1.05)
			(layers "F.Cu" "F.Mask" "F.Paste")
			(net "GND")
		)
		(pad "2" smd rect
			(at 0.7 0 180)
			(size 1.1 1.05)
			(layers "F.Cu" "F.Mask" "F.Paste")
			(net "+5.0V")
		)
	)
	(footprint "Connectors:AMPHENOL-901-143-6RFX"
		(layer "F.Cu")
		(at 63.564595 110.8946 180)
		(property "Reference" "AN2"
			(at -5.20749 -4.677855 0)
			(unlocked yes)
			(layer "F.SilkS")
			(effects
				(font
					(size 0.762 0.762)
					(thickness 0.2286)
				)
				(justify left bottom)
			)
		)
		(property "Value" "RF-901-143-6FRX"
			(at 4.6101 -2.05359 0)
			(unlocked yes)
			(layer "F.SilkS")
			(hide yes)
			(effects
				(font
					(size 1.524 1.524)
					(thickness 0.254)
				)
				(justify left bottom)
			)
		)
		(sheetfile ".kicad_sch")
		(duplicate_pad_numbers_are_jumpers no)
		(fp_line
			(start 4.318 3.556)
			(end 3.302 4.572)
			(stroke
				(width 0.1778)
				(type solid)
			)
			(layer "F.SilkS")
		)
		(fp_line
			(start 4.318 -3.556)
			(end 3.302 -4.572)
			(stroke
				(width 0.1778)
				(type solid)
			)
			(layer "F.SilkS")
		)
		(fp_line
			(start 3.302 4.572)
			(end 2.54 4.572)
			(stroke
				(width 0.1778)
				(type solid)
			)
			(layer "F.SilkS")
		)
		(fp_line
			(start 3.302 -4.572)
			(end 2.54 -4.572)
			(stroke
				(width 0.1778)
				(type solid)
			)
			(layer "F.SilkS")
		)
		(fp_line
			(start 2.54 4.572)
			(end -4.572 4.572)
			(stroke
				(width 0.1778)
				(type solid)
			)
			(layer "F.SilkS")
		)
		(fp_line
			(start 2.54 -4.572)
			(end -4.572 -4.572)
			(stroke
				(width 0.1778)
				(type solid)
			)
			(layer "F.SilkS")
		)
		(fp_line
			(start -4.572 2.54)
			(end -4.572 4.572)
			(stroke
				(width 0.1778)
				(type solid)
			)
			(layer "F.SilkS")
		)
		(fp_line
			(start -4.572 -4.572)
			(end -4.572 -2.54)
			(stroke
				(width 0.1778)
				(type solid)
			)
			(layer "F.SilkS")
		)
		(pad "1" thru_hole circle
			(at 0 0 180)
			(size 2.8448 2.8448)
			(drill 1.524)
			(layers "*.Cu" "*.Mask")
			(remove_unused_layers no)
			(net "ANT2")
			(thermal_bridge_angle 90)
		)
		(pad "2" thru_hole circle
			(at -2.54 2.54 180)
			(size 3.048 3.048)
			(drill 1.7272)
			(layers "*.Cu" "*.Mask")
			(remove_unused_layers no)
			(net "GND")
			(thermal_bridge_angle 90)
		)
		(pad "3" thru_hole circle
			(at -2.54 -2.54 180)
			(size 3.048 3.048)
			(drill 1.7272)
			(layers "*.Cu" "*.Mask")
			(remove_unused_layers no)
			(net "GND")
			(thermal_bridge_angle 90)
		)
		(pad "4" thru_hole circle
			(at 2.54 -2.54 180)
			(size 3.048 3.048)
			(drill 1.7272)
			(layers "*.Cu" "*.Mask")
			(remove_unused_layers no)
			(net "GND")
			(thermal_bridge_angle 90)
		)
		(pad "5" thru_hole circle
			(at 2.54 2.54 180)
			(size 3.048 3.048)
			(drill 1.7272)
			(layers "*.Cu" "*.Mask")
			(remove_unused_layers no)
			(net "GND")
			(thermal_bridge_angle 90)
		)
	)
	(footprint "Vault:CAPC1608X87X45ML20T05"
		(layer "F.Cu")
		(at 219.588595 96.1786 180)
		(property "Reference" "C10"
			(at 4.1 1.006655 0)
			(unlocked yes)
			(layer "F.SilkS")
			(effects
				(font
					(size 0.762 0.762)
					(thickness 0.2286)
				)
				(justify left bottom)
			)
		)
		(property "Value" "0.1uF"
			(at -9.9949 -0.30099 0)
			(unlocked yes)
			(layer "F.SilkS")
			(hide yes)
			(effects
				(font
					(size 1.524 1.524)
					(thickness 0.254)
				)
				(justify left bottom)
			)
		)
		(sheetname "POWER")
		(sheetfile "POWER.kicad_sch")
		(duplicate_pad_numbers_are_jumpers no)
		(pad "1" smd rect
			(at -0.7 0 270)
			(size 1.1 1.05)
			(layers "F.Cu" "F.Mask" "F.Paste")
			(net "GND")
		)
		(pad "2" smd rect
			(at 0.7 0 270)
			(size 1.1 1.05)
			(layers "F.Cu" "F.Mask" "F.Paste")
			(net "+3.3V")
		)
	)
	(footprint "Capacitors:CAPC2012X14N"
		(layer "B.Cu")
		(at 118.504795 85.7994)
		(property "Reference" "C87"
			(at -2.1412 0.622545 0)
			(unlocked yes)
			(layer "B.SilkS")
			(effects
				(font
					(size 0.762 0.762)
					(thickness 0.254)
				)
				(justify left bottom mirror)
			)
		)
		(property "Value" "CAP_0805_10UF_25V"
			(at 1.5875 3.52679 0)
			(unlocked yes)
			(layer "B.SilkS")
			(hide yes)
			(effects
				(font
					(size 1.524 1.524)
					(thickness 0.254)
				)
				(justify left bottom mirror)
			)
		)
		(sheetname "GPS_IMU_SENSORS")
		(sheetfile "GPS_IMU_SENSORS.kicad_sch")
		(duplicate_pad_numbers_are_jumpers no)
		(fp_line
			(start -0.762 -0.9652)
			(end 0.762 -0.9652)
			(stroke
				(width 0.1524)
				(type solid)
			)
			(layer "B.SilkS")
		)
		(fp_line
			(start -0.762 0.9652)
			(end 0.762 0.9652)
			(stroke
				(width 0.1524)
				(type solid)
			)
			(layer "B.SilkS")
		)
		(pad "1" smd rect
			(at -0.9 0 270)
			(size 1.45 1.15)
			(layers "B.Cu" "B.Mask" "B.Paste")
			(net "+3.3V")
		)
		(pad "2" smd rect
			(at 0.9 0 270)
			(size 1.45 1.15)
			(layers "B.Cu" "B.Mask" "B.Paste")
			(net "GND")
		)
	)
	(footprint "Vault:CAPC1608X87X45ML20T05"
		(layer "B.Cu")
		(at 118.657195 88.0854 180)
		(property "Reference" "C88"
			(at 2.2686 -0.586545 0)
			(unlocked yes)
			(layer "B.SilkS")
			(effects
				(font
					(size 0.762 0.762)
					(thickness 0.254)
				)
				(justify left bottom mirror)
			)
		)
		(property "Value" "0.1uF"
			(at -3.47599 0.2921 90)
			(unlocked yes)
			(layer "B.SilkS")
			(hide yes)
			(effects
				(font
					(size 1.524 1.524)
					(thickness 0.254)
				)
				(justify left bottom mirror)
			)
		)
		(sheetname "GPS_IMU_SENSORS")
		(sheetfile "GPS_IMU_SENSORS.kicad_sch")
		(duplicate_pad_numbers_are_jumpers no)
		(pad "1" smd rect
			(at -0.7 0 90)
			(size 1.1 1.05)
			(layers "B.Cu" "B.Mask" "B.Paste")
			(net "GND")
		)
		(pad "2" smd rect
			(at 0.7 0 90)
			(size 1.1 1.05)
			(layers "B.Cu" "B.Mask" "B.Paste")
			(net "+3.3V")
		)
	)
	(footprint "Capacitors:CAPC1005X06N"
		(layer "B.Cu")
		(at 134.176595 151.7886 90)
		(property "Reference" "C52"
			(at 2.41349 -0.613855 270)
			(unlocked yes)
			(layer "B.SilkS")
			(effects
				(font
					(size 0.762 0.762)
					(thickness 0.254)
				)
				(justify left bottom mirror)
			)
		)
		(property "Value" "CAP_0402_0.1UF_50V"
			(at -3.47599 0.2921 0)
			(unlocked yes)
			(layer "B.SilkS")
			(hide yes)
			(effects
				(font
					(size 1.524 1.524)
					(thickness 0.254)
				)
				(justify left bottom mirror)
			)
		)
		(sheetname "PCIe_JTAG")
		(sheetfile "PCIe_JTAG.kicad_sch")
		(duplicate_pad_numbers_are_jumpers no)
		(pad "1" smd rect
			(at -0.43 0)
			(size 0.64 0.68)
			(layers "B.Cu" "B.Mask" "B.Paste")
			(net "NetC52_1")
		)
		(pad "2" smd rect
			(at 0.43 0)
			(size 0.64 0.68)
			(layers "B.Cu" "B.Mask" "B.Paste")
			(net "PCIE_TX3_P")
		)
	)
	(footprint "Capacitors:CAPC1005X06N"
		(layer "B.Cu")
		(at 126.175595 151.7886 90)
		(property "Reference" "C48"
			(at 2.41349 -0.867855 270)
			(unlocked yes)
			(layer "B.SilkS")
			(effects
				(font
					(size 0.762 0.762)
					(thickness 0.254)
				)
				(justify left bottom mirror)
			)
		)
		(property "Value" "CAP_0402_0.1UF_50V"
			(at -3.47599 0.2921 0)
			(unlocked yes)
			(layer "B.SilkS")
			(hide yes)
			(effects
				(font
					(size 1.524 1.524)
					(thickness 0.254)
				)
				(justify left bottom mirror)
			)
		)
		(sheetname "PCIe_JTAG")
		(sheetfile "PCIe_JTAG.kicad_sch")
		(duplicate_pad_numbers_are_jumpers no)
		(pad "1" smd rect
			(at -0.43 0)
			(size 0.64 0.68)
			(layers "B.Cu" "B.Mask" "B.Paste")
			(net "NetC48_1")
		)
		(pad "2" smd rect
			(at 0.43 0)
			(size 0.64 0.68)
			(layers "B.Cu" "B.Mask" "B.Paste")
			(net "PCIE_TX1_P")
		)
	)
	(footprint "Modules:RCB-F9T"
		(layer "B.Cu")
		(at 126.126095 59.8204 -90)
		(property "Reference" "U14"
			(at -0.800855 0.1283 0)
			(unlocked yes)
			(layer "B.SilkS")
			(effects
				(font
					(size 0.762 0.762)
					(thickness 0.254)
				)
				(justify left bottom mirror)
			)
		)
		(property "Value" "RCB-F9T"
			(at 28.38949 -9.0232 0)
			(unlocked yes)
			(layer "B.SilkS")
			(hide yes)
			(effects
				(font
					(size 1.524 1.524)
					(thickness 0.254)
				)
				(justify left bottom mirror)
			)
		)
		(sheetname "GPS_IMU_SENSORS")
		(sheetfile "GPS_IMU_SENSORS.kicad_sch")
		(duplicate_pad_numbers_are_jumpers no)
		(fp_line
			(start 0 67.18)
			(end 0 0)
			(stroke
				(width 0.254)
				(type solid)
			)
			(layer "B.SilkS")
		)
		(fp_line
			(start 31.75 67.18)
			(end 0 67.18)
			(stroke
				(width 0.254)
				(type solid)
			)
			(layer "B.SilkS")
		)
		(fp_line
			(start 31.75 67.18)
			(end 31.75 0)
			(stroke
				(width 0.254)
				(type solid)
			)
			(layer "B.SilkS")
		)
		(fp_line
			(start 31.75 0)
			(end 0 0)
			(stroke
				(width 0.254)
				(type solid)
			)
			(layer "B.SilkS")
		)
		(fp_circle
			(center 28.875 63.84)
			(end 27.325 63.84)
			(stroke
				(width 0.254)
				(type solid)
			)
			(fill no)
			(layer "B.SilkS")
		)
		(fp_circle
			(center 2.875 3.34)
			(end 1.325 3.34)
			(stroke
				(width 0.254)
				(type solid)
			)
			(fill no)
			(layer "B.SilkS")
		)
		(fp_circle
			(center 28.875 3.34)
			(end 27.325 3.34)
			(stroke
				(width 0.254)
				(type solid)
			)
			(fill no)
			(layer "B.SilkS")
		)
		(pad "0" thru_hole circle
			(at 18.47 6.11 270)
			(size 0 0)
			(drill 0.76)
			(layers "*.Cu" "*.Mask")
			(remove_unused_layers no)
			(thermal_bridge_angle 90)
		)
		(pad "0" thru_hole circle
			(at 22.47 6.11 270)
			(size 0 0)
			(drill 0.76)
			(layers "*.Cu" "*.Mask")
			(remove_unused_layers no)
			(thermal_bridge_angle 90)
		)
		(pad "1" smd rect
			(at 23.47 3.8875 270)
			(size 1.12 2.105)
			(layers "B.Cu" "B.Mask" "B.Paste")
			(net "+5.0V")
		)
		(pad "2" smd rect
			(at 23.47 8.3325 270)
			(size 1.12 2.105)
			(layers "B.Cu" "B.Mask" "B.Paste")
			(net "+3.3V")
		)
		(pad "3" smd rect
			(at 21.47 3.8875 270)
			(size 1.12 2.105)
			(layers "B.Cu" "B.Mask" "B.Paste")
			(net "GPS2_TX")
		)
		(pad "4" smd rect
			(at 21.47 8.3325 270)
			(size 1.12 2.105)
			(layers "B.Cu" "B.Mask" "B.Paste")
			(net "GPS2_RST")
		)
		(pad "5" smd rect
			(at 19.47 3.8875 270)
			(size 1.12 2.105)
			(layers "B.Cu" "B.Mask" "B.Paste")
			(net "GPS2_RX")
		)
		(pad "6" smd rect
			(at 19.47 8.3325 270)
			(size 1.12 2.105)
			(layers "B.Cu" "B.Mask" "B.Paste")
			(net "GPS2_TP1")
		)
		(pad "7" smd rect
			(at 17.47 3.8875 270)
			(size 1.12 2.105)
			(layers "B.Cu" "B.Mask" "B.Paste")
			(net "GPS2_TP2")
		)
		(pad "8" smd rect
			(at 17.47 8.3325 270)
			(size 1.12 2.105)
			(layers "B.Cu" "B.Mask" "B.Paste")
			(net "GND")
		)
	)
	(footprint "Capacitors:CAPC2012X14N"
		(layer "B.Cu")
		(at 125.362795 84.1992 -90)
		(property "Reference" "C89"
			(at -1.8706 0.817545 270)
			(unlocked yes)
			(layer "B.SilkS")
			(effects
				(font
					(size 0.762 0.762)
					(thickness 0.254)
				)
				(justify left bottom mirror)
			)
		)
		(property "Value" "CAP_0805_10UF_25V"
			(at 3.52679 -1.5875 0)
			(unlocked yes)
			(layer "B.SilkS")
			(hide yes)
			(effects
				(font
					(size 1.524 1.524)
					(thickness 0.254)
				)
				(justify left bottom mirror)
			)
		)
		(sheetname "GPS_IMU_SENSORS")
		(sheetfile "GPS_IMU_SENSORS.kicad_sch")
		(duplicate_pad_numbers_are_jumpers no)
		(fp_line
			(start 0.762 0.9652)
			(end -0.762 0.9652)
			(stroke
				(width 0.1524)
				(type solid)
			)
			(layer "B.SilkS")
		)
		(fp_line
			(start 0.762 -0.9652)
			(end -0.762 -0.9652)
			(stroke
				(width 0.1524)
				(type solid)
			)
			(layer "B.SilkS")
		)
		(pad "1" smd rect
			(at -0.9 0 180)
			(size 1.45 1.15)
			(layers "B.Cu" "B.Mask" "B.Paste")
			(net "+5.0V")
		)
		(pad "2" smd rect
			(at 0.9 0 180)
			(size 1.45 1.15)
			(layers "B.Cu" "B.Mask" "B.Paste")
			(net "GND")
		)
	)
	(footprint "Capacitors:CAPC1005X06N"
		(layer "B.Cu")
		(at 130.112595 151.7886 90)
		(property "Reference" "C50"
			(at 2.41349 -0.766255 270)
			(unlocked yes)
			(layer "B.SilkS")
			(effects
				(font
					(size 0.762 0.762)
					(thickness 0.254)
				)
				(justify left bottom mirror)
			)
		)
		(property "Value" "CAP_0402_0.1UF_50V"
			(at -3.47599 0.2921 0)
			(unlocked yes)
			(layer "B.SilkS")
			(hide yes)
			(effects
				(font
					(size 1.524 1.524)
					(thickness 0.254)
				)
				(justify left bottom mirror)
			)
		)
		(sheetname "PCIe_JTAG")
		(sheetfile "PCIe_JTAG.kicad_sch")
		(duplicate_pad_numbers_are_jumpers no)
		(pad "1" smd rect
			(at -0.43 0)
			(size 0.64 0.68)
			(layers "B.Cu" "B.Mask" "B.Paste")
			(net "NetC50_1")
		)
		(pad "2" smd rect
			(at 0.43 0)
			(size 0.64 0.68)
			(layers "B.Cu" "B.Mask" "B.Paste")
			(net "PCIE_TX2_P")
		)
	)
	(footprint "Capacitors:CAPC1005X06N"
		(layer "B.Cu")
		(at 127.191595 151.7886 90)
		(property "Reference" "C49"
			(at 2.41349 -0.156655 270)
			(unlocked yes)
			(layer "B.SilkS")
			(effects
				(font
					(size 0.762 0.762)
					(thickness 0.254)
				)
				(justify left bottom mirror)
			)
		)
		(property "Value" "CAP_0402_0.1UF_50V"
			(at -3.47599 0.2921 0)
			(unlocked yes)
			(layer "B.SilkS")
			(hide yes)
			(effects
				(font
					(size 1.524 1.524)
					(thickness 0.254)
				)
				(justify left bottom mirror)
			)
		)
		(sheetname "PCIe_JTAG")
		(sheetfile "PCIe_JTAG.kicad_sch")
		(duplicate_pad_numbers_are_jumpers no)
		(pad "1" smd rect
			(at -0.43 0)
			(size 0.64 0.68)
			(layers "B.Cu" "B.Mask" "B.Paste")
			(net "NetC49_1")
		)
		(pad "2" smd rect
			(at 0.43 0)
			(size 0.64 0.68)
			(layers "B.Cu" "B.Mask" "B.Paste")
			(net "PCIE_TX1_N")
		)
	)
	(footprint "Vault:CAPC1608X87X45ML20T05"
		(layer "B.Cu")
		(at 127.388595 83.9786 90)
		(property "Reference" "C90"
			(at -3.7 -0.493345 270)
			(unlocked yes)
			(layer "B.SilkS")
			(effects
				(font
					(size 0.762 0.762)
					(thickness 0.254)
				)
				(justify left bottom mirror)
			)
		)
		(property "Value" "0.1uF"
			(at -3.47599 0.2921 0)
			(unlocked yes)
			(layer "B.SilkS")
			(hide yes)
			(effects
				(font
					(size 1.524 1.524)
					(thickness 0.254)
				)
				(justify left bottom mirror)
			)
		)
		(sheetname "GPS_IMU_SENSORS")
		(sheetfile "GPS_IMU_SENSORS.kicad_sch")
		(duplicate_pad_numbers_are_jumpers no)
		(pad "1" smd rect
			(at -0.7 0)
			(size 1.1 1.05)
			(layers "B.Cu" "B.Mask" "B.Paste")
			(net "GND")
		)
		(pad "2" smd rect
			(at 0.7 0)
			(size 1.1 1.05)
			(layers "B.Cu" "B.Mask" "B.Paste")
			(net "+5.0V")
		)
	)
	(footprint "Capacitors:CAPC1005X06N"
		(layer "B.Cu")
		(at 135.192595 151.7886 90)
		(property "Reference" "C53"
			(at 2.41349 0.046545 270)
			(unlocked yes)
			(layer "B.SilkS")
			(effects
				(font
					(size 0.762 0.762)
					(thickness 0.254)
				)
				(justify left bottom mirror)
			)
		)
		(property "Value" "CAP_0402_0.1UF_50V"
			(at -3.47599 0.2921 0)
			(unlocked yes)
			(layer "B.SilkS")
			(hide yes)
			(effects
				(font
					(size 1.524 1.524)
					(thickness 0.254)
				)
				(justify left bottom mirror)
			)
		)
		(sheetname "PCIe_JTAG")
		(sheetfile "PCIe_JTAG.kicad_sch")
		(duplicate_pad_numbers_are_jumpers no)
		(pad "1" smd rect
			(at -0.43 0)
			(size 0.64 0.68)
			(layers "B.Cu" "B.Mask" "B.Paste")
			(net "NetC53_1")
		)
		(pad "2" smd rect
			(at 0.43 0)
			(size 0.64 0.68)
			(layers "B.Cu" "B.Mask" "B.Paste")
			(net "PCIE_TX3_N")
		)
	)
	(footprint "Capacitors:CAPC1005X06N"
		(layer "B.Cu")
		(at 121.197195 151.7886 90)
		(property "Reference" "C46"
			(at 2.41349 -0.563055 270)
			(unlocked yes)
			(layer "B.SilkS")
			(effects
				(font
					(size 0.762 0.762)
					(thickness 0.254)
				)
				(justify left bottom mirror)
			)
		)
		(property "Value" "CAP_0402_0.1UF_50V"
			(at -3.47599 0.2921 0)
			(unlocked yes)
			(layer "B.SilkS")
			(hide yes)
			(effects
				(font
					(size 1.524 1.524)
					(thickness 0.254)
				)
				(justify left bottom mirror)
			)
		)
		(sheetname "PCIe_JTAG")
		(sheetfile "PCIe_JTAG.kicad_sch")
		(duplicate_pad_numbers_are_jumpers no)
		(pad "1" smd rect
			(at -0.43 0)
			(size 0.64 0.68)
			(layers "B.Cu" "B.Mask" "B.Paste")
			(net "NetC46_1")
		)
		(pad "2" smd rect
			(at 0.43 0)
			(size 0.64 0.68)
			(layers "B.Cu" "B.Mask" "B.Paste")
			(net "PCIE_TX0_P")
		)
	)
	(footprint "Capacitors:CAPC1005X06N"
		(layer "B.Cu")
		(at 131.001595 151.7886 90)
		(property "Reference" "C51"
			(at 2.41349 0.148145 270)
			(unlocked yes)
			(layer "B.SilkS")
			(effects
				(font
					(size 0.762 0.762)
					(thickness 0.254)
				)
				(justify left bottom mirror)
			)
		)
		(property "Value" "CAP_0402_0.1UF_50V"
			(at -3.47599 0.2921 0)
			(unlocked yes)
			(layer "B.SilkS")
			(hide yes)
			(effects
				(font
					(size 1.524 1.524)
					(thickness 0.254)
				)
				(justify left bottom mirror)
			)
		)
		(sheetname "PCIe_JTAG")
		(sheetfile "PCIe_JTAG.kicad_sch")
		(duplicate_pad_numbers_are_jumpers no)
		(pad "1" smd rect
			(at -0.43 0)
			(size 0.64 0.68)
			(layers "B.Cu" "B.Mask" "B.Paste")
			(net "NetC51_1")
		)
		(pad "2" smd rect
			(at 0.43 0)
			(size 0.64 0.68)
			(layers "B.Cu" "B.Mask" "B.Paste")
			(net "PCIE_TX2_N")
		)
	)
	(footprint "Capacitors:CAPC1005X06N"
		(layer "B.Cu")
		(at 122.289395 151.7886 90)
		(property "Reference" "C47"
			(at 2.41349 0.097345 270)
			(unlocked yes)
			(layer "B.SilkS")
			(effects
				(font
					(size 0.762 0.762)
					(thickness 0.254)
				)
				(justify left bottom mirror)
			)
		)
		(property "Value" "CAP_0402_0.1UF_50V"
			(at -3.47599 0.2921 0)
			(unlocked yes)
			(layer "B.SilkS")
			(hide yes)
			(effects
				(font
					(size 1.524 1.524)
					(thickness 0.254)
				)
				(justify left bottom mirror)
			)
		)
		(sheetname "PCIe_JTAG")
		(sheetfile "PCIe_JTAG.kicad_sch")
		(duplicate_pad_numbers_are_jumpers no)
		(pad "1" smd rect
			(at -0.43 0)
			(size 0.64 0.68)
			(layers "B.Cu" "B.Mask" "B.Paste")
			(net "NetC47_1")
		)
		(pad "2" smd rect
			(at 0.43 0)
			(size 0.64 0.68)
			(layers "B.Cu" "B.Mask" "B.Paste")
			(net "PCIE_TX0_N")
		)
	)
	(footprint "Capacitors:CAPC1005X06N"
		(layer "B.Cu")
		(at 118.174595 151.7886 90)
		(property "Reference" "C44"
			(at 2.885 -1.204345 270)
			(unlocked yes)
			(layer "B.SilkS")
			(effects
				(font
					(size 0.762 0.762)
					(thickness 0.254)
				)
				(justify left bottom mirror)
			)
		)
		(property "Value" "CAP_0402_0.1UF_50V"
			(at -3.47599 0.2921 0)
			(unlocked yes)
			(layer "B.SilkS")
			(hide yes)
			(effects
				(font
					(size 1.524 1.524)
					(thickness 0.254)
				)
				(justify left bottom mirror)
			)
		)
		(sheetname "PCIe_JTAG")
		(sheetfile "PCIe_JTAG.kicad_sch")
		(duplicate_pad_numbers_are_jumpers no)
		(pad "1" smd rect
			(at -0.43 0)
			(size 0.64 0.68)
			(layers "B.Cu" "B.Mask" "B.Paste")
			(net "NetC44_1")
		)
		(pad "2" smd rect
			(at 0.43 0)
			(size 0.64 0.68)
			(layers "B.Cu" "B.Mask" "B.Paste")
			(net "PCIE_CLK_P")
		)
	)
	(footprint "Capacitors:CAPC1005X06N"
		(layer "B.Cu")
		(at 119.190595 151.7886 90)
		(property "Reference" "C45"
			(at 2.835 -0.445345 270)
			(unlocked yes)
			(layer "B.SilkS")
			(effects
				(font
					(size 0.762 0.762)
					(thickness 0.254)
				)
				(justify left bottom mirror)
			)
		)
		(property "Value" "CAP_0402_0.1UF_50V"
			(at -3.47599 0.2921 0)
			(unlocked yes)
			(layer "B.SilkS")
			(hide yes)
			(effects
				(font
					(size 1.524 1.524)
					(thickness 0.254)
				)
				(justify left bottom mirror)
			)
		)
		(sheetname "PCIe_JTAG")
		(sheetfile "PCIe_JTAG.kicad_sch")
		(duplicate_pad_numbers_are_jumpers no)
		(pad "1" smd rect
			(at -0.43 0)
			(size 0.64 0.68)
			(layers "B.Cu" "B.Mask" "B.Paste")
			(net "NetC45_1")
		)
		(pad "2" smd rect
			(at 0.43 0)
			(size 0.64 0.68)
			(layers "B.Cu" "B.Mask" "B.Paste")
			(net "PCIE_CLK_N")
		)
	)
	(gr_poly
		(pts
			(xy 221.308615 137.9755) (xy 221.308615 137.98923) (xy 221.308615 138.00296) (xy 221.308615 138.0167)
			(xy 221.308615 138.03043) (xy 221.308615 138.04416) (xy 221.308615 138.05789) (xy 221.308615 138.07162)
			(xy 221.308615 138.08536) (xy 221.308615 138.09909) (xy 221.308615 138.11282) (xy 221.308615 138.12655)
			(xy 221.308615 138.14028) (xy 221.308615 138.15401) (xy 221.308615 138.16775) (xy 221.308615 138.18148)
			(xy 221.308615 138.19521) (xy 221.308615 138.20894) (xy 221.308615 138.22267) (xy 221.308615 138.2364)
			(xy 221.308615 138.25014) (xy 221.308615 138.26387) (xy 221.308615 138.2776) (xy 221.308615 138.29133)
			(xy 221.308615 138.30506) (xy 221.308615 138.31879) (xy 221.308615 138.33253) (xy 221.308615 138.34626)
			(xy 221.308615 138.35999) (xy 221.308615 138.37372) (xy 221.308615 138.38745) (xy 221.308615 138.40118)
			(xy 221.308615 138.41492) (xy 221.308615 138.42865) (xy 221.308615 138.44238) (xy 221.308615 138.45611)
			(xy 221.308615 138.46984) (xy 221.308615 138.48358) (xy 221.308615 138.49731) (xy 221.308615 138.51104)
			(xy 221.308615 138.52477) (xy 221.308615 138.5385) (xy 221.308615 138.55224) (xy 221.308615 138.56597)
			(xy 221.308615 138.5797) (xy 221.308615 138.59343) (xy 221.308615 138.60716) (xy 221.308615 138.62089)
			(xy 221.308615 138.63463) (xy 221.308615 138.64836) (xy 221.308615 138.66209) (xy 221.308615 138.67582)
			(xy 221.308615 138.68955) (xy 220.278735 138.68955) (xy 220.278735 138.67582) (xy 220.278735 138.66209)
			(xy 220.278735 138.64836) (xy 220.278735 138.63463) (xy 220.278735 138.62089) (xy 220.278735 138.60716)
			(xy 220.278735 138.59343) (xy 220.278735 138.5797) (xy 220.278735 138.56597) (xy 220.278735 138.55224)
			(xy 220.278735 138.5385) (xy 220.278735 138.52477) (xy 220.278735 138.51104) (xy 220.278735 138.49731)
			(xy 220.278735 138.48358) (xy 220.278735 138.46984) (xy 220.278735 138.45611) (xy 220.278735 138.44238)
			(xy 220.278735 138.42865) (xy 220.278735 138.41492) (xy 220.278735 138.40118) (xy 220.278735 138.38745)
			(xy 220.278735 138.37372) (xy 220.278735 138.35999) (xy 220.278735 138.34626) (xy 220.278735 138.33253)
			(xy 220.278735 138.31879) (xy 220.278735 138.30506) (xy 220.278735 138.29133) (xy 220.278735 138.2776)
			(xy 220.278735 138.26387) (xy 220.278735 138.25014) (xy 220.278735 138.2364) (xy 220.278735 138.22267)
			(xy 220.278735 138.20894) (xy 220.278735 138.19521) (xy 220.278735 138.18148) (xy 220.278735 138.16775)
			(xy 220.278735 138.15401) (xy 220.278735 138.14028) (xy 220.278735 138.12655) (xy 220.278735 138.11282)
			(xy 220.278735 138.09909) (xy 220.278735 138.08536) (xy 220.278735 138.07162) (xy 220.278735 138.05789)
			(xy 220.278735 138.04416) (xy 220.278735 138.03043) (xy 220.278735 138.0167) (xy 220.278735 138.00296)
			(xy 220.278735 137.98923) (xy 220.278735 137.9755) (xy 220.278735 137.96177) (xy 221.308615 137.96177)
		)
		(stroke
			(width 0)
			(type default)
		)
		(fill yes)
		(layer "F.Cu")
	)
	(gr_poly
		(pts
			(xy 210.213365 141.9989) (xy 210.268295 141.9989) (xy 210.268295 142.01263) (xy 210.295755 142.01263)
			(xy 210.295755 142.02637) (xy 210.323215 142.02637) (xy 210.323215 142.0401) (xy 210.350685 142.0401)
			(xy 210.350685 142.05383) (xy 210.378145 142.05383) (xy 210.378145 142.06756) (xy 210.391875 142.06756)
			(xy 210.391875 142.08129) (xy 210.419345 142.08129) (xy 210.419345 142.09502) (xy 210.433075 142.09502)
			(xy 210.433075 142.10876) (xy 210.446805 142.10876) (xy 210.446805 142.12249) (xy 210.460535 142.12249)
			(xy 210.460535 142.13622) (xy 210.474265 142.13622) (xy 210.474265 142.14995) (xy 210.487995 142.14995)
			(xy 210.487995 142.16368) (xy 210.501735 142.16368) (xy 210.501735 142.17742) (xy 210.515465 142.17742)
			(xy 210.515465 142.19115) (xy 210.515465 142.20488) (xy 210.529195 142.20488) (xy 210.529195 142.21861)
			(xy 210.542925 142.21861) (xy 210.542925 142.23234) (xy 210.542925 142.24608) (xy 210.556655 142.24608)
			(xy 210.556655 142.25981) (xy 210.556655 142.27354) (xy 210.570385 142.27354) (xy 210.570385 142.28727)
			(xy 210.570385 142.301) (xy 210.584125 142.301) (xy 210.584125 142.31473) (xy 210.584125 142.32847)
			(xy 210.584125 142.3422) (xy 210.597855 142.3422) (xy 210.597855 142.35593) (xy 210.597855 142.36966)
			(xy 210.597855 142.38339) (xy 210.597855 142.39712) (xy 210.597855 142.41086) (xy 210.611585 142.41086)
			(xy 210.611585 142.42459) (xy 210.611585 142.43832) (xy 210.611585 142.45205) (xy 210.611585 142.46578)
			(xy 210.611585 142.47951) (xy 210.611585 142.49325) (xy 210.611585 142.50698) (xy 210.611585 142.52071)
			(xy 210.611585 142.53444) (xy 210.611585 142.54817) (xy 210.611585 142.5619) (xy 210.611585 142.57564)
			(xy 210.597855 142.57564) (xy 210.597855 142.58937) (xy 210.597855 142.6031) (xy 210.597855 142.61683)
			(xy 210.597855 142.63056) (xy 210.597855 142.64429) (xy 210.584125 142.64429) (xy 210.584125 142.65803)
			(xy 210.584125 142.67176) (xy 210.584125 142.68549) (xy 210.570385 142.68549) (xy 210.570385 142.69922)
			(xy 210.570385 142.71295) (xy 210.556655 142.71295) (xy 210.556655 142.72669) (xy 210.556655 142.74042)
			(xy 210.542925 142.74042) (xy 210.542925 142.75415) (xy 210.542925 142.76788) (xy 210.529195 142.76788)
			(xy 210.529195 142.78161) (xy 210.515465 142.78161) (xy 210.515465 142.79535) (xy 210.515465 142.80908)
			(xy 210.501735 142.80908) (xy 210.501735 142.82281) (xy 210.487995 142.82281) (xy 210.487995 142.83654)
			(xy 210.474265 142.83654) (xy 210.474265 142.85027) (xy 210.460535 142.85027) (xy 210.460535 142.864)
			(xy 210.446805 142.864) (xy 210.446805 142.87774) (xy 210.433075 142.87774) (xy 210.433075 142.89147)
			(xy 210.419345 142.89147) (xy 210.419345 142.9052) (xy 210.391875 142.9052) (xy 210.391875 142.91893)
			(xy 210.378145 142.91893) (xy 210.378145 142.93266) (xy 210.350685 142.93266) (xy 210.350685 142.94639)
			(xy 210.323215 142.94639) (xy 210.323215 142.96013) (xy 210.295755 142.96013) (xy 210.295755 142.97386)
			(xy 210.254565 142.97386) (xy 210.254565 142.98759) (xy 210.213365 142.98759) (xy 210.213365 143.00132)
			(xy 209.979925 143.00132) (xy 209.979925 142.98759) (xy 209.938725 142.98759) (xy 209.938725 142.97386)
			(xy 209.897535 142.97386) (xy 209.897535 142.96013) (xy 209.870075 142.96013) (xy 209.870075 142.94639)
			(xy 209.842605 142.94639) (xy 209.842605 142.93266) (xy 209.815145 142.93266) (xy 209.815145 142.91893)
			(xy 209.801415 142.91893) (xy 209.801415 142.9052) (xy 209.787685 142.9052) (xy 209.787685 142.89147)
			(xy 209.760215 142.89147) (xy 209.760215 142.87774) (xy 209.746485 142.87774) (xy 209.746485 142.864)
			(xy 209.732755 142.864) (xy 209.732755 142.85027) (xy 209.719025 142.85027) (xy 209.719025 142.83654)
			(xy 209.705285 142.83654) (xy 209.705285 142.82281) (xy 209.691555 142.82281) (xy 209.691555 142.80908)
			(xy 209.691555 142.79535) (xy 209.677825 142.79535) (xy 209.677825 142.78161) (xy 209.664095 142.78161)
			(xy 209.664095 142.76788) (xy 209.664095 142.75415) (xy 209.650365 142.75415) (xy 209.650365 142.74042)
			(xy 209.650365 142.72669) (xy 209.636635 142.72669) (xy 209.636635 142.71295) (xy 209.636635 142.69922)
			(xy 209.622895 142.69922) (xy 209.622895 142.68549) (xy 209.622895 142.67176) (xy 209.609165 142.67176)
			(xy 209.609165 142.65803) (xy 209.609165 142.64429) (xy 209.609165 142.63056) (xy 209.595435 142.63056)
			(xy 209.595435 142.61683) (xy 209.595435 142.6031) (xy 209.595435 142.58937) (xy 209.595435 142.57564)
			(xy 209.595435 142.5619) (xy 209.581705 142.5619) (xy 209.581705 142.54817) (xy 209.581705 142.53444)
			(xy 209.581705 142.52071) (xy 209.581705 142.50698) (xy 209.581705 142.49325) (xy 209.581705 142.47951)
			(xy 209.581705 142.46578) (xy 209.581705 142.45205) (xy 209.581705 142.43832) (xy 209.581705 142.42459)
			(xy 209.595435 142.42459) (xy 209.595435 142.41086) (xy 209.595435 142.39712) (xy 209.595435 142.38339)
			(xy 209.595435 142.36966) (xy 209.595435 142.35593) (xy 209.609165 142.35593) (xy 209.609165 142.3422)
			(xy 209.609165 142.32847) (xy 209.609165 142.31473) (xy 209.622895 142.31473) (xy 209.622895 142.301)
			(xy 209.622895 142.28727) (xy 209.636635 142.28727) (xy 209.636635 142.27354) (xy 209.636635 142.25981)
			(xy 209.650365 142.25981) (xy 209.650365 142.24608) (xy 209.650365 142.23234) (xy 209.664095 142.23234)
			(xy 209.664095 142.21861) (xy 209.664095 142.20488) (xy 209.677825 142.20488) (xy 209.677825 142.19115)
			(xy 209.691555 142.19115) (xy 209.691555 142.17742) (xy 209.691555 142.16368) (xy 209.705285 142.16368)
			(xy 209.705285 142.14995) (xy 209.719025 142.14995) (xy 209.719025 142.13622) (xy 209.732755 142.13622)
			(xy 209.732755 142.12249) (xy 209.746485 142.12249) (xy 209.746485 142.10876) (xy 209.760215 142.10876)
			(xy 209.760215 142.09502) (xy 209.773945 142.09502) (xy 209.773945 142.08129) (xy 209.801415 142.08129)
			(xy 209.801415 142.06756) (xy 209.815145 142.06756) (xy 209.815145 142.05383) (xy 209.842605 142.05383)
			(xy 209.842605 142.0401) (xy 209.870075 142.0401) (xy 209.870075 142.02637) (xy 209.897535 142.02637)
			(xy 209.897535 142.01263) (xy 209.938725 142.01263) (xy 209.938725 141.9989) (xy 209.979925 141.9989)
			(xy 209.979925 141.98517) (xy 210.213365 141.98517)
		)
		(stroke
			(width 0)
			(type default)
		)
		(fill yes)
		(layer "F.Cu")
	)
	(gr_poly
		(pts
			(xy 224.206015 138.00296) (xy 224.233485 138.00296) (xy 224.233485 138.0167) (xy 224.233485 138.03043)
			(xy 224.233485 138.04416) (xy 224.233485 138.05789) (xy 224.233485 138.07162) (xy 224.233485 138.08536)
			(xy 224.233485 138.09909) (xy 224.233485 138.11282) (xy 224.233485 138.12655) (xy 224.233485 138.14028)
			(xy 224.233485 138.15401) (xy 224.233485 138.16775) (xy 224.233485 138.18148) (xy 224.233485 138.19521)
			(xy 224.233485 138.20894) (xy 224.233485 138.22267) (xy 224.233485 138.2364) (xy 224.233485 138.25014)
			(xy 224.233485 138.26387) (xy 224.233485 138.2776) (xy 224.233485 138.29133) (xy 224.233485 138.30506)
			(xy 224.233485 138.31879) (xy 224.233485 138.33253) (xy 224.233485 138.34626) (xy 224.233485 138.35999)
			(xy 224.233485 138.37372) (xy 224.233485 138.38745) (xy 224.233485 138.40118) (xy 224.233485 138.41492)
			(xy 224.233485 138.42865) (xy 224.233485 138.44238) (xy 224.233485 138.45611) (xy 224.233485 138.46984)
			(xy 224.233485 138.48358) (xy 224.233485 138.49731) (xy 224.233485 138.51104) (xy 224.233485 138.52477)
			(xy 224.233485 138.5385) (xy 224.233485 138.55224) (xy 224.233485 138.56597) (xy 224.233485 138.5797)
			(xy 224.233485 138.59343) (xy 224.233485 138.60716) (xy 224.233485 138.62089) (xy 224.233485 138.63463)
			(xy 224.233485 138.64836) (xy 224.233485 138.66209) (xy 224.233485 138.67582) (xy 224.233485 138.68955)
			(xy 224.233485 138.70328) (xy 224.233485 138.71702) (xy 224.233485 138.73075) (xy 224.233485 138.74448)
			(xy 224.233485 138.75821) (xy 224.233485 138.77194) (xy 224.233485 138.78567) (xy 224.233485 138.79941)
			(xy 224.233485 138.81314) (xy 224.233485 138.82687) (xy 224.233485 138.8406) (xy 224.233485 138.85433)
			(xy 224.233485 138.86806) (xy 224.233485 138.8818) (xy 224.233485 138.89553) (xy 224.233485 138.90926)
			(xy 224.233485 138.92299) (xy 224.233485 138.93672) (xy 224.233485 138.95045) (xy 224.233485 138.96419)
			(xy 224.233485 138.97792) (xy 224.233485 138.99165) (xy 224.233485 139.00538) (xy 224.233485 139.01911)
			(xy 224.233485 139.03285) (xy 224.233485 139.04658) (xy 224.233485 139.06031) (xy 224.233485 139.07404)
			(xy 224.233485 139.08777) (xy 224.233485 139.10151) (xy 224.233485 139.11524) (xy 224.233485 139.12897)
			(xy 224.233485 139.1427) (xy 224.233485 139.15643) (xy 224.233485 139.17016) (xy 224.233485 139.1839)
			(xy 224.233485 139.19763) (xy 224.233485 139.21136) (xy 224.233485 139.22509) (xy 224.233485 139.23882)
			(xy 224.233485 139.25255) (xy 224.233485 139.26629) (xy 224.233485 139.28002) (xy 224.233485 139.29375)
			(xy 224.233485 139.30748) (xy 224.233485 139.32121) (xy 224.233485 139.33494) (xy 224.233485 139.34868)
			(xy 224.233485 139.36241) (xy 224.233485 139.37614) (xy 224.233485 139.38987) (xy 224.233485 139.4036)
			(xy 224.233485 139.41733) (xy 224.233485 139.43107) (xy 224.233485 139.4448) (xy 224.233485 139.45853)
			(xy 224.233485 139.47226) (xy 224.233485 139.48599) (xy 224.233485 139.49972) (xy 224.233485 139.51346)
			(xy 224.233485 139.52719) (xy 223.231065 139.52719) (xy 223.231065 139.51346) (xy 223.231065 139.49972)
			(xy 223.231065 139.48599) (xy 223.231065 139.47226) (xy 223.231065 139.45853) (xy 223.231065 139.4448)
			(xy 223.231065 139.43107) (xy 223.231065 139.41733) (xy 223.231065 139.4036) (xy 223.231065 139.38987)
			(xy 223.231065 139.37614) (xy 223.231065 139.36241) (xy 223.231065 139.34868) (xy 223.231065 139.33494)
			(xy 223.231065 139.32121) (xy 223.231065 139.30748) (xy 223.231065 139.29375) (xy 223.231065 139.28002)
			(xy 223.231065 139.26629) (xy 223.231065 139.25255) (xy 223.231065 139.23882) (xy 223.231065 139.22509)
			(xy 223.231065 139.21136) (xy 223.231065 139.19763) (xy 223.231065 139.1839) (xy 223.231065 139.17016)
			(xy 223.231065 139.15643) (xy 223.231065 139.1427) (xy 223.231065 139.12897) (xy 223.231065 139.11524)
			(xy 223.231065 139.10151) (xy 223.231065 139.08777) (xy 223.231065 139.07404) (xy 223.231065 139.06031)
			(xy 223.231065 139.04658) (xy 223.231065 139.03285) (xy 223.231065 139.01911) (xy 223.231065 139.00538)
			(xy 223.231065 138.99165) (xy 223.231065 138.97792) (xy 223.231065 138.96419) (xy 223.231065 138.95045)
			(xy 223.231065 138.93672) (xy 223.231065 138.92299) (xy 223.231065 138.90926) (xy 223.231065 138.89553)
			(xy 223.231065 138.8818) (xy 223.231065 138.86806) (xy 223.231065 138.85433) (xy 223.231065 138.8406)
			(xy 223.231065 138.82687) (xy 223.231065 138.81314) (xy 223.231065 138.79941) (xy 223.231065 138.78567)
			(xy 223.231065 138.77194) (xy 223.231065 138.75821) (xy 223.231065 138.74448) (xy 223.231065 138.73075)
			(xy 223.231065 138.71702) (xy 223.231065 138.70328) (xy 223.231065 138.68955) (xy 223.231065 138.67582)
			(xy 223.231065 138.66209) (xy 223.231065 138.64836) (xy 223.231065 138.63463) (xy 223.231065 138.62089)
			(xy 223.231065 138.60716) (xy 223.231065 138.59343) (xy 223.231065 138.5797) (xy 223.231065 138.56597)
			(xy 223.231065 138.55224) (xy 223.231065 138.5385) (xy 223.231065 138.52477) (xy 223.231065 138.51104)
			(xy 223.231065 138.49731) (xy 223.231065 138.48358) (xy 223.231065 138.46984) (xy 223.231065 138.45611)
			(xy 223.231065 138.44238) (xy 223.231065 138.42865) (xy 223.231065 138.41492) (xy 223.231065 138.40118)
			(xy 223.231065 138.38745) (xy 223.231065 138.37372) (xy 223.231065 138.35999) (xy 223.231065 138.34626)
			(xy 223.231065 138.33253) (xy 223.231065 138.31879) (xy 223.231065 138.30506) (xy 223.231065 138.29133)
			(xy 223.231065 138.2776) (xy 223.231065 138.26387) (xy 223.231065 138.25014) (xy 223.231065 138.2364)
			(xy 223.231065 138.22267) (xy 223.231065 138.20894) (xy 223.231065 138.19521) (xy 223.231065 138.18148)
			(xy 223.231065 138.16775) (xy 223.231065 138.15401) (xy 223.231065 138.14028) (xy 223.231065 138.12655)
			(xy 223.231065 138.11282) (xy 223.231065 138.09909) (xy 223.231065 138.08536) (xy 223.231065 138.07162)
			(xy 223.231065 138.05789) (xy 223.231065 138.04416) (xy 223.231065 138.03043) (xy 223.231065 138.0167)
			(xy 223.231065 138.00296) (xy 223.244795 138.00296) (xy 223.244795 137.98923) (xy 223.258525 137.98923)
			(xy 223.258525 138.00296) (xy 224.151095 138.00296) (xy 224.151095 137.98923) (xy 224.164825 137.98923)
			(xy 224.164825 138.00296) (xy 224.192285 138.00296) (xy 224.192285 137.98923) (xy 224.206015 137.98923)
		)
		(stroke
			(width 0)
			(type default)
		)
		(fill yes)
		(layer "F.Cu")
	)
	(gr_poly
		(pts
			(xy 210.158435 140.13139) (xy 210.227095 140.13139) (xy 210.227095 140.14512) (xy 210.268295 140.14512)
			(xy 210.268295 140.15885) (xy 210.309485 140.15885) (xy 210.309485 140.17258) (xy 210.336955 140.17258)
			(xy 210.336955 140.18631) (xy 210.364415 140.18631) (xy 210.364415 140.20005) (xy 210.378145 140.20005)
			(xy 210.378145 140.21378) (xy 210.405605 140.21378) (xy 210.405605 140.22751) (xy 210.419345 140.22751)
			(xy 210.419345 140.24124) (xy 210.433075 140.24124) (xy 210.433075 140.25497) (xy 210.446805 140.25497)
			(xy 210.446805 140.2687) (xy 210.460535 140.2687) (xy 210.460535 140.28244) (xy 210.474265 140.28244)
			(xy 210.474265 140.29617) (xy 210.487995 140.29617) (xy 210.487995 140.3099) (xy 210.501735 140.3099)
			(xy 210.501735 140.32363) (xy 210.515465 140.32363) (xy 210.515465 140.33736) (xy 210.515465 140.35109)
			(xy 210.529195 140.35109) (xy 210.529195 140.36483) (xy 210.542925 140.36483) (xy 210.542925 140.37856)
			(xy 210.542925 140.39229) (xy 210.556655 140.39229) (xy 210.556655 140.40602) (xy 210.556655 140.41975)
			(xy 210.570385 140.41975) (xy 210.570385 140.43348) (xy 210.570385 140.44722) (xy 210.584125 140.44722)
			(xy 210.584125 140.46095) (xy 210.584125 140.47468) (xy 210.584125 140.48841) (xy 210.597855 140.48841)
			(xy 210.597855 140.50214) (xy 210.597855 140.51587) (xy 210.597855 140.5296) (xy 210.597855 140.54334)
			(xy 210.611585 140.54334) (xy 210.611585 140.55707) (xy 210.611585 140.5708) (xy 210.611585 140.58453)
			(xy 210.611585 140.59827) (xy 210.611585 140.612) (xy 210.611585 140.62573) (xy 210.611585 140.63946)
			(xy 210.611585 140.65319) (xy 210.611585 140.66693) (xy 210.611585 140.68066) (xy 210.611585 140.69439)
			(xy 210.611585 140.70812) (xy 210.611585 140.72185) (xy 210.597855 140.72185) (xy 210.597855 140.73558)
			(xy 210.597855 140.74931) (xy 210.597855 140.76305) (xy 210.597855 140.77678) (xy 210.584125 140.77678)
			(xy 210.584125 140.79051) (xy 210.584125 140.80424) (xy 210.584125 140.81797) (xy 210.570385 140.81797)
			(xy 210.570385 140.8317) (xy 210.570385 140.84544) (xy 210.570385 140.85917) (xy 210.556655 140.85917)
			(xy 210.556655 140.8729) (xy 210.556655 140.88663) (xy 210.542925 140.88663) (xy 210.542925 140.90036)
			(xy 210.529195 140.90036) (xy 210.529195 140.91409) (xy 210.529195 140.92783) (xy 210.515465 140.92783)
			(xy 210.515465 140.94156) (xy 210.501735 140.94156) (xy 210.501735 140.95529) (xy 210.501735 140.96902)
			(xy 210.487995 140.96902) (xy 210.487995 140.98275) (xy 210.474265 140.98275) (xy 210.474265 140.99648)
			(xy 210.460535 140.99648) (xy 210.460535 141.01022) (xy 210.446805 141.01022) (xy 210.446805 141.02395)
			(xy 210.433075 141.02395) (xy 210.433075 141.03768) (xy 210.405605 141.03768) (xy 210.405605 141.05141)
			(xy 210.391875 141.05141) (xy 210.391875 141.06514) (xy 210.364415 141.06514) (xy 210.364415 141.07888)
			(xy 210.350685 141.07888) (xy 210.350685 141.09261) (xy 210.323215 141.09261) (xy 210.323215 141.10634)
			(xy 210.282025 141.10634) (xy 210.282025 141.12007) (xy 210.254565 141.12007) (xy 210.254565 141.1338)
			(xy 210.199635 141.1338) (xy 210.199635 141.14754) (xy 209.993655 141.14754) (xy 209.993655 141.1338)
			(xy 209.952465 141.1338) (xy 209.952465 141.12007) (xy 209.911265 141.12007) (xy 209.911265 141.10634)
			(xy 209.870075 141.10634) (xy 209.870075 141.09261) (xy 209.856345 141.09261) (xy 209.856345 141.07888)
			(xy 209.828875 141.07888) (xy 209.828875 141.06514) (xy 209.801415 141.06514) (xy 209.801415 141.05141)
			(xy 209.787685 141.05141) (xy 209.787685 141.03768) (xy 209.773945 141.03768) (xy 209.773945 141.02395)
			(xy 209.746485 141.02395) (xy 209.746485 141.01022) (xy 209.732755 141.01022) (xy 209.732755 140.99648)
			(xy 209.719025 140.99648) (xy 209.719025 140.98275) (xy 209.705285 140.98275) (xy 209.705285 140.96902)
			(xy 209.705285 140.95529) (xy 209.691555 140.95529) (xy 209.691555 140.94156) (xy 209.677825 140.94156)
			(xy 209.677825 140.92783) (xy 209.664095 140.92783) (xy 209.664095 140.91409) (xy 209.664095 140.90036)
			(xy 209.650365 140.90036) (xy 209.650365 140.88663) (xy 209.650365 140.8729) (xy 209.636635 140.8729)
			(xy 209.636635 140.85917) (xy 209.636635 140.84544) (xy 209.622895 140.84544) (xy 209.622895 140.8317)
			(xy 209.622895 140.81797) (xy 209.609165 140.81797) (xy 209.609165 140.80424) (xy 209.609165 140.79051)
			(xy 209.609165 140.77678) (xy 209.595435 140.77678) (xy 209.595435 140.76305) (xy 209.595435 140.74931)
			(xy 209.595435 140.73558) (xy 209.595435 140.72185) (xy 209.595435 140.70812) (xy 209.581705 140.70812)
			(xy 209.581705 140.69439) (xy 209.581705 140.68066) (xy 209.581705 140.66693) (xy 209.581705 140.65319)
			(xy 209.581705 140.63946) (xy 209.581705 140.62573) (xy 209.581705 140.612) (xy 209.581705 140.59827)
			(xy 209.581705 140.58453) (xy 209.581705 140.5708) (xy 209.595435 140.5708) (xy 209.595435 140.55707)
			(xy 209.595435 140.54334) (xy 209.595435 140.5296) (xy 209.595435 140.51587) (xy 209.595435 140.50214)
			(xy 209.609165 140.50214) (xy 209.609165 140.48841) (xy 209.609165 140.47468) (xy 209.609165 140.46095)
			(xy 209.622895 140.46095) (xy 209.622895 140.44722) (xy 209.622895 140.43348) (xy 209.622895 140.41975)
			(xy 209.636635 140.41975) (xy 209.636635 140.40602) (xy 209.636635 140.39229) (xy 209.650365 140.39229)
			(xy 209.650365 140.37856) (xy 209.650365 140.36483) (xy 209.664095 140.36483) (xy 209.664095 140.35109)
			(xy 209.677825 140.35109) (xy 209.677825 140.33736) (xy 209.677825 140.32363) (xy 209.691555 140.32363)
			(xy 209.691555 140.3099) (xy 209.705285 140.3099) (xy 209.705285 140.29617) (xy 209.719025 140.29617)
			(xy 209.719025 140.28244) (xy 209.732755 140.28244) (xy 209.732755 140.2687) (xy 209.746485 140.2687)
			(xy 209.746485 140.25497) (xy 209.760215 140.25497) (xy 209.760215 140.24124) (xy 209.773945 140.24124)
			(xy 209.773945 140.22751) (xy 209.787685 140.22751) (xy 209.787685 140.21378) (xy 209.815145 140.21378)
			(xy 209.815145 140.20005) (xy 209.842605 140.20005) (xy 209.842605 140.18631) (xy 209.856345 140.18631)
			(xy 209.856345 140.17258) (xy 209.883805 140.17258) (xy 209.883805 140.15885) (xy 209.924995 140.15885)
			(xy 209.924995 140.14512) (xy 209.966195 140.14512) (xy 209.966195 140.13139) (xy 210.034855 140.13139)
			(xy 210.034855 140.11765) (xy 210.158435 140.11765)
		)
		(stroke
			(width 0)
			(type default)
		)
		(fill yes)
		(layer "F.Cu")
	)
	(gr_poly
		(pts
			(xy 210.185905 138.2776) (xy 210.240825 138.2776) (xy 210.240825 138.29133) (xy 210.282025 138.29133)
			(xy 210.282025 138.30506) (xy 210.309485 138.30506) (xy 210.309485 138.31879) (xy 210.336955 138.31879)
			(xy 210.336955 138.33253) (xy 210.364415 138.33253) (xy 210.364415 138.34626) (xy 210.391875 138.34626)
			(xy 210.391875 138.35999) (xy 210.405605 138.35999) (xy 210.405605 138.37372) (xy 210.419345 138.37372)
			(xy 210.419345 138.38745) (xy 210.446805 138.38745) (xy 210.446805 138.40118) (xy 210.460535 138.40118)
			(xy 210.460535 138.41492) (xy 210.474265 138.41492) (xy 210.474265 138.42865) (xy 210.487995 138.42865)
			(xy 210.487995 138.44238) (xy 210.487995 138.45611) (xy 210.501735 138.45611) (xy 210.501735 138.46984)
			(xy 210.515465 138.46984) (xy 210.515465 138.48358) (xy 210.529195 138.48358) (xy 210.529195 138.49731)
			(xy 210.529195 138.51104) (xy 210.542925 138.51104) (xy 210.542925 138.52477) (xy 210.542925 138.5385)
			(xy 210.556655 138.5385) (xy 210.556655 138.55224) (xy 210.556655 138.56597) (xy 210.570385 138.56597)
			(xy 210.570385 138.5797) (xy 210.570385 138.59343) (xy 210.584125 138.59343) (xy 210.584125 138.60716)
			(xy 210.584125 138.62089) (xy 210.584125 138.63463) (xy 210.597855 138.63463) (xy 210.597855 138.64836)
			(xy 210.597855 138.66209) (xy 210.597855 138.67582) (xy 210.597855 138.68955) (xy 210.611585 138.68955)
			(xy 210.611585 138.70328) (xy 210.611585 138.71702) (xy 210.611585 138.73075) (xy 210.611585 138.74448)
			(xy 210.611585 138.75821) (xy 210.611585 138.77194) (xy 210.611585 138.78567) (xy 210.611585 138.79941)
			(xy 210.611585 138.81314) (xy 210.611585 138.82687) (xy 210.611585 138.8406) (xy 210.611585 138.85433)
			(xy 210.611585 138.86806) (xy 210.597855 138.86806) (xy 210.597855 138.8818) (xy 210.597855 138.89553)
			(xy 210.597855 138.90926) (xy 210.597855 138.92299) (xy 210.584125 138.92299) (xy 210.584125 138.93672)
			(xy 210.584125 138.95045) (xy 210.584125 138.96419) (xy 210.570385 138.96419) (xy 210.570385 138.97792)
			(xy 210.570385 138.99165) (xy 210.556655 138.99165) (xy 210.556655 139.00538) (xy 210.556655 139.01911)
			(xy 210.542925 139.01911) (xy 210.542925 139.03285) (xy 210.542925 139.04658) (xy 210.529195 139.04658)
			(xy 210.529195 139.06031) (xy 210.529195 139.07404) (xy 210.515465 139.07404) (xy 210.515465 139.08777)
			(xy 210.501735 139.08777) (xy 210.501735 139.10151) (xy 210.487995 139.10151) (xy 210.487995 139.11524)
			(xy 210.487995 139.12897) (xy 210.474265 139.12897) (xy 210.474265 139.1427) (xy 210.460535 139.1427)
			(xy 210.460535 139.15643) (xy 210.433075 139.15643) (xy 210.433075 139.17016) (xy 210.419345 139.17016)
			(xy 210.419345 139.1839) (xy 210.405605 139.1839) (xy 210.405605 139.19763) (xy 210.391875 139.19763)
			(xy 210.391875 139.21136) (xy 210.364415 139.21136) (xy 210.364415 139.22509) (xy 210.336955 139.22509)
			(xy 210.336955 139.23882) (xy 210.309485 139.23882) (xy 210.309485 139.25255) (xy 210.282025 139.25255)
			(xy 210.282025 139.26629) (xy 210.240825 139.26629) (xy 210.240825 139.28002) (xy 210.172165 139.28002)
			(xy 210.172165 139.29375) (xy 210.021115 139.29375) (xy 210.021115 139.28002) (xy 209.952465 139.28002)
			(xy 209.952465 139.26629) (xy 209.911265 139.26629) (xy 209.911265 139.25255) (xy 209.883805 139.25255)
			(xy 209.883805 139.23882) (xy 209.856345 139.23882) (xy 209.856345 139.22509) (xy 209.828875 139.22509)
			(xy 209.828875 139.21136) (xy 209.815145 139.21136) (xy 209.815145 139.19763) (xy 209.787685 139.19763)
			(xy 209.787685 139.1839) (xy 209.773945 139.1839) (xy 209.773945 139.17016) (xy 209.760215 139.17016)
			(xy 209.760215 139.15643) (xy 209.746485 139.15643) (xy 209.746485 139.1427) (xy 209.732755 139.1427)
			(xy 209.732755 139.12897) (xy 209.719025 139.12897) (xy 209.719025 139.11524) (xy 209.705285 139.11524)
			(xy 209.705285 139.10151) (xy 209.691555 139.10151) (xy 209.691555 139.08777) (xy 209.677825 139.08777)
			(xy 209.677825 139.07404) (xy 209.677825 139.06031) (xy 209.664095 139.06031) (xy 209.664095 139.04658)
			(xy 209.650365 139.04658) (xy 209.650365 139.03285) (xy 209.650365 139.01911) (xy 209.636635 139.01911)
			(xy 209.636635 139.00538) (xy 209.636635 138.99165) (xy 209.622895 138.99165) (xy 209.622895 138.97792)
			(xy 209.622895 138.96419) (xy 209.622895 138.95045) (xy 209.609165 138.95045) (xy 209.609165 138.93672)
			(xy 209.609165 138.92299) (xy 209.609165 138.90926) (xy 209.595435 138.90926) (xy 209.595435 138.89553)
			(xy 209.595435 138.8818) (xy 209.595435 138.86806) (xy 209.595435 138.85433) (xy 209.581705 138.85433)
			(xy 209.581705 138.8406) (xy 209.581705 138.82687) (xy 209.581705 138.81314) (xy 209.581705 138.79941)
			(xy 209.581705 138.78567) (xy 209.581705 138.77194) (xy 209.581705 138.75821) (xy 209.581705 138.74448)
			(xy 209.581705 138.73075) (xy 209.581705 138.71702) (xy 209.581705 138.70328) (xy 209.595435 138.70328)
			(xy 209.595435 138.68955) (xy 209.595435 138.67582) (xy 209.595435 138.66209) (xy 209.595435 138.64836)
			(xy 209.609165 138.64836) (xy 209.609165 138.63463) (xy 209.609165 138.62089) (xy 209.609165 138.60716)
			(xy 209.609165 138.59343) (xy 209.622895 138.59343) (xy 209.622895 138.5797) (xy 209.622895 138.56597)
			(xy 209.636635 138.56597) (xy 209.636635 138.55224) (xy 209.636635 138.5385) (xy 209.650365 138.5385)
			(xy 209.650365 138.52477) (xy 209.650365 138.51104) (xy 209.664095 138.51104) (xy 209.664095 138.49731)
			(xy 209.677825 138.49731) (xy 209.677825 138.48358) (xy 209.677825 138.46984) (xy 209.691555 138.46984)
			(xy 209.691555 138.45611) (xy 209.705285 138.45611) (xy 209.705285 138.44238) (xy 209.719025 138.44238)
			(xy 209.719025 138.42865) (xy 209.732755 138.42865) (xy 209.732755 138.41492) (xy 209.746485 138.41492)
			(xy 209.746485 138.40118) (xy 209.760215 138.40118) (xy 209.760215 138.38745) (xy 209.773945 138.38745)
			(xy 209.773945 138.37372) (xy 209.787685 138.37372) (xy 209.787685 138.35999) (xy 209.815145 138.35999)
			(xy 209.815145 138.34626) (xy 209.828875 138.34626) (xy 209.828875 138.33253) (xy 209.856345 138.33253)
			(xy 209.856345 138.31879) (xy 209.883805 138.31879) (xy 209.883805 138.30506) (xy 209.911265 138.30506)
			(xy 209.911265 138.29133) (xy 209.952465 138.29133) (xy 209.952465 138.2776) (xy 210.021115 138.2776)
			(xy 210.021115 138.26387) (xy 210.185905 138.26387)
		)
		(stroke
			(width 0)
			(type default)
		)
		(fill yes)
		(layer "F.Cu")
	)
	(gr_poly
		(pts
			(xy 210.199635 136.42381) (xy 210.254565 136.42381) (xy 210.254565 136.43755) (xy 210.295755 136.43755)
			(xy 210.295755 136.45128) (xy 210.323215 136.45128) (xy 210.323215 136.46501) (xy 210.350685 136.46501)
			(xy 210.350685 136.47874) (xy 210.364415 136.47874) (xy 210.364415 136.49247) (xy 210.391875 136.49247)
			(xy 210.391875 136.5062) (xy 210.405605 136.5062) (xy 210.405605 136.51994) (xy 210.433075 136.51994)
			(xy 210.433075 136.53367) (xy 210.446805 136.53367) (xy 210.446805 136.5474) (xy 210.460535 136.5474)
			(xy 210.460535 136.56113) (xy 210.474265 136.56113) (xy 210.474265 136.57486) (xy 210.487995 136.57486)
			(xy 210.487995 136.58859) (xy 210.501735 136.58859) (xy 210.501735 136.60233) (xy 210.501735 136.61606)
			(xy 210.515465 136.61606) (xy 210.515465 136.62979) (xy 210.529195 136.62979) (xy 210.529195 136.64352)
			(xy 210.529195 136.65725) (xy 210.542925 136.65725) (xy 210.542925 136.67098) (xy 210.556655 136.67098)
			(xy 210.556655 136.68472) (xy 210.556655 136.69845) (xy 210.570385 136.69845) (xy 210.570385 136.71218)
			(xy 210.570385 136.72591) (xy 210.570385 136.73964) (xy 210.584125 136.73964) (xy 210.584125 136.75337)
			(xy 210.584125 136.76711) (xy 210.584125 136.78084) (xy 210.597855 136.78084) (xy 210.597855 136.79457)
			(xy 210.597855 136.8083) (xy 210.597855 136.82203) (xy 210.597855 136.83576) (xy 210.611585 136.83576)
			(xy 210.611585 136.8495) (xy 210.611585 136.86323) (xy 210.611585 136.87696) (xy 210.611585 136.89069)
			(xy 210.611585 136.90442) (xy 210.611585 136.91816) (xy 210.611585 136.93189) (xy 210.611585 136.94562)
			(xy 210.611585 136.95935) (xy 210.611585 136.97308) (xy 210.611585 136.98682) (xy 210.611585 137.00055)
			(xy 210.611585 137.01428) (xy 210.597855 137.01428) (xy 210.597855 137.02801) (xy 210.597855 137.04174)
			(xy 210.597855 137.05547) (xy 210.597855 137.06921) (xy 210.584125 137.06921) (xy 210.584125 137.08294)
			(xy 210.584125 137.09667) (xy 210.584125 137.1104) (xy 210.570385 137.1104) (xy 210.570385 137.12413)
			(xy 210.570385 137.13786) (xy 210.556655 137.13786) (xy 210.556655 137.1516) (xy 210.556655 137.16533)
			(xy 210.542925 137.16533) (xy 210.542925 137.17906) (xy 210.542925 137.19279) (xy 210.529195 137.19279)
			(xy 210.529195 137.20652) (xy 210.515465 137.20652) (xy 210.515465 137.22025) (xy 210.515465 137.23399)
			(xy 210.501735 137.23399) (xy 210.501735 137.24772) (xy 210.487995 137.24772) (xy 210.487995 137.26145)
			(xy 210.474265 137.26145) (xy 210.474265 137.27518) (xy 210.460535 137.27518) (xy 210.460535 137.28891)
			(xy 210.446805 137.28891) (xy 210.446805 137.30264) (xy 210.433075 137.30264) (xy 210.433075 137.31638)
			(xy 210.419345 137.31638) (xy 210.419345 137.33011) (xy 210.405605 137.33011) (xy 210.405605 137.34384)
			(xy 210.378145 137.34384) (xy 210.378145 137.35757) (xy 210.364415 137.35757) (xy 210.364415 137.3713)
			(xy 210.336955 137.3713) (xy 210.336955 137.38503) (xy 210.309485 137.38503) (xy 210.309485 137.39877)
			(xy 210.268295 137.39877) (xy 210.268295 137.4125) (xy 210.227095 137.4125) (xy 210.227095 137.42623)
			(xy 210.144705 137.42623) (xy 210.144705 137.43996) (xy 210.048585 137.43996) (xy 210.048585 137.42623)
			(xy 209.966195 137.42623) (xy 209.966195 137.4125) (xy 209.924995 137.4125) (xy 209.924995 137.39877)
			(xy 209.897535 137.39877) (xy 209.897535 137.38503) (xy 209.856345 137.38503) (xy 209.856345 137.3713)
			(xy 209.842605 137.3713) (xy 209.842605 137.35757) (xy 209.815145 137.35757) (xy 209.815145 137.34384)
			(xy 209.801415 137.34384) (xy 209.801415 137.33011) (xy 209.773945 137.33011) (xy 209.773945 137.31638)
			(xy 209.760215 137.31638) (xy 209.760215 137.30264) (xy 209.746485 137.30264) (xy 209.746485 137.28891)
			(xy 209.732755 137.28891) (xy 209.732755 137.27518) (xy 209.719025 137.27518) (xy 209.719025 137.26145)
			(xy 209.705285 137.26145) (xy 209.705285 137.24772) (xy 209.691555 137.24772) (xy 209.691555 137.23399)
			(xy 209.677825 137.23399) (xy 209.677825 137.22025) (xy 209.677825 137.20652) (xy 209.664095 137.20652)
			(xy 209.664095 137.19279) (xy 209.664095 137.17906) (xy 209.650365 137.17906) (xy 209.650365 137.16533)
			(xy 209.636635 137.16533) (xy 209.636635 137.1516) (xy 209.636635 137.13786) (xy 209.622895 137.13786)
			(xy 209.622895 137.12413) (xy 209.622895 137.1104) (xy 209.622895 137.09667) (xy 209.609165 137.09667)
			(xy 209.609165 137.08294) (xy 209.609165 137.06921) (xy 209.609165 137.05547) (xy 209.595435 137.05547)
			(xy 209.595435 137.04174) (xy 209.595435 137.02801) (xy 209.595435 137.01428) (xy 209.595435 137.00055)
			(xy 209.595435 136.98682) (xy 209.581705 136.98682) (xy 209.581705 136.97308) (xy 209.581705 136.95935)
			(xy 209.581705 136.94562) (xy 209.581705 136.93189) (xy 209.581705 136.91816) (xy 209.581705 136.90442)
			(xy 209.581705 136.89069) (xy 209.581705 136.87696) (xy 209.581705 136.86323) (xy 209.581705 136.8495)
			(xy 209.595435 136.8495) (xy 209.595435 136.83576) (xy 209.595435 136.82203) (xy 209.595435 136.8083)
			(xy 209.595435 136.79457) (xy 209.595435 136.78084) (xy 209.609165 136.78084) (xy 209.609165 136.76711)
			(xy 209.609165 136.75337) (xy 209.609165 136.73964) (xy 209.622895 136.73964) (xy 209.622895 136.72591)
			(xy 209.622895 136.71218) (xy 209.636635 136.71218) (xy 209.636635 136.69845) (xy 209.636635 136.68472)
			(xy 209.650365 136.68472) (xy 209.650365 136.67098) (xy 209.650365 136.65725) (xy 209.664095 136.65725)
			(xy 209.664095 136.64352) (xy 209.664095 136.62979) (xy 209.677825 136.62979) (xy 209.677825 136.61606)
			(xy 209.691555 136.61606) (xy 209.691555 136.60233) (xy 209.705285 136.60233) (xy 209.705285 136.58859)
			(xy 209.705285 136.57486) (xy 209.719025 136.57486) (xy 209.719025 136.56113) (xy 209.732755 136.56113)
			(xy 209.732755 136.5474) (xy 209.746485 136.5474) (xy 209.746485 136.53367) (xy 209.773945 136.53367)
			(xy 209.773945 136.51994) (xy 209.787685 136.51994) (xy 209.787685 136.5062) (xy 209.801415 136.5062)
			(xy 209.801415 136.49247) (xy 209.828875 136.49247) (xy 209.828875 136.47874) (xy 209.842605 136.47874)
			(xy 209.842605 136.46501) (xy 209.870075 136.46501) (xy 209.870075 136.45128) (xy 209.911265 136.45128)
			(xy 209.911265 136.43755) (xy 209.938725 136.43755) (xy 209.938725 136.42381) (xy 209.993655 136.42381)
			(xy 209.993655 136.41008) (xy 210.199635 136.41008)
		)
		(stroke
			(width 0)
			(type default)
		)
		(fill yes)
		(layer "F.Cu")
	)
	(gr_poly
		(pts
			(xy 231.003235 130.68394) (xy 231.140555 130.68394) (xy 231.140555 130.69767) (xy 231.209215 130.69767)
			(xy 231.209215 130.71141) (xy 231.264135 130.71141) (xy 231.264135 130.72514) (xy 231.291605 130.72514)
			(xy 231.291605 130.73887) (xy 231.332795 130.73887) (xy 231.332795 130.7526) (xy 231.360265 130.7526)
			(xy 231.360265 130.76633) (xy 231.401455 130.76633) (xy 231.401455 130.78006) (xy 231.415185 130.78006)
			(xy 231.415185 130.7938) (xy 231.442655 130.7938) (xy 231.442655 130.80753) (xy 231.470115 130.80753)
			(xy 231.470115 130.82126) (xy 231.483845 130.82126) (xy 231.483845 130.83499) (xy 231.511315 130.83499)
			(xy 231.511315 130.84872) (xy 231.525045 130.84872) (xy 231.525045 130.86245) (xy 231.552505 130.86245)
			(xy 231.552505 130.87619) (xy 231.566235 130.87619) (xy 231.566235 130.88992) (xy 231.579965 130.88992)
			(xy 231.579965 130.90365) (xy 231.593705 130.90365) (xy 231.593705 130.91738) (xy 231.607435 130.91738)
			(xy 231.607435 130.93111) (xy 231.621165 130.93111) (xy 231.621165 130.94484) (xy 231.634895 130.94484)
			(xy 231.634895 130.95858) (xy 231.648625 130.95858) (xy 231.648625 130.97231) (xy 231.662355 130.97231)
			(xy 231.662355 130.98604) (xy 231.676095 130.98604) (xy 231.676095 130.99977) (xy 231.689825 130.99977)
			(xy 231.689825 131.0135) (xy 231.703555 131.0135) (xy 231.703555 131.02723) (xy 231.703555 131.04097)
			(xy 231.717285 131.04097) (xy 231.717285 131.0547) (xy 231.731015 131.0547) (xy 231.731015 131.06843)
			(xy 231.731015 131.08216) (xy 231.744745 131.08216) (xy 231.744745 131.09589) (xy 231.758485 131.09589)
			(xy 231.758485 131.10962) (xy 231.758485 131.12336) (xy 231.772215 131.12336) (xy 231.772215 131.13709)
			(xy 231.772215 131.15082) (xy 231.785945 131.15082) (xy 231.785945 131.16455) (xy 231.799675 131.16455)
			(xy 231.799675 131.17828) (xy 231.799675 131.19202) (xy 231.813405 131.19202) (xy 231.813405 131.20575)
			(xy 231.813405 131.21948) (xy 231.813405 131.23321) (xy 231.827145 131.23321) (xy 231.827145 131.24694)
			(xy 231.827145 131.26068) (xy 231.840875 131.26068) (xy 231.840875 131.27441) (xy 231.840875 131.28814)
			(xy 231.840875 131.30187) (xy 231.854605 131.30187) (xy 231.854605 131.3156) (xy 231.854605 131.32933)
			(xy 231.854605 131.34307) (xy 231.854605 131.3568) (xy 231.868335 131.3568) (xy 231.868335 131.37053)
			(xy 231.868335 131.38426) (xy 231.868335 131.39799) (xy 231.868335 131.41172) (xy 231.882065 131.41172)
			(xy 231.882065 131.42546) (xy 231.882065 131.43919) (xy 231.882065 131.45292) (xy 231.882065 131.46665)
			(xy 231.882065 131.48038) (xy 231.882065 131.49411) (xy 231.882065 131.50785) (xy 231.882065 131.52158)
			(xy 231.882065 131.53531) (xy 231.882065 131.54904) (xy 231.895805 131.54904) (xy 231.895805 131.56277)
			(xy 231.895805 131.5765) (xy 231.895805 131.59024) (xy 231.895805 131.60397) (xy 231.882065 131.60397)
			(xy 231.882065 131.6177) (xy 231.882065 131.63143) (xy 231.882065 131.64516) (xy 231.882065 131.6589)
			(xy 231.882065 131.67263) (xy 231.882065 131.68636) (xy 231.882065 131.70009) (xy 231.882065 131.71382)
			(xy 231.882065 131.72756) (xy 231.868335 131.72756) (xy 231.868335 131.74129) (xy 231.868335 131.75502)
			(xy 231.868335 131.76875) (xy 231.868335 131.78248) (xy 231.868335 131.79621) (xy 231.854605 131.79621)
			(xy 231.854605 131.80995) (xy 231.854605 131.82368) (xy 231.854605 131.83741) (xy 231.840875 131.83741)
			(xy 231.840875 131.85114) (xy 231.840875 131.86487) (xy 231.840875 131.8786) (xy 231.827145 131.8786)
			(xy 231.827145 131.89233) (xy 231.827145 131.90607) (xy 231.827145 131.9198) (xy 231.813405 131.9198)
			(xy 231.813405 131.93353) (xy 231.813405 131.94726) (xy 231.799675 131.94726) (xy 231.799675 131.96099)
			(xy 231.799675 131.97472) (xy 231.785945 131.97472) (xy 231.785945 131.98846) (xy 231.785945 132.00219)
			(xy 231.772215 132.00219) (xy 231.772215 132.01592) (xy 231.772215 132.02965) (xy 231.758485 132.02965)
			(xy 231.758485 132.04338) (xy 231.758485 132.05711) (xy 231.744745 132.05711) (xy 231.744745 132.07085)
			(xy 231.731015 132.07085) (xy 231.731015 132.08458) (xy 231.731015 132.09831) (xy 231.717285 132.09831)
			(xy 231.717285 132.11204) (xy 231.703555 132.11204) (xy 231.703555 132.12577) (xy 231.689825 132.12577)
			(xy 231.689825 132.13951) (xy 231.689825 132.15324) (xy 231.676095 132.15324) (xy 231.676095 132.16697)
			(xy 231.662355 132.16697) (xy 231.662355 132.1807) (xy 231.648625 132.1807) (xy 231.648625 132.19443)
			(xy 231.634895 132.19443) (xy 231.634895 132.20817) (xy 231.621165 132.20817) (xy 231.621165 132.2219)
			(xy 231.607435 132.2219) (xy 231.607435 132.23563) (xy 231.593705 132.23563) (xy 231.593705 132.24936)
			(xy 231.579965 132.24936) (xy 231.579965 132.26309) (xy 231.552505 132.26309) (xy 231.552505 132.27682)
			(xy 231.538775 132.27682) (xy 231.538775 132.29056) (xy 231.525045 132.29056) (xy 231.525045 132.30429)
			(xy 231.511315 132.30429) (xy 231.511315 132.31802) (xy 231.483845 132.31802) (xy 231.483845 132.33175)
			(xy 231.470115 132.33175) (xy 231.470115 132.34548) (xy 231.442655 132.34548) (xy 231.442655 132.35921)
			(xy 231.415185 132.35921) (xy 231.415185 132.37295) (xy 231.387725 132.37295) (xy 231.387725 132.38668)
			(xy 231.360265 132.38668) (xy 231.360265 132.40041) (xy 231.332795 132.40041) (xy 231.332795 132.41414)
			(xy 231.291605 132.41414) (xy 231.291605 132.42787) (xy 231.250405 132.42787) (xy 231.250405 132.4416)
			(xy 231.195475 132.4416) (xy 231.195475 132.45534) (xy 231.126825 132.45534) (xy 231.126825 132.46907)
			(xy 229.794845 132.46907) (xy 229.794845 132.45534) (xy 229.726185 132.45534) (xy 229.726185 132.4416)
			(xy 229.684985 132.4416) (xy 229.684985 132.42787) (xy 229.643795 132.42787) (xy 229.643795 132.41414)
			(xy 229.602595 132.41414) (xy 229.602595 132.40041) (xy 229.575135 132.40041) (xy 229.575135 132.38668)
			(xy 229.533935 132.38668) (xy 229.533935 132.37295) (xy 229.520205 132.37295) (xy 229.520205 132.35921)
			(xy 229.492745 132.35921) (xy 229.492745 132.34548) (xy 229.465275 132.34548) (xy 229.465275 132.33175)
			(xy 229.451545 132.33175) (xy 229.451545 132.31802) (xy 229.424085 132.31802) (xy 229.424085 132.30429)
			(xy 229.410355 132.30429) (xy 229.410355 132.29056) (xy 229.382885 132.29056) (xy 229.382885 132.27682)
			(xy 229.369155 132.27682) (xy 229.369155 132.26309) (xy 229.355425 132.26309) (xy 229.355425 132.24936)
			(xy 229.341695 132.24936) (xy 229.341695 132.23563) (xy 229.327965 132.23563) (xy 229.327965 132.2219)
			(xy 229.314235 132.2219) (xy 229.314235 132.20817) (xy 229.300495 132.20817) (xy 229.300495 132.19443)
			(xy 229.286765 132.19443) (xy 229.286765 132.1807) (xy 229.273035 132.1807) (xy 229.273035 132.16697)
			(xy 229.259305 132.16697) (xy 229.259305 132.15324) (xy 229.245575 132.15324) (xy 229.245575 132.13951)
			(xy 229.231845 132.13951) (xy 229.231845 132.12577) (xy 229.231845 132.11204) (xy 229.218105 132.11204)
			(xy 229.218105 132.09831) (xy 229.204375 132.09831) (xy 229.204375 132.08458) (xy 229.190645 132.08458)
			(xy 229.190645 132.07085) (xy 229.190645 132.05711) (xy 229.176915 132.05711) (xy 229.176915 132.04338)
			(xy 229.176915 132.02965) (xy 229.163185 132.02965) (xy 229.163185 132.01592) (xy 229.149445 132.01592)
			(xy 229.149445 132.00219) (xy 229.149445 131.98846) (xy 229.135715 131.98846) (xy 229.135715 131.97472)
			(xy 229.135715 131.96099) (xy 229.121985 131.96099) (xy 229.121985 131.94726) (xy 229.121985 131.93353)
			(xy 229.108255 131.93353) (xy 229.108255 131.9198) (xy 229.108255 131.90607) (xy 229.108255 131.89233)
			(xy 229.094525 131.89233) (xy 229.094525 131.8786) (xy 229.094525 131.86487) (xy 229.094525 131.85114)
			(xy 229.080785 131.85114) (xy 229.080785 131.83741) (xy 229.080785 131.82368) (xy 229.080785 131.80995)
			(xy 229.067055 131.80995) (xy 229.067055 131.79621) (xy 229.067055 131.78248) (xy 229.067055 131.76875)
			(xy 229.067055 131.75502) (xy 229.067055 131.74129) (xy 229.053325 131.74129) (xy 229.053325 131.72756)
			(xy 229.053325 131.71382) (xy 229.053325 131.70009) (xy 229.053325 131.68636) (xy 229.053325 131.67263)
			(xy 229.039595 131.67263) (xy 229.039595 131.6589) (xy 229.039595 131.64516) (xy 229.039595 131.63143)
			(xy 229.039595 131.6177) (xy 229.039595 131.60397) (xy 229.039595 131.59024) (xy 229.039595 131.5765)
			(xy 229.039595 131.56277) (xy 229.039595 131.54904) (xy 229.039595 131.53531) (xy 229.039595 131.52158)
			(xy 229.039595 131.50785) (xy 229.039595 131.49411) (xy 229.053325 131.49411) (xy 229.053325 131.48038)
			(xy 229.053325 131.46665) (xy 229.053325 131.45292) (xy 229.053325 131.43919) (xy 229.053325 131.42546)
			(xy 229.053325 131.41172) (xy 229.053325 131.39799) (xy 229.067055 131.39799) (xy 229.067055 131.38426)
			(xy 229.067055 131.37053) (xy 229.067055 131.3568) (xy 229.067055 131.34307) (xy 229.080785 131.34307)
			(xy 229.080785 131.32933) (xy 229.080785 131.3156) (xy 229.080785 131.30187) (xy 229.080785 131.28814)
			(xy 229.094525 131.28814) (xy 229.094525 131.27441) (xy 229.094525 131.26068) (xy 229.108255 131.26068)
			(xy 229.108255 131.24694) (xy 229.108255 131.23321) (xy 229.108255 131.21948) (xy 229.121985 131.21948)
			(xy 229.121985 131.20575) (xy 229.121985 131.19202) (xy 229.135715 131.19202) (xy 229.135715 131.17828)
			(xy 229.135715 131.16455) (xy 229.149445 131.16455) (xy 229.149445 131.15082) (xy 229.149445 131.13709)
			(xy 229.163185 131.13709) (xy 229.163185 131.12336) (xy 229.163185 131.10962) (xy 229.176915 131.10962)
			(xy 229.176915 131.09589) (xy 229.190645 131.09589) (xy 229.190645 131.08216) (xy 229.190645 131.06843)
			(xy 229.204375 131.06843) (xy 229.204375 131.0547) (xy 229.218105 131.0547) (xy 229.218105 131.04097)
			(xy 229.218105 131.02723) (xy 229.231845 131.02723) (xy 229.231845 131.0135) (xy 229.245575 131.0135)
			(xy 229.245575 130.99977) (xy 229.259305 130.99977) (xy 229.259305 130.98604) (xy 229.273035 130.98604)
			(xy 229.273035 130.97231) (xy 229.286765 130.97231) (xy 229.286765 130.95858) (xy 229.300495 130.95858)
			(xy 229.300495 130.94484) (xy 229.314235 130.94484) (xy 229.314235 130.93111) (xy 229.327965 130.93111)
			(xy 229.327965 130.91738) (xy 229.341695 130.91738) (xy 229.341695 130.90365) (xy 229.355425 130.90365)
			(xy 229.355425 130.88992) (xy 229.369155 130.88992) (xy 229.369155 130.87619) (xy 229.382885 130.87619)
			(xy 229.382885 130.86245) (xy 229.396625 130.86245) (xy 229.396625 130.84872) (xy 229.424085 130.84872)
			(xy 229.424085 130.83499) (xy 229.437815 130.83499) (xy 229.437815 130.82126) (xy 229.465275 130.82126)
			(xy 229.465275 130.80753) (xy 229.479015 130.80753) (xy 229.479015 130.7938) (xy 229.506475 130.7938)
			(xy 229.506475 130.78006) (xy 229.533935 130.78006) (xy 229.533935 130.76633) (xy 229.561405 130.76633)
			(xy 229.561405 130.7526) (xy 229.602595 130.7526) (xy 229.602595 130.73887) (xy 229.630055 130.73887)
			(xy 229.630055 130.72514) (xy 229.671255 130.72514) (xy 229.671255 130.71141) (xy 229.726185 130.71141)
			(xy 229.726185 130.69767) (xy 229.781115 130.69767) (xy 229.781115 130.68394) (xy 229.932155 130.68394)
			(xy 229.932155 130.67021) (xy 230.975775 130.67021) (xy 230.975775 130.68394) (xy 230.989505 130.68394)
			(xy 230.989505 130.67021) (xy 231.003235 130.67021)
		)
		(stroke
			(width 0)
			(type default)
		)
		(fill yes)
		(layer "F.Cu")
	)
	(gr_poly
		(pts
			(xy 234.161535 137.85191) (xy 234.243925 137.85191) (xy 234.243925 137.86565) (xy 234.298855 137.86565)
			(xy 234.298855 137.87938) (xy 234.340055 137.87938) (xy 234.340055 137.89311) (xy 234.381245 137.89311)
			(xy 234.381245 137.90684) (xy 234.408705 137.90684) (xy 234.408705 137.92057) (xy 234.449905 137.92057)
			(xy 234.449905 137.9343) (xy 234.477365 137.9343) (xy 234.477365 137.94804) (xy 234.491105 137.94804)
			(xy 234.491105 137.96177) (xy 234.518565 137.96177) (xy 234.518565 137.9755) (xy 234.546025 137.9755)
			(xy 234.546025 137.98923) (xy 234.559765 137.98923) (xy 234.559765 138.00296) (xy 234.587225 138.00296)
			(xy 234.587225 138.0167) (xy 234.600955 138.0167) (xy 234.600955 138.03043) (xy 234.614685 138.03043)
			(xy 234.614685 138.04416) (xy 234.628415 138.04416) (xy 234.628415 138.05789) (xy 234.655885 138.05789)
			(xy 234.655885 138.07162) (xy 234.669615 138.07162) (xy 234.669615 138.08536) (xy 234.683345 138.08536)
			(xy 234.683345 138.09909) (xy 234.697075 138.09909) (xy 234.697075 138.11282) (xy 234.710805 138.11282)
			(xy 234.710805 138.12655) (xy 234.724545 138.12655) (xy 234.724545 138.14028) (xy 234.738275 138.14028)
			(xy 234.738275 138.15401) (xy 234.752005 138.15401) (xy 234.752005 138.16775) (xy 234.752005 138.18148)
			(xy 234.765735 138.18148) (xy 234.765735 138.19521) (xy 234.779465 138.19521) (xy 234.779465 138.20894)
			(xy 234.793195 138.20894) (xy 234.793195 138.22267) (xy 234.793195 138.2364) (xy 234.806935 138.2364)
			(xy 234.806935 138.25014) (xy 234.820665 138.25014) (xy 234.820665 138.26387) (xy 234.820665 138.2776)
			(xy 234.834395 138.2776) (xy 234.834395 138.29133) (xy 234.834395 138.30506) (xy 234.848125 138.30506)
			(xy 234.848125 138.31879) (xy 234.861855 138.31879) (xy 234.861855 138.33253) (xy 234.861855 138.34626)
			(xy 234.875585 138.34626) (xy 234.875585 138.35999) (xy 234.875585 138.37372) (xy 234.875585 138.38745)
			(xy 234.889325 138.38745) (xy 234.889325 138.40118) (xy 234.889325 138.41492) (xy 234.903055 138.41492)
			(xy 234.903055 138.42865) (xy 234.903055 138.44238) (xy 234.903055 138.45611) (xy 234.916785 138.45611)
			(xy 234.916785 138.46984) (xy 234.916785 138.48358) (xy 234.916785 138.49731) (xy 234.930515 138.49731)
			(xy 234.930515 138.51104) (xy 234.930515 138.52477) (xy 234.930515 138.5385) (xy 234.930515 138.55224)
			(xy 234.944245 138.55224) (xy 234.944245 138.56597) (xy 234.944245 138.5797) (xy 234.944245 138.59343)
			(xy 234.944245 138.60716) (xy 234.944245 138.62089) (xy 234.944245 138.63463) (xy 234.957975 138.63463)
			(xy 234.957975 138.64836) (xy 234.957975 138.66209) (xy 234.957975 138.67582) (xy 234.957975 138.68955)
			(xy 234.957975 138.70328) (xy 234.957975 138.71702) (xy 234.957975 138.73075) (xy 234.957975 138.74448)
			(xy 234.957975 138.75821) (xy 234.957975 138.77194) (xy 234.957975 138.78567) (xy 234.957975 138.79941)
			(xy 234.957975 138.81314) (xy 234.957975 138.82687) (xy 234.957975 138.8406) (xy 234.944245 138.8406)
			(xy 234.944245 138.85433) (xy 234.944245 138.86806) (xy 234.944245 138.8818) (xy 234.944245 138.89553)
			(xy 234.944245 138.90926) (xy 234.944245 138.92299) (xy 234.930515 138.92299) (xy 234.930515 138.93672)
			(xy 234.930515 138.95045) (xy 234.930515 138.96419) (xy 234.930515 138.97792) (xy 234.916785 138.97792)
			(xy 234.916785 138.99165) (xy 234.916785 139.00538) (xy 234.916785 139.01911) (xy 234.903055 139.01911)
			(xy 234.903055 139.03285) (xy 234.903055 139.04658) (xy 234.903055 139.06031) (xy 234.889325 139.06031)
			(xy 234.889325 139.07404) (xy 234.889325 139.08777) (xy 234.875585 139.08777) (xy 234.875585 139.10151)
			(xy 234.875585 139.11524) (xy 234.861855 139.11524) (xy 234.861855 139.12897) (xy 234.861855 139.1427)
			(xy 234.848125 139.1427) (xy 234.848125 139.15643) (xy 234.848125 139.17016) (xy 234.834395 139.17016)
			(xy 234.834395 139.1839) (xy 234.834395 139.19763) (xy 234.820665 139.19763) (xy 234.820665 139.21136)
			(xy 234.806935 139.21136) (xy 234.806935 139.22509) (xy 234.806935 139.23882) (xy 234.793195 139.23882)
			(xy 234.793195 139.25255) (xy 234.779465 139.25255) (xy 234.779465 139.26629) (xy 234.779465 139.28002)
			(xy 234.765735 139.28002) (xy 234.765735 139.29375) (xy 234.752005 139.29375) (xy 234.752005 139.30748)
			(xy 234.738275 139.30748) (xy 234.738275 139.32121) (xy 234.724545 139.32121) (xy 234.724545 139.33494)
			(xy 234.710805 139.33494) (xy 234.710805 139.34868) (xy 234.697075 139.34868) (xy 234.697075 139.36241)
			(xy 234.683345 139.36241) (xy 234.683345 139.37614) (xy 234.669615 139.37614) (xy 234.669615 139.38987)
			(xy 234.655885 139.38987) (xy 234.655885 139.4036) (xy 234.642155 139.4036) (xy 234.642155 139.41733)
			(xy 234.628415 139.41733) (xy 234.628415 139.43107) (xy 234.614685 139.43107) (xy 234.614685 139.4448)
			(xy 234.587225 139.4448) (xy 234.587225 139.45853) (xy 234.573495 139.45853) (xy 234.573495 139.47226)
			(xy 234.559765 139.47226) (xy 234.559765 139.48599) (xy 234.532295 139.48599) (xy 234.532295 139.49972)
			(xy 234.504835 139.49972) (xy 234.504835 139.51346) (xy 234.491105 139.51346) (xy 234.491105 139.52719)
			(xy 234.463635 139.52719) (xy 234.463635 139.54092) (xy 234.436175 139.54092) (xy 234.436175 139.55465)
			(xy 234.394975 139.55465) (xy 234.394975 139.56838) (xy 234.367515 139.56838) (xy 234.367515 139.58212)
			(xy 234.326315 139.58212) (xy 234.326315 139.59585) (xy 234.271395 139.59585) (xy 234.271395 139.60958)
			(xy 234.202735 139.60958) (xy 234.202735 139.62331) (xy 234.120345 139.62331) (xy 234.120345 139.63704)
			(xy 234.106615 139.63704) (xy 234.106615 139.62331) (xy 234.092885 139.62331) (xy 234.092885 139.63704)
			(xy 234.079145 139.63704) (xy 234.079145 139.62331) (xy 234.065415 139.62331) (xy 234.065415 139.63704)
			(xy 233.969295 139.63704) (xy 233.969295 139.62331) (xy 233.873175 139.62331) (xy 233.873175 139.60958)
			(xy 233.804515 139.60958) (xy 233.804515 139.59585) (xy 233.763315 139.59585) (xy 233.763315 139.58212)
			(xy 233.722125 139.58212) (xy 233.722125 139.56838) (xy 233.680925 139.56838) (xy 233.680925 139.55465)
			(xy 233.653465 139.55465) (xy 233.653465 139.54092) (xy 233.626005 139.54092) (xy 233.626005 139.52719)
			(xy 233.598535 139.52719) (xy 233.598535 139.51346) (xy 233.571075 139.51346) (xy 233.571075 139.49972)
			(xy 233.557345 139.49972) (xy 233.557345 139.48599) (xy 233.529875 139.48599) (xy 233.529875 139.47226)
			(xy 233.516145 139.47226) (xy 233.516145 139.45853) (xy 233.488685 139.45853) (xy 233.488685 139.4448)
			(xy 233.474955 139.4448) (xy 233.474955 139.43107) (xy 233.461225 139.43107) (xy 233.461225 139.41733)
			(xy 233.447485 139.41733) (xy 233.447485 139.4036) (xy 233.420025 139.4036) (xy 233.420025 139.38987)
			(xy 233.406295 139.38987) (xy 233.406295 139.37614) (xy 233.392565 139.37614) (xy 233.392565 139.36241)
			(xy 233.378825 139.36241) (xy 233.378825 139.34868) (xy 233.365095 139.34868) (xy 233.365095 139.33494)
			(xy 233.351365 139.33494) (xy 233.351365 139.32121) (xy 233.351365 139.30748) (xy 233.337635 139.30748)
			(xy 233.337635 139.29375) (xy 233.323905 139.29375) (xy 233.323905 139.28002) (xy 233.310165 139.28002)
			(xy 233.310165 139.26629) (xy 233.296435 139.26629) (xy 233.296435 139.25255) (xy 233.296435 139.23882)
			(xy 233.282705 139.23882) (xy 233.282705 139.22509) (xy 233.268975 139.22509) (xy 233.268975 139.21136)
			(xy 233.268975 139.19763) (xy 233.255245 139.19763) (xy 233.255245 139.1839) (xy 233.255245 139.17016)
			(xy 233.241515 139.17016) (xy 233.241515 139.15643) (xy 233.227775 139.15643) (xy 233.227775 139.1427)
			(xy 233.227775 139.12897) (xy 233.214045 139.12897) (xy 233.214045 139.11524) (xy 233.214045 139.10151)
			(xy 233.200315 139.10151) (xy 233.200315 139.08777) (xy 233.200315 139.07404) (xy 233.200315 139.06031)
			(xy 233.186585 139.06031) (xy 233.186585 139.04658) (xy 233.186585 139.03285) (xy 233.172855 139.03285)
			(xy 233.172855 139.01911) (xy 233.172855 139.00538) (xy 233.172855 138.99165) (xy 233.159125 138.99165)
			(xy 233.159125 138.97792) (xy 233.159125 138.96419) (xy 233.159125 138.95045) (xy 233.159125 138.93672)
			(xy 233.145385 138.93672) (xy 233.145385 138.92299) (xy 233.145385 138.90926) (xy 233.145385 138.89553)
			(xy 233.145385 138.8818) (xy 233.145385 138.86806) (xy 233.131655 138.86806) (xy 233.131655 138.85433)
			(xy 233.131655 138.8406) (xy 233.131655 138.82687) (xy 233.131655 138.81314) (xy 233.131655 138.79941)
			(xy 233.131655 138.78567) (xy 233.131655 138.77194) (xy 233.131655 138.75821) (xy 233.131655 138.74448)
			(xy 233.131655 138.73075) (xy 233.131655 138.71702) (xy 233.131655 138.70328) (xy 233.131655 138.68955)
			(xy 233.131655 138.67582) (xy 233.131655 138.66209) (xy 233.131655 138.64836) (xy 233.131655 138.63463)
			(xy 233.131655 138.62089) (xy 233.131655 138.60716) (xy 233.145385 138.60716) (xy 233.145385 138.59343)
			(xy 233.145385 138.5797) (xy 233.145385 138.56597) (xy 233.145385 138.55224) (xy 233.145385 138.5385)
			(xy 233.159125 138.5385) (xy 233.159125 138.52477) (xy 233.159125 138.51104) (xy 233.159125 138.49731)
			(xy 233.159125 138.48358) (xy 233.172855 138.48358) (xy 233.172855 138.46984) (xy 233.172855 138.45611)
			(xy 233.172855 138.44238) (xy 233.186585 138.44238) (xy 233.186585 138.42865) (xy 233.186585 138.41492)
			(xy 233.186585 138.40118) (xy 233.200315 138.40118) (xy 233.200315 138.38745) (xy 233.200315 138.37372)
			(xy 233.214045 138.37372) (xy 233.214045 138.35999) (xy 233.214045 138.34626) (xy 233.227775 138.34626)
			(xy 233.227775 138.33253) (xy 233.227775 138.31879) (xy 233.241515 138.31879) (xy 233.241515 138.30506)
			(xy 233.241515 138.29133) (xy 233.255245 138.29133) (xy 233.255245 138.2776) (xy 233.255245 138.26387)
			(xy 233.268975 138.26387) (xy 233.268975 138.25014) (xy 233.282705 138.25014) (xy 233.282705 138.2364)
			(xy 233.282705 138.22267) (xy 233.296435 138.22267) (xy 233.296435 138.20894) (xy 233.310165 138.20894)
			(xy 233.310165 138.19521) (xy 233.323905 138.19521) (xy 233.323905 138.18148) (xy 233.323905 138.16775)
			(xy 233.337635 138.16775) (xy 233.337635 138.15401) (xy 233.351365 138.15401) (xy 233.351365 138.14028)
			(xy 233.365095 138.14028) (xy 233.365095 138.12655) (xy 233.378825 138.12655) (xy 233.378825 138.11282)
			(xy 233.392565 138.11282) (xy 233.392565 138.09909) (xy 233.406295 138.09909) (xy 233.406295 138.08536)
			(xy 233.420025 138.08536) (xy 233.420025 138.07162) (xy 233.433755 138.07162) (xy 233.433755 138.05789)
			(xy 233.447485 138.05789) (xy 233.447485 138.04416) (xy 233.461225 138.04416) (xy 233.461225 138.03043)
			(xy 233.488685 138.03043) (xy 233.488685 138.0167) (xy 233.502415 138.0167) (xy 233.502415 138.00296)
			(xy 233.529875 138.00296) (xy 233.529875 137.98923) (xy 233.543615 137.98923) (xy 233.543615 137.9755)
			(xy 233.571075 137.9755) (xy 233.571075 137.96177) (xy 233.584805 137.96177) (xy 233.584805 137.94804)
			(xy 233.612265 137.94804) (xy 233.612265 137.9343) (xy 233.639735 137.9343) (xy 233.639735 137.92057)
			(xy 233.667195 137.92057) (xy 233.667195 137.90684) (xy 233.708395 137.90684) (xy 233.708395 137.89311)
			(xy 233.749585 137.89311) (xy 233.749585 137.87938) (xy 233.790785 137.87938) (xy 233.790785 137.86565)
			(xy 233.845705 137.86565) (xy 233.845705 137.85191) (xy 233.914365 137.85191) (xy 233.914365 137.83818)
			(xy 234.161535 137.83818)
		)
		(stroke
			(width 0)
			(type default)
		)
		(fill yes)
		(layer "F.Cu")
	)
	(gr_poly
		(pts
			(xy 208.208535 130.68394) (xy 208.345845 130.68394) (xy 208.345845 130.69767) (xy 208.400775 130.69767)
			(xy 208.400775 130.71141) (xy 208.455705 130.71141) (xy 208.455705 130.72514) (xy 208.483165 130.72514)
			(xy 208.483165 130.73887) (xy 208.524355 130.73887) (xy 208.524355 130.7526) (xy 208.551825 130.7526)
			(xy 208.551825 130.76633) (xy 208.579285 130.76633) (xy 208.579285 130.78006) (xy 208.606745 130.78006)
			(xy 208.606745 130.7938) (xy 208.634215 130.7938) (xy 208.634215 130.80753) (xy 208.647945 130.80753)
			(xy 208.647945 130.82126) (xy 208.675405 130.82126) (xy 208.675405 130.83499) (xy 208.689145 130.83499)
			(xy 208.689145 130.84872) (xy 208.702875 130.84872) (xy 208.702875 130.86245) (xy 208.730335 130.86245)
			(xy 208.730335 130.87619) (xy 208.744065 130.87619) (xy 208.744065 130.88992) (xy 208.757805 130.88992)
			(xy 208.757805 130.90365) (xy 208.771535 130.90365) (xy 208.771535 130.91738) (xy 208.785265 130.91738)
			(xy 208.785265 130.93111) (xy 208.798995 130.93111) (xy 208.798995 130.94484) (xy 208.812725 130.94484)
			(xy 208.812725 130.95858) (xy 208.826455 130.95858) (xy 208.826455 130.97231) (xy 208.840195 130.97231)
			(xy 208.840195 130.98604) (xy 208.840195 130.99977) (xy 208.853925 130.99977) (xy 208.853925 131.0135)
			(xy 208.867655 131.0135) (xy 208.867655 131.02723) (xy 208.881385 131.02723) (xy 208.881385 131.04097)
			(xy 208.881385 131.0547) (xy 208.895115 131.0547) (xy 208.895115 131.06843) (xy 208.908845 131.06843)
			(xy 208.908845 131.08216) (xy 208.908845 131.09589) (xy 208.922585 131.09589) (xy 208.922585 131.10962)
			(xy 208.922585 131.12336) (xy 208.936315 131.12336) (xy 208.936315 131.13709) (xy 208.936315 131.15082)
			(xy 208.950045 131.15082) (xy 208.950045 131.16455) (xy 208.950045 131.17828) (xy 208.963775 131.17828)
			(xy 208.963775 131.19202) (xy 208.963775 131.20575) (xy 208.963775 131.21948) (xy 208.977505 131.21948)
			(xy 208.977505 131.23321) (xy 208.977505 131.24694) (xy 208.991235 131.24694) (xy 208.991235 131.26068)
			(xy 208.991235 131.27441) (xy 208.991235 131.28814) (xy 208.991235 131.30187) (xy 209.004975 131.30187)
			(xy 209.004975 131.3156) (xy 209.004975 131.32933) (xy 209.004975 131.34307) (xy 209.004975 131.3568)
			(xy 209.004975 131.37053) (xy 209.018705 131.37053) (xy 209.018705 131.38426) (xy 209.018705 131.39799)
			(xy 209.018705 131.41172) (xy 209.018705 131.42546) (xy 209.018705 131.43919) (xy 209.018705 131.45292)
			(xy 209.018705 131.46665) (xy 209.018705 131.48038) (xy 209.018705 131.49411) (xy 209.018705 131.50785)
			(xy 209.018705 131.52158) (xy 209.018705 131.53531) (xy 209.018705 131.54904) (xy 209.018705 131.56277)
			(xy 209.018705 131.5765) (xy 209.018705 131.59024) (xy 209.018705 131.60397) (xy 209.018705 131.6177)
			(xy 209.018705 131.63143) (xy 209.018705 131.64516) (xy 209.018705 131.6589) (xy 209.018705 131.67263)
			(xy 209.018705 131.68636) (xy 209.018705 131.70009) (xy 209.018705 131.71382) (xy 209.018705 131.72756)
			(xy 209.018705 131.74129) (xy 209.018705 131.75502) (xy 209.018705 131.76875) (xy 209.018705 131.78248)
			(xy 209.018705 131.79621) (xy 209.018705 131.80995) (xy 209.018705 131.82368) (xy 209.018705 131.83741)
			(xy 209.018705 131.85114) (xy 209.018705 131.86487) (xy 209.018705 131.8786) (xy 209.018705 131.89233)
			(xy 209.018705 131.90607) (xy 209.018705 131.9198) (xy 209.018705 131.93353) (xy 209.018705 131.94726)
			(xy 209.018705 131.96099) (xy 209.018705 131.97472) (xy 209.018705 131.98846) (xy 209.018705 132.00219)
			(xy 209.018705 132.01592) (xy 209.018705 132.02965) (xy 209.018705 132.04338) (xy 209.018705 132.05711)
			(xy 209.018705 132.07085) (xy 209.018705 132.08458) (xy 209.018705 132.09831) (xy 209.018705 132.11204)
			(xy 209.018705 132.12577) (xy 209.018705 132.13951) (xy 209.018705 132.15324) (xy 209.018705 132.16697)
			(xy 209.018705 132.1807) (xy 209.018705 132.19443) (xy 209.018705 132.20817) (xy 209.018705 132.2219)
			(xy 209.018705 132.23563) (xy 209.018705 132.24936) (xy 209.018705 132.26309) (xy 209.018705 132.27682)
			(xy 209.018705 132.29056) (xy 209.018705 132.30429) (xy 209.018705 132.31802) (xy 209.018705 132.33175)
			(xy 209.018705 132.34548) (xy 209.018705 132.35921) (xy 209.018705 132.37295) (xy 209.018705 132.38668)
			(xy 209.018705 132.40041) (xy 209.018705 132.41414) (xy 209.018705 132.42787) (xy 209.018705 132.4416)
			(xy 209.018705 132.45534) (xy 209.018705 132.46907) (xy 209.018705 132.4828) (xy 209.018705 132.49653)
			(xy 209.018705 132.51026) (xy 209.018705 132.52399) (xy 209.018705 132.53773) (xy 209.018705 132.55146)
			(xy 209.018705 132.56519) (xy 209.018705 132.57892) (xy 209.018705 132.59265) (xy 209.018705 132.60638)
			(xy 209.018705 132.62012) (xy 209.018705 132.63385) (xy 209.018705 132.64758) (xy 209.018705 132.66131)
			(xy 209.018705 132.67504) (xy 209.018705 132.68878) (xy 209.018705 132.70251) (xy 209.018705 132.71624)
			(xy 209.018705 132.72997) (xy 209.018705 132.7437) (xy 209.018705 132.75744) (xy 209.018705 132.77117)
			(xy 209.018705 132.7849) (xy 209.018705 132.79863) (xy 209.018705 132.81236) (xy 209.018705 132.82609)
			(xy 209.018705 132.83983) (xy 209.018705 132.85356) (xy 209.018705 132.86729) (xy 209.018705 132.88102)
			(xy 209.018705 132.89475) (xy 209.018705 132.90848) (xy 209.018705 132.92222) (xy 209.018705 132.93595)
			(xy 209.018705 132.94968) (xy 209.018705 132.96341) (xy 209.018705 132.97714) (xy 209.018705 132.99087)
			(xy 209.018705 133.00461) (xy 209.018705 133.01834) (xy 209.018705 133.03207) (xy 209.018705 133.0458)
			(xy 209.018705 133.05953) (xy 209.018705 133.07326) (xy 209.018705 133.087) (xy 209.018705 133.10073)
			(xy 209.018705 133.11446) (xy 209.018705 133.12819) (xy 209.018705 133.14192) (xy 209.018705 133.15565)
			(xy 209.018705 133.16939) (xy 209.018705 133.18312) (xy 209.018705 133.19685) (xy 209.018705 133.21058)
			(xy 209.018705 133.22431) (xy 209.018705 133.23805) (xy 209.018705 133.25178) (xy 209.018705 133.26551)
			(xy 209.018705 133.27924) (xy 209.018705 133.29297) (xy 209.018705 133.30671) (xy 209.018705 133.32044)
			(xy 209.018705 133.33417) (xy 209.018705 133.3479) (xy 209.018705 133.36163) (xy 209.018705 133.37536)
			(xy 209.018705 133.3891) (xy 209.018705 133.40283) (xy 209.018705 133.41656) (xy 209.018705 133.43029)
			(xy 209.018705 133.44402) (xy 209.018705 133.45775) (xy 209.018705 133.47149) (xy 209.018705 133.48522)
			(xy 209.018705 133.49895) (xy 209.018705 133.51268) (xy 209.018705 133.52641) (xy 209.018705 133.54014)
			(xy 209.018705 133.55388) (xy 209.018705 133.56761) (xy 209.018705 133.58134) (xy 209.018705 133.59507)
			(xy 209.018705 133.6088) (xy 209.018705 133.62253) (xy 209.018705 133.63627) (xy 209.018705 133.65)
			(xy 209.018705 133.66373) (xy 209.018705 133.67746) (xy 209.018705 133.69119) (xy 209.018705 133.70493)
			(xy 209.018705 133.71866) (xy 209.018705 133.73239) (xy 209.018705 133.74612) (xy 209.018705 133.75985)
			(xy 209.018705 133.77359) (xy 209.018705 133.78732) (xy 209.018705 133.80105) (xy 209.018705 133.81478)
			(xy 209.018705 133.82851) (xy 209.018705 133.84224) (xy 209.018705 133.85598) (xy 209.018705 133.86971)
			(xy 209.018705 133.88344) (xy 209.018705 133.89717) (xy 209.018705 133.9109) (xy 209.018705 133.92463)
			(xy 209.018705 133.93837) (xy 209.018705 133.9521) (xy 209.018705 133.96583) (xy 209.018705 133.97956)
			(xy 209.018705 133.99329) (xy 209.018705 134.00702) (xy 209.018705 134.02076) (xy 209.018705 134.03449)
			(xy 209.018705 134.04822) (xy 209.018705 134.06195) (xy 209.018705 134.07568) (xy 209.018705 134.08941)
			(xy 209.018705 134.10315) (xy 209.018705 134.11688) (xy 209.018705 134.13061) (xy 209.018705 134.14434)
			(xy 209.018705 134.15807) (xy 209.018705 134.1718) (xy 209.018705 134.18554) (xy 209.018705 134.19927)
			(xy 209.018705 134.213) (xy 209.018705 134.22673) (xy 209.018705 134.24046) (xy 209.018705 134.2542)
			(xy 209.018705 134.26793) (xy 209.018705 134.28166) (xy 209.018705 134.29539) (xy 209.018705 134.30912)
			(xy 209.018705 134.32286) (xy 209.018705 134.33659) (xy 209.018705 134.35032) (xy 209.018705 134.36405)
			(xy 209.018705 134.37778) (xy 209.018705 134.39151) (xy 209.018705 134.40525) (xy 209.018705 134.41898)
			(xy 209.018705 134.43271) (xy 209.018705 134.44644) (xy 209.018705 134.46017) (xy 209.018705 134.4739)
			(xy 209.018705 134.48764) (xy 209.018705 134.50137) (xy 209.018705 134.5151) (xy 209.018705 134.52883)
			(xy 209.018705 134.54256) (xy 209.018705 134.55629) (xy 209.018705 134.57003) (xy 209.018705 134.58376)
			(xy 209.018705 134.59749) (xy 209.018705 134.61122) (xy 209.018705 134.62495) (xy 209.018705 134.63868)
			(xy 209.018705 134.65242) (xy 209.018705 134.66615) (xy 209.018705 134.67988) (xy 209.018705 134.69361)
			(xy 209.018705 134.70734) (xy 209.018705 134.72107) (xy 209.018705 134.73481) (xy 209.018705 134.74854)
			(xy 209.018705 134.76227) (xy 209.018705 134.776) (xy 209.018705 134.78973) (xy 209.018705 134.80347)
			(xy 209.018705 134.8172) (xy 209.018705 134.83093) (xy 209.018705 134.84466) (xy 209.018705 134.85839)
			(xy 209.018705 134.87213) (xy 209.018705 134.88586) (xy 209.018705 134.89959) (xy 209.018705 134.91332)
			(xy 209.018705 134.92705) (xy 209.018705 134.94078) (xy 209.018705 134.95452) (xy 209.018705 134.96825)
			(xy 209.018705 134.98198) (xy 209.018705 134.99571) (xy 209.018705 135.00944) (xy 209.018705 135.02317)
			(xy 209.018705 135.03691) (xy 209.018705 135.05064) (xy 209.018705 135.06437) (xy 209.018705 135.0781)
			(xy 209.018705 135.09183) (xy 209.018705 135.10556) (xy 209.018705 135.1193) (xy 209.018705 135.13303)
			(xy 209.018705 135.14676) (xy 209.018705 135.16049) (xy 209.018705 135.17422) (xy 209.018705 135.18795)
			(xy 209.018705 135.20169) (xy 209.018705 135.21542) (xy 209.018705 135.22915) (xy 209.018705 135.24288)
			(xy 209.018705 135.25661) (xy 209.018705 135.27034) (xy 209.018705 135.28408) (xy 209.018705 135.29781)
			(xy 209.018705 135.31154) (xy 209.018705 135.32527) (xy 209.018705 135.339) (xy 209.018705 135.35274)
			(xy 209.018705 135.36647) (xy 209.018705 135.3802) (xy 209.018705 135.39393) (xy 209.018705 135.40766)
			(xy 209.018705 135.4214) (xy 209.018705 135.43513) (xy 209.018705 135.44886) (xy 209.018705 135.46259)
			(xy 209.018705 135.47632) (xy 209.018705 135.49005) (xy 209.018705 135.50379) (xy 209.018705 135.51752)
			(xy 209.018705 135.53125) (xy 209.018705 135.54498) (xy 209.018705 135.55871) (xy 209.018705 135.57244)
			(xy 209.018705 135.58618) (xy 209.018705 135.59991) (xy 209.018705 135.61364) (xy 209.018705 135.62737)
			(xy 209.018705 135.6411) (xy 209.018705 135.65483) (xy 209.018705 135.66857) (xy 209.018705 135.6823)
			(xy 209.018705 135.69603) (xy 209.018705 135.70976) (xy 209.018705 135.72349) (xy 209.018705 135.73722)
			(xy 209.018705 135.75096) (xy 209.018705 135.76469) (xy 209.018705 135.77842) (xy 209.018705 135.79215)
			(xy 209.018705 135.80588) (xy 209.018705 135.81961) (xy 209.018705 135.83335) (xy 209.018705 135.84708)
			(xy 209.018705 135.86081) (xy 209.018705 135.87454) (xy 209.018705 135.88827) (xy 209.018705 135.90201)
			(xy 209.018705 135.91574) (xy 209.018705 135.92947) (xy 209.018705 135.9432) (xy 209.018705 135.95693)
			(xy 209.018705 135.97067) (xy 209.018705 135.9844) (xy 209.018705 135.99813) (xy 209.018705 136.01186)
			(xy 209.018705 136.02559) (xy 209.018705 136.03932) (xy 209.018705 136.05306) (xy 209.018705 136.06679)
			(xy 209.018705 136.08052) (xy 209.018705 136.09425) (xy 209.018705 136.10798) (xy 209.018705 136.12171)
			(xy 209.018705 136.13545) (xy 209.018705 136.14918) (xy 209.018705 136.16291) (xy 209.018705 136.17664)
			(xy 209.018705 136.19037) (xy 209.018705 136.2041) (xy 209.018705 136.21784) (xy 209.018705 136.23157)
			(xy 209.018705 136.2453) (xy 209.018705 136.25903) (xy 209.018705 136.27276) (xy 209.018705 136.28649)
			(xy 209.018705 136.30023) (xy 209.018705 136.31396) (xy 209.018705 136.32769) (xy 209.018705 136.34142)
			(xy 209.018705 136.35515) (xy 209.018705 136.36889) (xy 209.018705 136.38262) (xy 209.018705 136.39635)
			(xy 209.018705 136.41008) (xy 209.018705 136.42381) (xy 209.018705 136.43755) (xy 209.018705 136.45128)
			(xy 209.018705 136.46501) (xy 209.018705 136.47874) (xy 209.018705 136.49247) (xy 209.018705 136.5062)
			(xy 209.018705 136.51994) (xy 209.018705 136.53367) (xy 209.018705 136.5474) (xy 209.018705 136.56113)
			(xy 209.018705 136.57486) (xy 209.018705 136.58859) (xy 209.018705 136.60233) (xy 209.018705 136.61606)
			(xy 209.018705 136.62979) (xy 209.018705 136.64352) (xy 209.018705 136.65725) (xy 209.018705 136.67098)
			(xy 209.018705 136.68472) (xy 209.018705 136.69845) (xy 209.018705 136.71218) (xy 209.018705 136.72591)
			(xy 209.018705 136.73964) (xy 209.018705 136.75337) (xy 209.018705 136.76711) (xy 209.018705 136.78084)
			(xy 209.018705 136.79457) (xy 209.018705 136.8083) (xy 209.018705 136.82203) (xy 209.018705 136.83576)
			(xy 209.018705 136.8495) (xy 209.018705 136.86323) (xy 209.018705 136.87696) (xy 209.018705 136.89069)
			(xy 209.018705 136.90442) (xy 209.018705 136.91816) (xy 209.018705 136.93189) (xy 209.018705 136.94562)
			(xy 209.018705 136.95935) (xy 209.018705 136.97308) (xy 209.018705 136.98682) (xy 209.018705 137.00055)
			(xy 209.018705 137.01428) (xy 209.018705 137.02801) (xy 209.018705 137.04174) (xy 209.018705 137.05547)
			(xy 209.018705 137.06921) (xy 209.018705 137.08294) (xy 209.018705 137.09667) (xy 209.018705 137.1104)
			(xy 209.018705 137.12413) (xy 209.018705 137.13786) (xy 209.018705 137.1516) (xy 209.018705 137.16533)
			(xy 209.018705 137.17906) (xy 209.018705 137.19279) (xy 209.018705 137.20652) (xy 209.018705 137.22025)
			(xy 209.018705 137.23399) (xy 209.018705 137.24772) (xy 209.018705 137.26145) (xy 209.018705 137.27518)
			(xy 209.018705 137.28891) (xy 209.018705 137.30264) (xy 209.018705 137.31638) (xy 209.018705 137.33011)
			(xy 209.018705 137.34384) (xy 209.018705 137.35757) (xy 209.018705 137.3713) (xy 209.018705 137.38503)
			(xy 209.018705 137.39877) (xy 209.018705 137.4125) (xy 209.018705 137.42623) (xy 209.018705 137.43996)
			(xy 209.018705 137.45369) (xy 209.018705 137.46743) (xy 209.018705 137.48116) (xy 209.018705 137.49489)
			(xy 209.018705 137.50862) (xy 209.018705 137.52235) (xy 209.018705 137.53609) (xy 209.018705 137.54982)
			(xy 209.018705 137.56355) (xy 209.018705 137.57728) (xy 209.018705 137.59101) (xy 209.018705 137.60474)
			(xy 209.018705 137.61848) (xy 209.018705 137.63221) (xy 209.018705 137.64594) (xy 209.018705 137.65967)
			(xy 209.018705 137.6734) (xy 209.018705 137.68713) (xy 209.018705 137.70087) (xy 209.018705 137.7146)
			(xy 209.018705 137.72833) (xy 209.018705 137.74206) (xy 209.018705 137.75579) (xy 209.018705 137.76952)
			(xy 209.018705 137.78326) (xy 209.018705 137.79699) (xy 209.018705 137.81072) (xy 209.018705 137.82445)
			(xy 209.018705 137.83818) (xy 209.018705 137.85191) (xy 209.018705 137.86565) (xy 209.018705 137.87938)
			(xy 209.018705 137.89311) (xy 209.018705 137.90684) (xy 209.018705 137.92057) (xy 209.018705 137.9343)
			(xy 209.018705 137.94804) (xy 209.018705 137.96177) (xy 209.018705 137.9755) (xy 209.018705 137.98923)
			(xy 209.018705 138.00296) (xy 209.018705 138.0167) (xy 209.018705 138.03043) (xy 209.018705 138.04416)
			(xy 209.018705 138.05789) (xy 209.018705 138.07162) (xy 209.018705 138.08536) (xy 209.018705 138.09909)
			(xy 209.018705 138.11282) (xy 209.018705 138.12655) (xy 209.018705 138.14028) (xy 209.018705 138.15401)
			(xy 209.018705 138.16775) (xy 209.018705 138.18148) (xy 209.018705 138.19521) (xy 209.018705 138.20894)
			(xy 209.018705 138.22267) (xy 209.018705 138.2364) (xy 209.018705 138.25014) (xy 209.018705 138.26387)
			(xy 209.018705 138.2776) (xy 209.018705 138.29133) (xy 209.018705 138.30506) (xy 209.018705 138.31879)
			(xy 209.018705 138.33253) (xy 209.018705 138.34626) (xy 209.018705 138.35999) (xy 209.018705 138.37372)
			(xy 209.018705 138.38745) (xy 209.018705 138.40118) (xy 209.018705 138.41492) (xy 209.018705 138.42865)
			(xy 209.018705 138.44238) (xy 209.018705 138.45611) (xy 209.018705 138.46984) (xy 209.018705 138.48358)
			(xy 209.018705 138.49731) (xy 209.018705 138.51104) (xy 209.018705 138.52477) (xy 209.018705 138.5385)
			(xy 209.018705 138.55224) (xy 209.018705 138.56597) (xy 209.018705 138.5797) (xy 209.018705 138.59343)
			(xy 209.018705 138.60716) (xy 209.018705 138.62089) (xy 209.018705 138.63463) (xy 209.018705 138.64836)
			(xy 209.018705 138.66209) (xy 209.018705 138.67582) (xy 209.018705 138.68955) (xy 209.018705 138.70328)
			(xy 209.018705 138.71702) (xy 209.018705 138.73075) (xy 209.018705 138.74448) (xy 209.018705 138.75821)
			(xy 209.018705 138.77194) (xy 209.018705 138.78567) (xy 209.018705 138.79941) (xy 209.018705 138.81314)
			(xy 209.018705 138.82687) (xy 209.018705 138.8406) (xy 209.018705 138.85433) (xy 209.018705 138.86806)
			(xy 209.018705 138.8818) (xy 209.018705 138.89553) (xy 209.018705 138.90926) (xy 209.018705 138.92299)
			(xy 209.018705 138.93672) (xy 209.018705 138.95045) (xy 209.018705 138.96419) (xy 209.018705 138.97792)
			(xy 209.018705 138.99165) (xy 209.018705 139.00538) (xy 209.018705 139.01911) (xy 209.018705 139.03285)
			(xy 209.018705 139.04658) (xy 209.018705 139.06031) (xy 209.018705 139.07404) (xy 209.018705 139.08777)
			(xy 209.018705 139.10151) (xy 209.018705 139.11524) (xy 209.018705 139.12897) (xy 209.018705 139.1427)
			(xy 209.018705 139.15643) (xy 209.018705 139.17016) (xy 209.018705 139.1839) (xy 209.018705 139.19763)
			(xy 209.018705 139.21136) (xy 209.018705 139.22509) (xy 209.018705 139.23882) (xy 209.018705 139.25255)
			(xy 209.018705 139.26629) (xy 209.018705 139.28002) (xy 209.018705 139.29375) (xy 209.018705 139.30748)
			(xy 209.018705 139.32121) (xy 209.018705 139.33494) (xy 209.018705 139.34868) (xy 209.018705 139.36241)
			(xy 209.018705 139.37614) (xy 209.018705 139.38987) (xy 209.018705 139.4036) (xy 209.018705 139.41733)
			(xy 209.018705 139.43107) (xy 209.018705 139.4448) (xy 209.018705 139.45853) (xy 209.018705 139.47226)
			(xy 209.018705 139.48599) (xy 209.018705 139.49972) (xy 209.018705 139.51346) (xy 209.018705 139.52719)
			(xy 209.018705 139.54092) (xy 209.018705 139.55465) (xy 209.018705 139.56838) (xy 209.018705 139.58212)
			(xy 209.018705 139.59585) (xy 209.018705 139.60958) (xy 209.018705 139.62331) (xy 209.018705 139.63704)
			(xy 209.018705 139.65078) (xy 209.018705 139.66451) (xy 209.018705 139.67824) (xy 209.018705 139.69197)
			(xy 209.018705 139.7057) (xy 209.018705 139.71943) (xy 209.018705 139.73317) (xy 209.018705 139.7469)
			(xy 209.018705 139.76063) (xy 209.018705 139.77436) (xy 209.018705 139.78809) (xy 209.018705 139.80182)
			(xy 209.018705 139.81556) (xy 209.018705 139.82929) (xy 209.018705 139.84302) (xy 209.018705 139.85675)
			(xy 209.018705 139.87048) (xy 209.018705 139.88421) (xy 209.018705 139.89795) (xy 209.018705 139.91168)
			(xy 209.018705 139.92541) (xy 209.018705 139.93914) (xy 209.018705 139.95287) (xy 209.018705 139.9666)
			(xy 209.018705 139.98034) (xy 209.018705 139.99407) (xy 209.018705 140.0078) (xy 209.018705 140.02153)
			(xy 209.018705 140.03526) (xy 209.018705 140.04899) (xy 209.018705 140.06273) (xy 209.018705 140.07646)
			(xy 209.018705 140.09019) (xy 209.018705 140.10392) (xy 209.018705 140.11765) (xy 209.018705 140.13139)
			(xy 209.018705 140.14512) (xy 209.018705 140.15885) (xy 209.018705 140.17258) (xy 209.018705 140.18631)
			(xy 209.018705 140.20005) (xy 209.018705 140.21378) (xy 209.018705 140.22751) (xy 209.018705 140.24124)
			(xy 209.018705 140.25497) (xy 209.018705 140.2687) (xy 209.018705 140.28244) (xy 209.018705 140.29617)
			(xy 209.018705 140.3099) (xy 209.018705 140.32363) (xy 209.018705 140.33736) (xy 209.018705 140.35109)
			(xy 209.018705 140.36483) (xy 209.018705 140.37856) (xy 209.018705 140.39229) (xy 209.018705 140.40602)
			(xy 209.018705 140.41975) (xy 209.018705 140.43348) (xy 209.018705 140.44722) (xy 209.018705 140.46095)
			(xy 209.018705 140.47468) (xy 209.018705 140.48841) (xy 209.018705 140.50214) (xy 209.018705 140.51587)
			(xy 209.018705 140.5296) (xy 209.018705 140.54334) (xy 209.018705 140.55707) (xy 209.018705 140.5708)
			(xy 209.018705 140.58453) (xy 209.018705 140.59827) (xy 209.018705 140.612) (xy 209.018705 140.62573)
			(xy 209.018705 140.63946) (xy 209.018705 140.65319) (xy 209.018705 140.66693) (xy 209.018705 140.68066)
			(xy 209.018705 140.69439) (xy 209.018705 140.70812) (xy 209.018705 140.72185) (xy 209.018705 140.73558)
			(xy 209.018705 140.74931) (xy 209.018705 140.76305) (xy 209.018705 140.77678) (xy 209.018705 140.79051)
			(xy 209.018705 140.80424) (xy 209.018705 140.81797) (xy 209.018705 140.8317) (xy 209.018705 140.84544)
			(xy 209.018705 140.85917) (xy 209.018705 140.8729) (xy 209.018705 140.88663) (xy 209.018705 140.90036)
			(xy 209.018705 140.91409) (xy 209.018705 140.92783) (xy 209.018705 140.94156) (xy 209.018705 140.95529)
			(xy 209.018705 140.96902) (xy 209.018705 140.98275) (xy 209.018705 140.99648) (xy 209.018705 141.01022)
			(xy 209.018705 141.02395) (xy 209.018705 141.03768) (xy 209.018705 141.05141) (xy 209.018705 141.06514)
			(xy 209.018705 141.07888) (xy 209.018705 141.09261) (xy 209.018705 141.10634) (xy 209.018705 141.12007)
			(xy 209.018705 141.1338) (xy 209.018705 141.14754) (xy 209.018705 141.16127) (xy 209.018705 141.175)
			(xy 209.018705 141.18873) (xy 209.018705 141.20246) (xy 209.018705 141.21619) (xy 209.018705 141.22993)
			(xy 209.018705 141.24366) (xy 209.018705 141.25739) (xy 209.018705 141.27112) (xy 209.018705 141.28485)
			(xy 209.018705 141.29858) (xy 209.018705 141.31232) (xy 209.018705 141.32605) (xy 209.018705 141.33978)
			(xy 209.018705 141.35351) (xy 209.018705 141.36724) (xy 209.018705 141.38097) (xy 209.018705 141.39471)
			(xy 209.018705 141.40844) (xy 209.018705 141.42217) (xy 209.018705 141.4359) (xy 209.018705 141.44963)
			(xy 209.018705 141.46336) (xy 209.018705 141.4771) (xy 209.018705 141.49083) (xy 209.018705 141.50456)
			(xy 209.018705 141.51829) (xy 209.018705 141.53202) (xy 209.018705 141.54575) (xy 209.018705 141.55949)
			(xy 209.018705 141.57322) (xy 209.018705 141.58695) (xy 209.018705 141.60068) (xy 209.018705 141.61441)
			(xy 209.018705 141.62815) (xy 209.018705 141.64188) (xy 209.018705 141.65561) (xy 209.018705 141.66934)
			(xy 209.018705 141.68307) (xy 209.018705 141.69681) (xy 209.018705 141.71054) (xy 209.018705 141.72427)
			(xy 209.018705 141.738) (xy 209.018705 141.75173) (xy 209.018705 141.76546) (xy 209.018705 141.7792)
			(xy 209.018705 141.79293) (xy 209.018705 141.80666) (xy 209.018705 141.82039) (xy 209.018705 141.83412)
			(xy 209.018705 141.84785) (xy 209.018705 141.86159) (xy 209.018705 141.87532) (xy 209.018705 141.88905)
			(xy 209.018705 141.90278) (xy 209.018705 141.91651) (xy 209.018705 141.93024) (xy 209.018705 141.94398)
			(xy 209.018705 141.95771) (xy 209.018705 141.97144) (xy 209.018705 141.98517) (xy 209.018705 141.9989)
			(xy 209.018705 142.01263) (xy 209.018705 142.02637) (xy 209.018705 142.0401) (xy 209.018705 142.05383)
			(xy 209.018705 142.06756) (xy 209.018705 142.08129) (xy 209.018705 142.09502) (xy 209.018705 142.10876)
			(xy 209.018705 142.12249) (xy 209.018705 142.13622) (xy 209.018705 142.14995) (xy 209.018705 142.16368)
			(xy 209.018705 142.17742) (xy 209.018705 142.19115) (xy 209.018705 142.20488) (xy 209.018705 142.21861)
			(xy 209.018705 142.23234) (xy 209.018705 142.24608) (xy 209.018705 142.25981) (xy 209.018705 142.27354)
			(xy 209.018705 142.28727) (xy 209.018705 142.301) (xy 209.018705 142.31473) (xy 209.018705 142.32847)
			(xy 209.018705 142.3422) (xy 209.018705 142.35593) (xy 209.018705 142.36966) (xy 209.018705 142.38339)
			(xy 209.018705 142.39712) (xy 209.018705 142.41086) (xy 209.018705 142.42459) (xy 209.018705 142.43832)
			(xy 209.018705 142.45205) (xy 209.018705 142.46578) (xy 209.018705 142.47951) (xy 209.018705 142.49325)
			(xy 209.018705 142.50698) (xy 209.018705 142.52071) (xy 209.018705 142.53444) (xy 209.018705 142.54817)
			(xy 209.018705 142.5619) (xy 209.018705 142.57564) (xy 209.018705 142.58937) (xy 209.018705 142.6031)
			(xy 209.018705 142.61683) (xy 209.018705 142.63056) (xy 209.018705 142.64429) (xy 209.018705 142.65803)
			(xy 209.018705 142.67176) (xy 209.018705 142.68549) (xy 209.018705 142.69922) (xy 209.018705 142.71295)
			(xy 209.018705 142.72669) (xy 209.018705 142.74042) (xy 209.018705 142.75415) (xy 209.018705 142.76788)
			(xy 209.018705 142.78161) (xy 209.018705 142.79535) (xy 209.018705 142.80908) (xy 209.018705 142.82281)
			(xy 209.018705 142.83654) (xy 209.018705 142.85027) (xy 209.018705 142.864) (xy 209.018705 142.87774)
			(xy 209.018705 142.89147) (xy 209.018705 142.9052) (xy 209.018705 142.91893) (xy 209.018705 142.93266)
			(xy 209.018705 142.94639) (xy 209.018705 142.96013) (xy 209.018705 142.97386) (xy 209.018705 142.98759)
			(xy 209.018705 143.00132) (xy 209.018705 143.01505) (xy 209.018705 143.02878) (xy 209.018705 143.04252)
			(xy 209.018705 143.05625) (xy 209.018705 143.06998) (xy 209.018705 143.08371) (xy 209.018705 143.09744)
			(xy 209.018705 143.11117) (xy 209.018705 143.12491) (xy 209.018705 143.13864) (xy 209.018705 143.15237)
			(xy 209.018705 143.1661) (xy 209.018705 143.17983) (xy 209.018705 143.19357) (xy 209.018705 143.2073)
			(xy 209.018705 143.22103) (xy 209.018705 143.23476) (xy 209.018705 143.24849) (xy 209.018705 143.26223)
			(xy 209.018705 143.27596) (xy 209.018705 143.28969) (xy 209.018705 143.30342) (xy 209.018705 143.31715)
			(xy 209.018705 143.33088) (xy 209.018705 143.34462) (xy 209.018705 143.35835) (xy 209.018705 143.37208)
			(xy 209.018705 143.38581) (xy 209.018705 143.39954) (xy 209.018705 143.41327) (xy 209.018705 143.42701)
			(xy 209.018705 143.44074) (xy 209.018705 143.45447) (xy 209.018705 143.4682) (xy 209.018705 143.48193)
			(xy 209.018705 143.49566) (xy 209.018705 143.5094) (xy 209.018705 143.52313) (xy 209.018705 143.53686)
			(xy 209.018705 143.55059) (xy 209.018705 143.56432) (xy 209.018705 143.57805) (xy 209.018705 143.59179)
			(xy 209.018705 143.60552) (xy 209.018705 143.61925) (xy 209.018705 143.63298) (xy 209.018705 143.64671)
			(xy 209.018705 143.66044) (xy 209.018705 143.67418) (xy 209.018705 143.68791) (xy 209.018705 143.70164)
			(xy 209.018705 143.71537) (xy 209.018705 143.7291) (xy 209.018705 143.74284) (xy 209.018705 143.75657)
			(xy 209.018705 143.7703) (xy 209.018705 143.78403) (xy 209.018705 143.79776) (xy 209.018705 143.8115)
			(xy 209.018705 143.82523) (xy 209.018705 143.83896) (xy 209.018705 143.85269) (xy 209.018705 143.86642)
			(xy 209.018705 143.88015) (xy 209.018705 143.89389) (xy 209.018705 143.90762) (xy 209.018705 143.92135)
			(xy 209.018705 143.93508) (xy 209.018705 143.94881) (xy 209.018705 143.96254) (xy 209.018705 143.97628)
			(xy 209.018705 143.99001) (xy 209.018705 144.00374) (xy 209.018705 144.01747) (xy 209.018705 144.0312)
			(xy 209.018705 144.04493) (xy 209.018705 144.05867) (xy 209.018705 144.0724) (xy 209.018705 144.08613)
			(xy 209.018705 144.09986) (xy 209.018705 144.11359) (xy 209.018705 144.12732) (xy 209.018705 144.14106)
			(xy 209.018705 144.15479) (xy 209.018705 144.16852) (xy 209.018705 144.18225) (xy 209.018705 144.19598)
			(xy 209.018705 144.20971) (xy 209.018705 144.22345) (xy 209.018705 144.23718) (xy 209.018705 144.25091)
			(xy 209.018705 144.26464) (xy 209.018705 144.27837) (xy 209.018705 144.29211) (xy 209.018705 144.30584)
			(xy 209.018705 144.31957) (xy 209.018705 144.3333) (xy 209.018705 144.34703) (xy 209.018705 144.36077)
			(xy 209.018705 144.3745) (xy 209.018705 144.38823) (xy 209.018705 144.40196) (xy 209.018705 144.41569)
			(xy 209.018705 144.42942) (xy 209.018705 144.44316) (xy 209.018705 144.45689) (xy 209.018705 144.47062)
			(xy 209.018705 144.48435) (xy 209.018705 144.49808) (xy 209.018705 144.51181) (xy 209.018705 144.52555)
			(xy 209.018705 144.53928) (xy 209.018705 144.55301) (xy 209.018705 144.56674) (xy 209.018705 144.58047)
			(xy 209.018705 144.5942) (xy 209.018705 144.60794) (xy 209.018705 144.62167) (xy 209.018705 144.6354)
			(xy 209.018705 144.64913) (xy 209.018705 144.66286) (xy 209.018705 144.67659) (xy 209.018705 144.69033)
			(xy 209.018705 144.70406) (xy 209.018705 144.71779) (xy 209.018705 144.73152) (xy 209.018705 144.74525)
			(xy 209.018705 144.75898) (xy 209.018705 144.77272) (xy 209.018705 144.78645) (xy 209.018705 144.80018)
			(xy 209.018705 144.81391) (xy 209.018705 144.82764) (xy 209.018705 144.84138) (xy 209.018705 144.85511)
			(xy 209.018705 144.86884) (xy 209.018705 144.88257) (xy 209.018705 144.8963) (xy 209.018705 144.91004)
			(xy 209.018705 144.92377) (xy 209.018705 144.9375) (xy 209.018705 144.95123) (xy 209.018705 144.96496)
			(xy 209.018705 144.97869) (xy 209.018705 144.99243) (xy 209.018705 145.00616) (xy 209.018705 145.01989)
			(xy 209.018705 145.03362) (xy 209.018705 145.04735) (xy 209.018705 145.06108) (xy 209.018705 145.07482)
			(xy 209.018705 145.08855) (xy 209.018705 145.10228) (xy 209.018705 145.11601) (xy 209.018705 145.12974)
			(xy 209.018705 145.14347) (xy 209.018705 145.15721) (xy 209.018705 145.17094) (xy 209.018705 145.18467)
			(xy 209.018705 145.1984) (xy 209.018705 145.21213) (xy 209.018705 145.22586) (xy 209.018705 145.2396)
			(xy 209.018705 145.25333) (xy 209.018705 145.26706) (xy 209.018705 145.28079) (xy 209.018705 145.29452)
			(xy 209.018705 145.30826) (xy 209.018705 145.32199) (xy 209.018705 145.33572) (xy 209.018705 145.34945)
			(xy 209.018705 145.36318) (xy 209.018705 145.37692) (xy 209.018705 145.39065) (xy 209.018705 145.40438)
			(xy 209.018705 145.41811) (xy 209.018705 145.43184) (xy 209.018705 145.44557) (xy 209.018705 145.45931)
			(xy 209.018705 145.47304) (xy 209.018705 145.48677) (xy 209.018705 145.5005) (xy 209.018705 145.51423)
			(xy 209.018705 145.52796) (xy 209.018705 145.5417) (xy 209.018705 145.55543) (xy 209.018705 145.56916)
			(xy 209.018705 145.58289) (xy 209.018705 145.59662) (xy 209.018705 145.61035) (xy 209.018705 145.62409)
			(xy 209.018705 145.63782) (xy 209.018705 145.65155) (xy 209.018705 145.66528) (xy 209.018705 145.67901)
			(xy 209.018705 145.69274) (xy 209.018705 145.70648) (xy 209.018705 145.72021) (xy 209.018705 145.73394)
			(xy 209.018705 145.74767) (xy 209.018705 145.7614) (xy 209.018705 145.77513) (xy 209.018705 145.78887)
			(xy 209.018705 145.8026) (xy 209.018705 145.81633) (xy 209.018705 145.83006) (xy 209.018705 145.84379)
			(xy 209.018705 145.85753) (xy 209.018705 145.87126) (xy 209.018705 145.88499) (xy 209.018705 145.89872)
			(xy 209.018705 145.91245) (xy 209.018705 145.92619) (xy 209.018705 145.93992) (xy 209.018705 145.95365)
			(xy 209.018705 145.96738) (xy 209.018705 145.98111) (xy 209.018705 145.99484) (xy 209.018705 146.00858)
			(xy 209.018705 146.02231) (xy 209.018705 146.03604) (xy 209.018705 146.04977) (xy 209.018705 146.0635)
			(xy 209.018705 146.07723) (xy 209.018705 146.09097) (xy 209.018705 146.1047) (xy 209.018705 146.11843)
			(xy 209.018705 146.13216) (xy 209.018705 146.14589) (xy 209.018705 146.15962) (xy 209.018705 146.17336)
			(xy 209.018705 146.18709) (xy 209.018705 146.20082) (xy 209.018705 146.21455) (xy 209.018705 146.22828)
			(xy 209.018705 146.24201) (xy 209.018705 146.25575) (xy 209.018705 146.26948) (xy 209.018705 146.28321)
			(xy 209.018705 146.29694) (xy 209.018705 146.31067) (xy 209.018705 146.3244) (xy 209.018705 146.33814)
			(xy 209.018705 146.35187) (xy 209.018705 146.3656) (xy 208.510625 146.3656) (xy 208.510625 146.35187)
			(xy 208.510625 146.33814) (xy 208.510625 146.3244) (xy 208.510625 146.31067) (xy 208.510625 146.29694)
			(xy 208.510625 146.28321) (xy 208.510625 146.26948) (xy 208.510625 146.25575) (xy 208.510625 146.24201)
			(xy 208.510625 146.22828) (xy 208.510625 146.21455) (xy 208.510625 146.20082) (xy 208.510625 146.18709)
			(xy 208.510625 146.17336) (xy 208.510625 146.15962) (xy 208.510625 146.14589) (xy 208.510625 146.13216)
			(xy 208.510625 146.11843) (xy 208.510625 146.1047) (xy 208.510625 146.09097) (xy 208.510625 146.07723)
			(xy 208.510625 146.0635) (xy 208.510625 146.04977) (xy 208.510625 146.03604) (xy 208.510625 146.02231)
			(xy 208.510625 146.00858) (xy 208.510625 145.99484) (xy 208.510625 145.98111) (xy 208.510625 145.96738)
			(xy 208.510625 145.95365) (xy 208.510625 145.93992) (xy 208.510625 145.92619) (xy 208.510625 145.91245)
			(xy 208.510625 145.89872) (xy 208.510625 145.88499) (xy 208.510625 145.87126) (xy 208.510625 145.85753)
			(xy 208.510625 145.84379) (xy 208.510625 145.83006) (xy 208.510625 145.81633) (xy 208.510625 145.8026)
			(xy 208.510625 145.78887) (xy 208.510625 145.77513) (xy 208.510625 145.7614) (xy 208.510625 145.74767)
			(xy 208.510625 145.73394) (xy 208.510625 145.72021) (xy 208.510625 145.70648) (xy 208.510625 145.69274)
			(xy 208.510625 145.67901) (xy 208.510625 145.66528) (xy 208.510625 145.65155) (xy 208.510625 145.63782)
			(xy 208.510625 145.62409) (xy 208.510625 145.61035) (xy 208.510625 145.59662) (xy 208.510625 145.58289)
			(xy 208.510625 145.56916) (xy 208.510625 145.55543) (xy 208.510625 145.5417) (xy 208.510625 145.52796)
			(xy 208.510625 145.51423) (xy 208.510625 145.5005) (xy 208.510625 145.48677) (xy 208.510625 145.47304)
			(xy 208.510625 145.45931) (xy 208.510625 145.44557) (xy 208.510625 145.43184) (xy 208.510625 145.41811)
			(xy 208.510625 145.40438) (xy 208.510625 145.39065) (xy 208.510625 145.37692) (xy 208.510625 145.36318)
			(xy 208.510625 145.34945) (xy 208.510625 145.33572) (xy 208.510625 145.32199) (xy 208.510625 145.30826)
			(xy 208.510625 145.29452) (xy 208.510625 145.28079) (xy 208.510625 145.26706) (xy 208.510625 145.25333)
			(xy 208.510625 145.2396) (xy 208.510625 145.22586) (xy 208.510625 145.21213) (xy 208.510625 145.1984)
			(xy 208.510625 145.18467) (xy 208.510625 145.17094) (xy 208.510625 145.15721) (xy 208.510625 145.14347)
			(xy 208.510625 145.12974) (xy 208.510625 145.11601) (xy 208.510625 145.10228) (xy 208.510625 145.08855)
			(xy 208.510625 145.07482) (xy 208.510625 145.06108) (xy 208.510625 145.04735) (xy 208.510625 145.03362)
			(xy 208.510625 145.01989) (xy 208.510625 145.00616) (xy 208.510625 144.99243) (xy 208.510625 144.97869)
			(xy 208.510625 144.96496) (xy 208.510625 144.95123) (xy 208.510625 144.9375) (xy 208.510625 144.92377)
			(xy 208.510625 144.91004) (xy 208.510625 144.8963) (xy 208.510625 144.88257) (xy 208.510625 144.86884)
			(xy 208.510625 144.85511) (xy 208.510625 144.84138) (xy 208.510625 144.82764) (xy 208.510625 144.81391)
			(xy 208.510625 144.80018) (xy 208.510625 144.78645) (xy 208.510625 144.77272) (xy 208.510625 144.75898)
			(xy 208.510625 144.74525) (xy 208.510625 144.73152) (xy 208.510625 144.71779) (xy 208.510625 144.70406)
			(xy 208.510625 144.69033) (xy 208.510625 144.67659) (xy 208.510625 144.66286) (xy 208.510625 144.64913)
			(xy 208.510625 144.6354) (xy 208.510625 144.62167) (xy 208.510625 144.60794) (xy 208.510625 144.5942)
			(xy 208.510625 144.58047) (xy 208.510625 144.56674) (xy 208.510625 144.55301) (xy 208.510625 144.53928)
			(xy 208.510625 144.52555) (xy 208.510625 144.51181) (xy 208.510625 144.49808) (xy 208.510625 144.48435)
			(xy 208.510625 144.47062) (xy 208.510625 144.45689) (xy 208.510625 144.44316) (xy 208.510625 144.42942)
			(xy 208.510625 144.41569) (xy 208.510625 144.40196) (xy 208.510625 144.38823) (xy 208.510625 144.3745)
			(xy 208.510625 144.36077) (xy 208.510625 144.34703) (xy 208.510625 144.3333) (xy 208.510625 144.31957)
			(xy 208.510625 144.30584) (xy 208.510625 144.29211) (xy 208.510625 144.27837) (xy 208.510625 144.26464)
			(xy 208.510625 144.25091) (xy 208.510625 144.23718) (xy 208.510625 144.22345) (xy 208.510625 144.20971)
			(xy 208.510625 144.19598) (xy 208.510625 144.18225) (xy 208.510625 144.16852) (xy 208.510625 144.15479)
			(xy 208.510625 144.14106) (xy 208.510625 144.12732) (xy 208.510625 144.11359) (xy 208.510625 144.09986)
			(xy 208.510625 144.08613) (xy 208.510625 144.0724) (xy 208.510625 144.05867) (xy 208.510625 144.04493)
			(xy 208.510625 144.0312) (xy 208.510625 144.01747) (xy 208.510625 144.00374) (xy 208.510625 143.99001)
			(xy 208.510625 143.97628) (xy 208.510625 143.96254) (xy 208.510625 143.94881) (xy 208.510625 143.93508)
			(xy 208.510625 143.92135) (xy 208.510625 143.90762) (xy 208.510625 143.89389) (xy 208.510625 143.88015)
			(xy 208.510625 143.86642) (xy 208.510625 143.85269) (xy 208.510625 143.83896) (xy 208.510625 143.82523)
			(xy 208.510625 143.8115) (xy 208.510625 143.79776) (xy 208.510625 143.78403) (xy 208.510625 143.7703)
			(xy 208.510625 143.75657) (xy 208.510625 143.74284) (xy 208.510625 143.7291) (xy 208.510625 143.71537)
			(xy 208.510625 143.70164) (xy 208.510625 143.68791) (xy 208.510625 143.67418) (xy 208.510625 143.66044)
			(xy 208.510625 143.64671) (xy 208.510625 143.63298) (xy 208.510625 143.61925) (xy 208.510625 143.60552)
			(xy 208.510625 143.59179) (xy 208.510625 143.57805) (xy 208.510625 143.56432) (xy 208.510625 143.55059)
			(xy 208.510625 143.53686) (xy 208.510625 143.52313) (xy 208.510625 143.5094) (xy 208.510625 143.49566)
			(xy 208.510625 143.48193) (xy 208.510625 143.4682) (xy 208.510625 143.45447) (xy 208.510625 143.44074)
			(xy 208.510625 143.42701) (xy 208.510625 143.41327) (xy 208.510625 143.39954) (xy 208.510625 143.38581)
			(xy 208.510625 143.37208) (xy 208.510625 143.35835) (xy 208.510625 143.34462) (xy 208.510625 143.33088)
			(xy 208.510625 143.31715) (xy 208.510625 143.30342) (xy 208.510625 143.28969) (xy 208.510625 143.27596)
			(xy 208.510625 143.26223) (xy 208.510625 143.24849) (xy 208.510625 143.23476) (xy 208.510625 143.22103)
			(xy 208.510625 143.2073) (xy 208.510625 143.19357) (xy 208.510625 143.17983) (xy 208.510625 143.1661)
			(xy 208.510625 143.15237) (xy 208.510625 143.13864) (xy 208.510625 143.12491) (xy 208.510625 143.11117)
			(xy 208.510625 143.09744) (xy 208.510625 143.08371) (xy 208.510625 143.06998) (xy 208.510625 143.05625)
			(xy 208.510625 143.04252) (xy 208.510625 143.02878) (xy 208.510625 143.01505) (xy 208.510625 143.00132)
			(xy 208.510625 142.98759) (xy 208.510625 142.97386) (xy 208.510625 142.96013) (xy 208.510625 142.94639)
			(xy 208.510625 142.93266) (xy 208.510625 142.91893) (xy 208.510625 142.9052) (xy 208.510625 142.89147)
			(xy 208.510625 142.87774) (xy 208.510625 142.864) (xy 208.510625 142.85027) (xy 208.510625 142.83654)
			(xy 208.510625 142.82281) (xy 208.510625 142.80908) (xy 208.510625 142.79535) (xy 208.510625 142.78161)
			(xy 208.510625 142.76788) (xy 208.510625 142.75415) (xy 208.510625 142.74042) (xy 208.510625 142.72669)
			(xy 208.510625 142.71295) (xy 208.510625 142.69922) (xy 208.510625 142.68549) (xy 208.510625 142.67176)
			(xy 208.510625 142.65803) (xy 208.510625 142.64429) (xy 208.510625 142.63056) (xy 208.510625 142.61683)
			(xy 208.510625 142.6031) (xy 208.510625 142.58937) (xy 208.510625 142.57564) (xy 208.510625 142.5619)
			(xy 208.510625 142.54817) (xy 208.510625 142.53444) (xy 208.510625 142.52071) (xy 208.510625 142.50698)
			(xy 208.510625 142.49325) (xy 208.510625 142.47951) (xy 208.510625 142.46578) (xy 208.510625 142.45205)
			(xy 208.510625 142.43832) (xy 208.510625 142.42459) (xy 208.510625 142.41086) (xy 208.510625 142.39712)
			(xy 208.510625 142.38339) (xy 208.510625 142.36966) (xy 208.510625 142.35593) (xy 208.510625 142.3422)
			(xy 208.510625 142.32847) (xy 208.510625 142.31473) (xy 208.510625 142.301) (xy 208.510625 142.28727)
			(xy 208.510625 142.27354) (xy 208.510625 142.25981) (xy 208.510625 142.24608) (xy 208.510625 142.23234)
			(xy 208.510625 142.21861) (xy 208.510625 142.20488) (xy 208.510625 142.19115) (xy 208.510625 142.17742)
			(xy 208.510625 142.16368) (xy 208.510625 142.14995) (xy 208.510625 142.13622) (xy 208.510625 142.12249)
			(xy 208.510625 142.10876) (xy 208.510625 142.09502) (xy 208.510625 142.08129) (xy 208.510625 142.06756)
			(xy 208.510625 142.05383) (xy 208.510625 142.0401) (xy 208.510625 142.02637) (xy 208.510625 142.01263)
			(xy 208.510625 141.9989) (xy 208.510625 141.98517) (xy 208.510625 141.97144) (xy 208.510625 141.95771)
			(xy 208.510625 141.94398) (xy 208.510625 141.93024) (xy 208.510625 141.91651) (xy 208.510625 141.90278)
			(xy 208.510625 141.88905) (xy 208.510625 141.87532) (xy 208.510625 141.86159) (xy 208.510625 141.84785)
			(xy 208.510625 141.83412) (xy 208.510625 141.82039) (xy 208.510625 141.80666) (xy 208.510625 141.79293)
			(xy 208.510625 141.7792) (xy 208.510625 141.76546) (xy 208.510625 141.75173) (xy 208.510625 141.738)
			(xy 208.510625 141.72427) (xy 208.510625 141.71054) (xy 208.510625 141.69681) (xy 208.510625 141.68307)
			(xy 208.510625 141.66934) (xy 208.510625 141.65561) (xy 208.510625 141.64188) (xy 208.510625 141.62815)
			(xy 208.510625 141.61441) (xy 208.510625 141.60068) (xy 208.510625 141.58695) (xy 208.510625 141.57322)
			(xy 208.510625 141.55949) (xy 208.510625 141.54575) (xy 208.510625 141.53202) (xy 208.510625 141.51829)
			(xy 208.510625 141.50456) (xy 208.510625 141.49083) (xy 208.510625 141.4771) (xy 208.510625 141.46336)
			(xy 208.510625 141.44963) (xy 208.510625 141.4359) (xy 208.510625 141.42217) (xy 208.510625 141.40844)
			(xy 208.510625 141.39471) (xy 208.510625 141.38097) (xy 208.510625 141.36724) (xy 208.510625 141.35351)
			(xy 208.510625 141.33978) (xy 208.510625 141.32605) (xy 208.510625 141.31232) (xy 208.510625 141.29858)
			(xy 208.510625 141.28485) (xy 208.510625 141.27112) (xy 208.510625 141.25739) (xy 208.510625 141.24366)
			(xy 208.510625 141.22993) (xy 208.510625 141.21619) (xy 208.510625 141.20246) (xy 208.510625 141.18873)
			(xy 208.510625 141.175) (xy 208.510625 141.16127) (xy 208.510625 141.14754) (xy 208.510625 141.1338)
			(xy 208.510625 141.12007) (xy 208.510625 141.10634) (xy 208.510625 141.09261) (xy 208.510625 141.07888)
			(xy 208.510625 141.06514) (xy 208.510625 141.05141) (xy 208.510625 141.03768) (xy 208.510625 141.02395)
			(xy 208.510625 141.01022) (xy 208.510625 140.99648) (xy 208.510625 140.98275) (xy 208.510625 140.96902)
			(xy 208.510625 140.95529) (xy 208.510625 140.94156) (xy 208.510625 140.92783) (xy 208.510625 140.91409)
			(xy 208.510625 140.90036) (xy 208.510625 140.88663) (xy 208.510625 140.8729) (xy 208.510625 140.85917)
			(xy 208.510625 140.84544) (xy 208.510625 140.8317) (xy 208.510625 140.81797) (xy 208.510625 140.80424)
			(xy 208.510625 140.79051) (xy 208.510625 140.77678) (xy 208.510625 140.76305) (xy 208.510625 140.74931)
			(xy 208.510625 140.73558) (xy 208.510625 140.72185) (xy 208.510625 140.70812) (xy 208.510625 140.69439)
			(xy 208.510625 140.68066) (xy 208.510625 140.66693) (xy 208.510625 140.65319) (xy 208.510625 140.63946)
			(xy 208.510625 140.62573) (xy 208.510625 140.612) (xy 208.510625 140.59827) (xy 208.510625 140.58453)
			(xy 208.510625 140.5708) (xy 208.510625 140.55707) (xy 208.510625 140.54334) (xy 208.510625 140.5296)
			(xy 208.510625 140.51587) (xy 208.510625 140.50214) (xy 208.510625 140.48841) (xy 208.510625 140.47468)
			(xy 208.510625 140.46095) (xy 208.510625 140.44722) (xy 208.510625 140.43348) (xy 208.510625 140.41975)
			(xy 208.510625 140.40602) (xy 208.510625 140.39229) (xy 208.510625 140.37856) (xy 208.510625 140.36483)
			(xy 208.510625 140.35109) (xy 208.510625 140.33736) (xy 208.510625 140.32363) (xy 208.510625 140.3099)
			(xy 208.510625 140.29617) (xy 208.510625 140.28244) (xy 208.510625 140.2687) (xy 208.510625 140.25497)
			(xy 208.510625 140.24124) (xy 208.510625 140.22751) (xy 208.510625 140.21378) (xy 208.510625 140.20005)
			(xy 208.510625 140.18631) (xy 208.510625 140.17258) (xy 208.510625 140.15885) (xy 208.510625 140.14512)
			(xy 208.510625 140.13139) (xy 208.510625 140.11765) (xy 208.510625 140.10392) (xy 208.510625 140.09019)
			(xy 208.510625 140.07646) (xy 208.510625 140.06273) (xy 208.510625 140.04899) (xy 208.510625 140.03526)
			(xy 208.510625 140.02153) (xy 208.510625 140.0078) (xy 208.510625 139.99407) (xy 208.510625 139.98034)
			(xy 208.510625 139.9666) (xy 208.510625 139.95287) (xy 208.510625 139.93914) (xy 208.510625 139.92541)
			(xy 208.510625 139.91168) (xy 208.510625 139.89795) (xy 208.510625 139.88421) (xy 208.510625 139.87048)
			(xy 208.510625 139.85675) (xy 208.510625 139.84302) (xy 208.510625 139.82929) (xy 208.510625 139.81556)
			(xy 208.510625 139.80182) (xy 208.510625 139.78809) (xy 208.510625 139.77436) (xy 208.510625 139.76063)
			(xy 208.510625 139.7469) (xy 208.510625 139.73317) (xy 208.510625 139.71943) (xy 208.510625 139.7057)
			(xy 208.510625 139.69197) (xy 208.510625 139.67824) (xy 208.510625 139.66451) (xy 208.510625 139.65078)
			(xy 208.510625 139.63704) (xy 208.510625 139.62331) (xy 208.510625 139.60958) (xy 208.510625 139.59585)
			(xy 208.510625 139.58212) (xy 208.510625 139.56838) (xy 208.510625 139.55465) (xy 208.510625 139.54092)
			(xy 208.510625 139.52719) (xy 208.510625 139.51346) (xy 208.510625 139.49972) (xy 208.510625 139.48599)
			(xy 208.510625 139.47226) (xy 208.510625 139.45853) (xy 208.510625 139.4448) (xy 208.510625 139.43107)
			(xy 208.510625 139.41733) (xy 208.510625 139.4036) (xy 208.510625 139.38987) (xy 208.510625 139.37614)
			(xy 208.510625 139.36241) (xy 208.510625 139.34868) (xy 208.510625 139.33494) (xy 208.510625 139.32121)
			(xy 208.510625 139.30748) (xy 208.510625 139.29375) (xy 208.510625 139.28002) (xy 208.510625 139.26629)
			(xy 208.510625 139.25255) (xy 208.510625 139.23882) (xy 208.510625 139.22509) (xy 208.510625 139.21136)
			(xy 208.510625 139.19763) (xy 208.510625 139.1839) (xy 208.510625 139.17016) (xy 208.510625 139.15643)
			(xy 208.510625 139.1427) (xy 208.510625 139.12897) (xy 208.510625 139.11524) (xy 208.510625 139.10151)
			(xy 208.510625 139.08777) (xy 208.510625 139.07404) (xy 208.510625 139.06031) (xy 208.510625 139.04658)
			(xy 208.510625 139.03285) (xy 208.510625 139.01911) (xy 208.510625 139.00538) (xy 208.510625 138.99165)
			(xy 208.510625 138.97792) (xy 208.510625 138.96419) (xy 208.510625 138.95045) (xy 208.510625 138.93672)
			(xy 208.510625 138.92299) (xy 208.510625 138.90926) (xy 208.510625 138.89553) (xy 208.510625 138.8818)
			(xy 208.510625 138.86806) (xy 208.510625 138.85433) (xy 208.510625 138.8406) (xy 208.510625 138.82687)
			(xy 208.510625 138.81314) (xy 208.510625 138.79941) (xy 208.510625 138.78567) (xy 208.510625 138.77194)
			(xy 208.510625 138.75821) (xy 208.510625 138.74448) (xy 208.510625 138.73075) (xy 208.510625 138.71702)
			(xy 208.510625 138.70328) (xy 208.510625 138.68955) (xy 208.510625 138.67582) (xy 208.510625 138.66209)
			(xy 208.510625 138.64836) (xy 208.510625 138.63463) (xy 208.510625 138.62089) (xy 208.510625 138.60716)
			(xy 208.510625 138.59343) (xy 208.510625 138.5797) (xy 208.510625 138.56597) (xy 208.510625 138.55224)
			(xy 208.510625 138.5385) (xy 208.510625 138.52477) (xy 208.510625 138.51104) (xy 208.510625 138.49731)
			(xy 208.510625 138.48358) (xy 208.510625 138.46984) (xy 208.510625 138.45611) (xy 208.510625 138.44238)
			(xy 208.510625 138.42865) (xy 208.510625 138.41492) (xy 208.510625 138.40118) (xy 208.510625 138.38745)
			(xy 208.510625 138.37372) (xy 208.510625 138.35999) (xy 208.510625 138.34626) (xy 208.510625 138.33253)
			(xy 208.510625 138.31879) (xy 208.510625 138.30506) (xy 208.510625 138.29133) (xy 208.510625 138.2776)
			(xy 208.510625 138.26387) (xy 208.510625 138.25014) (xy 208.510625 138.2364) (xy 208.510625 138.22267)
			(xy 208.510625 138.20894) (xy 208.510625 138.19521) (xy 208.510625 138.18148) (xy 208.510625 138.16775)
			(xy 208.510625 138.15401) (xy 208.510625 138.14028) (xy 208.510625 138.12655) (xy 208.510625 138.11282)
			(xy 208.510625 138.09909) (xy 208.510625 138.08536) (xy 208.510625 138.07162) (xy 208.510625 138.05789)
			(xy 208.510625 138.04416) (xy 208.510625 138.03043) (xy 208.510625 138.0167) (xy 208.510625 138.00296)
			(xy 208.510625 137.98923) (xy 208.510625 137.9755) (xy 208.510625 137.96177) (xy 208.510625 137.94804)
			(xy 208.510625 137.9343) (xy 208.510625 137.92057) (xy 208.510625 137.90684) (xy 208.510625 137.89311)
			(xy 208.510625 137.87938) (xy 208.510625 137.86565) (xy 208.510625 137.85191) (xy 208.510625 137.83818)
			(xy 208.510625 137.82445) (xy 208.510625 137.81072) (xy 208.510625 137.79699) (xy 208.510625 137.78326)
			(xy 208.510625 137.76952) (xy 208.510625 137.75579) (xy 208.510625 137.74206) (xy 208.510625 137.72833)
			(xy 208.510625 137.7146) (xy 208.510625 137.70087) (xy 208.510625 137.68713) (xy 208.510625 137.6734)
			(xy 208.510625 137.65967) (xy 208.510625 137.64594) (xy 208.510625 137.63221) (xy 208.510625 137.61848)
			(xy 208.510625 137.60474) (xy 208.510625 137.59101) (xy 208.510625 137.57728) (xy 208.510625 137.56355)
			(xy 208.510625 137.54982) (xy 208.510625 137.53609) (xy 208.510625 137.52235) (xy 208.510625 137.50862)
			(xy 208.510625 137.49489) (xy 208.510625 137.48116) (xy 208.510625 137.46743) (xy 208.510625 137.45369)
			(xy 208.510625 137.43996) (xy 208.510625 137.42623) (xy 208.510625 137.4125) (xy 208.510625 137.39877)
			(xy 208.510625 137.38503) (xy 208.510625 137.3713) (xy 208.510625 137.35757) (xy 208.510625 137.34384)
			(xy 208.510625 137.33011) (xy 208.510625 137.31638) (xy 208.510625 137.30264) (xy 208.510625 137.28891)
			(xy 208.510625 137.27518) (xy 208.510625 137.26145) (xy 208.510625 137.24772) (xy 208.510625 137.23399)
			(xy 208.510625 137.22025) (xy 208.510625 137.20652) (xy 208.510625 137.19279) (xy 208.510625 137.17906)
			(xy 208.510625 137.16533) (xy 208.510625 137.1516) (xy 208.510625 137.13786) (xy 208.510625 137.12413)
			(xy 208.510625 137.1104) (xy 208.510625 137.09667) (xy 208.510625 137.08294) (xy 208.510625 137.06921)
			(xy 208.510625 137.05547) (xy 208.510625 137.04174) (xy 208.510625 137.02801) (xy 208.510625 137.01428)
			(xy 208.510625 137.00055) (xy 208.510625 136.98682) (xy 208.510625 136.97308) (xy 208.510625 136.95935)
			(xy 208.510625 136.94562) (xy 208.510625 136.93189) (xy 208.510625 136.91816) (xy 208.510625 136.90442)
			(xy 208.510625 136.89069) (xy 208.510625 136.87696) (xy 208.510625 136.86323) (xy 208.510625 136.8495)
			(xy 208.510625 136.83576) (xy 208.510625 136.82203) (xy 208.510625 136.8083) (xy 208.510625 136.79457)
			(xy 208.510625 136.78084) (xy 208.510625 136.76711) (xy 208.510625 136.75337) (xy 208.510625 136.73964)
			(xy 208.510625 136.72591) (xy 208.510625 136.71218) (xy 208.510625 136.69845) (xy 208.510625 136.68472)
			(xy 208.510625 136.67098) (xy 208.510625 136.65725) (xy 208.510625 136.64352) (xy 208.510625 136.62979)
			(xy 208.510625 136.61606) (xy 208.510625 136.60233) (xy 208.510625 136.58859) (xy 208.510625 136.57486)
			(xy 208.510625 136.56113) (xy 208.510625 136.5474) (xy 208.510625 136.53367) (xy 208.510625 136.51994)
			(xy 208.510625 136.5062) (xy 208.510625 136.49247) (xy 208.510625 136.47874) (xy 208.510625 136.46501)
			(xy 208.510625 136.45128) (xy 208.510625 136.43755) (xy 208.510625 136.42381) (xy 208.510625 136.41008)
			(xy 208.510625 136.39635) (xy 208.510625 136.38262) (xy 208.510625 136.36889) (xy 208.510625 136.35515)
			(xy 208.510625 136.34142) (xy 208.510625 136.32769) (xy 208.510625 136.31396) (xy 208.510625 136.30023)
			(xy 208.510625 136.28649) (xy 208.510625 136.27276) (xy 208.510625 136.25903) (xy 208.510625 136.2453)
			(xy 208.510625 136.23157) (xy 208.510625 136.21784) (xy 208.510625 136.2041) (xy 208.510625 136.19037)
			(xy 208.510625 136.17664) (xy 208.510625 136.16291) (xy 208.510625 136.14918) (xy 208.510625 136.13545)
			(xy 208.510625 136.12171) (xy 208.510625 136.10798) (xy 208.510625 136.09425) (xy 208.510625 136.08052)
			(xy 208.510625 136.06679) (xy 208.510625 136.05306) (xy 208.510625 136.03932) (xy 208.510625 136.02559)
			(xy 208.510625 136.01186) (xy 208.510625 135.99813) (xy 208.510625 135.9844) (xy 208.510625 135.97067)
			(xy 208.510625 135.95693) (xy 208.510625 135.9432) (xy 208.510625 135.92947) (xy 208.510625 135.91574)
			(xy 208.510625 135.90201) (xy 208.510625 135.88827) (xy 208.510625 135.87454) (xy 208.510625 135.86081)
			(xy 208.510625 135.84708) (xy 208.510625 135.83335) (xy 208.510625 135.81961) (xy 208.510625 135.80588)
			(xy 208.510625 135.79215) (xy 208.510625 135.77842) (xy 208.510625 135.76469) (xy 208.510625 135.75096)
			(xy 208.510625 135.73722) (xy 208.510625 135.72349) (xy 208.510625 135.70976) (xy 208.510625 135.69603)
			(xy 208.510625 135.6823) (xy 208.510625 135.66857) (xy 208.510625 135.65483) (xy 208.510625 135.6411)
			(xy 208.510625 135.62737) (xy 208.510625 135.61364) (xy 208.510625 135.59991) (xy 208.510625 135.58618)
			(xy 208.510625 135.57244) (xy 208.510625 135.55871) (xy 208.510625 135.54498) (xy 208.510625 135.53125)
			(xy 208.510625 135.51752) (xy 208.510625 135.50379) (xy 208.510625 135.49005) (xy 208.510625 135.47632)
			(xy 208.510625 135.46259) (xy 208.510625 135.44886) (xy 208.510625 135.43513) (xy 208.510625 135.4214)
			(xy 208.510625 135.40766) (xy 208.510625 135.39393) (xy 208.510625 135.3802) (xy 208.510625 135.36647)
			(xy 208.510625 135.35274) (xy 208.510625 135.339) (xy 208.510625 135.32527) (xy 208.510625 135.31154)
			(xy 208.510625 135.29781) (xy 208.510625 135.28408) (xy 208.510625 135.27034) (xy 208.510625 135.25661)
			(xy 208.510625 135.24288) (xy 208.510625 135.22915) (xy 208.510625 135.21542) (xy 208.510625 135.20169)
			(xy 208.510625 135.18795) (xy 208.510625 135.17422) (xy 208.510625 135.16049) (xy 208.510625 135.14676)
			(xy 208.510625 135.13303) (xy 208.510625 135.1193) (xy 208.510625 135.10556) (xy 208.510625 135.09183)
			(xy 208.510625 135.0781) (xy 208.510625 135.06437) (xy 208.510625 135.05064) (xy 208.510625 135.03691)
			(xy 208.510625 135.02317) (xy 208.510625 135.00944) (xy 208.510625 134.99571) (xy 208.510625 134.98198)
			(xy 208.510625 134.96825) (xy 208.510625 134.95452) (xy 208.510625 134.94078) (xy 208.510625 134.92705)
			(xy 208.510625 134.91332) (xy 208.510625 134.89959) (xy 208.510625 134.88586) (xy 208.510625 134.87213)
			(xy 208.510625 134.85839) (xy 208.510625 134.84466) (xy 208.510625 134.83093) (xy 208.510625 134.8172)
			(xy 208.510625 134.80347) (xy 208.510625 134.78973) (xy 208.510625 134.776) (xy 208.510625 134.76227)
			(xy 208.510625 134.74854) (xy 208.510625 134.73481) (xy 208.510625 134.72107) (xy 208.510625 134.70734)
			(xy 208.510625 134.69361) (xy 208.510625 134.67988) (xy 208.510625 134.66615) (xy 208.510625 134.65242)
			(xy 208.510625 134.63868) (xy 208.510625 134.62495) (xy 208.510625 134.61122) (xy 208.510625 134.59749)
			(xy 208.510625 134.58376) (xy 208.510625 134.57003) (xy 208.510625 134.55629) (xy 208.510625 134.54256)
			(xy 208.510625 134.52883) (xy 208.510625 134.5151) (xy 208.510625 134.50137) (xy 208.510625 134.48764)
			(xy 208.510625 134.4739) (xy 208.510625 134.46017) (xy 208.510625 134.44644) (xy 208.510625 134.43271)
			(xy 208.510625 134.41898) (xy 208.510625 134.40525) (xy 208.510625 134.39151) (xy 208.510625 134.37778)
			(xy 208.510625 134.36405) (xy 208.510625 134.35032) (xy 208.510625 134.33659) (xy 208.510625 134.32286)
			(xy 208.510625 134.30912) (xy 208.510625 134.29539) (xy 208.510625 134.28166) (xy 208.510625 134.26793)
			(xy 208.510625 134.2542) (xy 208.510625 134.24046) (xy 208.510625 134.22673) (xy 208.510625 134.213)
			(xy 208.510625 134.19927) (xy 208.510625 134.18554) (xy 208.510625 134.1718) (xy 208.510625 134.15807)
			(xy 208.510625 134.14434) (xy 208.510625 134.13061) (xy 208.510625 134.11688) (xy 208.510625 134.10315)
			(xy 208.510625 134.08941) (xy 208.510625 134.07568) (xy 208.510625 134.06195) (xy 208.510625 134.04822)
			(xy 208.510625 134.03449) (xy 208.510625 134.02076) (xy 208.510625 134.00702) (xy 208.510625 133.99329)
			(xy 208.510625 133.97956) (xy 208.510625 133.96583) (xy 208.510625 133.9521) (xy 208.510625 133.93837)
			(xy 208.510625 133.92463) (xy 208.510625 133.9109) (xy 208.510625 133.89717) (xy 208.510625 133.88344)
			(xy 208.510625 133.86971) (xy 208.510625 133.85598) (xy 208.510625 133.84224) (xy 208.510625 133.82851)
			(xy 208.510625 133.81478) (xy 208.510625 133.80105) (xy 208.510625 133.78732) (xy 208.510625 133.77359)
			(xy 208.510625 133.75985) (xy 208.510625 133.74612) (xy 208.510625 133.73239) (xy 208.510625 133.71866)
			(xy 208.510625 133.70493) (xy 208.510625 133.69119) (xy 208.510625 133.67746) (xy 208.510625 133.66373)
			(xy 208.510625 133.65) (xy 208.510625 133.63627) (xy 208.510625 133.62253) (xy 208.510625 133.6088)
			(xy 208.510625 133.59507) (xy 208.510625 133.58134) (xy 208.510625 133.56761) (xy 208.510625 133.55388)
			(xy 208.510625 133.54014) (xy 208.510625 133.52641) (xy 208.510625 133.51268) (xy 208.510625 133.49895)
			(xy 208.510625 133.48522) (xy 208.510625 133.47149) (xy 208.510625 133.45775) (xy 208.510625 133.44402)
			(xy 208.510625 133.43029) (xy 208.510625 133.41656) (xy 208.510625 133.40283) (xy 208.510625 133.3891)
			(xy 208.510625 133.37536) (xy 208.510625 133.36163) (xy 208.510625 133.3479) (xy 208.510625 133.33417)
			(xy 208.510625 133.32044) (xy 208.510625 133.30671) (xy 208.510625 133.29297) (xy 208.510625 133.27924)
			(xy 208.510625 133.26551) (xy 208.510625 133.25178) (xy 208.510625 133.23805) (xy 208.510625 133.22431)
			(xy 208.510625 133.21058) (xy 208.510625 133.19685) (xy 208.510625 133.18312) (xy 208.510625 133.16939)
			(xy 208.510625 133.15565) (xy 208.510625 133.14192) (xy 208.510625 133.12819) (xy 208.510625 133.11446)
			(xy 208.510625 133.10073) (xy 208.510625 133.087) (xy 208.510625 133.07326) (xy 208.510625 133.05953)
			(xy 208.510625 133.0458) (xy 208.510625 133.03207) (xy 208.510625 133.01834) (xy 208.510625 133.00461)
			(xy 208.510625 132.99087) (xy 208.510625 132.97714) (xy 208.510625 132.96341) (xy 208.510625 132.94968)
			(xy 208.510625 132.93595) (xy 208.510625 132.92222) (xy 208.510625 132.90848) (xy 208.510625 132.89475)
			(xy 208.510625 132.88102) (xy 208.510625 132.86729) (xy 208.510625 132.85356) (xy 208.510625 132.83983)
			(xy 208.510625 132.82609) (xy 208.510625 132.81236) (xy 208.510625 132.79863) (xy 208.510625 132.7849)
			(xy 208.510625 132.77117) (xy 208.510625 132.75744) (xy 208.510625 132.7437) (xy 208.510625 132.72997)
			(xy 208.510625 132.71624) (xy 208.510625 132.70251) (xy 208.510625 132.68878) (xy 208.510625 132.67504)
			(xy 208.510625 132.66131) (xy 208.510625 132.64758) (xy 208.510625 132.63385) (xy 208.510625 132.62012)
			(xy 208.510625 132.60638) (xy 208.510625 132.59265) (xy 208.510625 132.57892) (xy 208.510625 132.56519)
			(xy 208.510625 132.55146) (xy 208.510625 132.53773) (xy 208.510625 132.52399) (xy 208.510625 132.51026)
			(xy 208.510625 132.49653) (xy 208.510625 132.4828) (xy 208.510625 132.46907) (xy 208.510625 132.45534)
			(xy 208.510625 132.4416) (xy 208.510625 132.42787) (xy 208.510625 132.41414) (xy 208.510625 132.40041)
			(xy 208.510625 132.38668) (xy 208.510625 132.37295) (xy 208.510625 132.35921) (xy 208.510625 132.34548)
			(xy 208.510625 132.33175) (xy 208.510625 132.31802) (xy 208.510625 132.30429) (xy 208.510625 132.29056)
			(xy 208.510625 132.27682) (xy 208.510625 132.26309) (xy 208.510625 132.24936) (xy 208.510625 132.23563)
			(xy 208.510625 132.2219) (xy 208.510625 132.20817) (xy 208.510625 132.19443) (xy 208.510625 132.1807)
			(xy 208.510625 132.16697) (xy 208.510625 132.15324) (xy 208.510625 132.13951) (xy 208.510625 132.12577)
			(xy 208.510625 132.11204) (xy 208.510625 132.09831) (xy 208.510625 132.08458) (xy 208.510625 132.07085)
			(xy 208.510625 132.05711) (xy 208.510625 132.04338) (xy 208.510625 132.02965) (xy 208.510625 132.01592)
			(xy 208.510625 132.00219) (xy 208.510625 131.98846) (xy 208.510625 131.97472) (xy 208.510625 131.96099)
			(xy 208.510625 131.94726) (xy 208.510625 131.93353) (xy 208.510625 131.9198) (xy 208.510625 131.90607)
			(xy 208.510625 131.89233) (xy 208.510625 131.8786) (xy 208.510625 131.86487) (xy 208.510625 131.85114)
			(xy 208.510625 131.83741) (xy 208.510625 131.82368) (xy 208.510625 131.80995) (xy 208.510625 131.79621)
			(xy 208.510625 131.78248) (xy 208.510625 131.76875) (xy 208.510625 131.75502) (xy 208.510625 131.74129)
			(xy 208.510625 131.72756) (xy 208.510625 131.71382) (xy 208.510625 131.70009) (xy 208.510625 131.68636)
			(xy 208.510625 131.67263) (xy 208.510625 131.6589) (xy 208.510625 131.64516) (xy 208.510625 131.63143)
			(xy 208.510625 131.6177) (xy 208.510625 131.60397) (xy 208.510625 131.59024) (xy 208.510625 131.5765)
			(xy 208.510625 131.56277) (xy 208.510625 131.54904) (xy 208.510625 131.53531) (xy 208.510625 131.52158)
			(xy 208.510625 131.50785) (xy 208.496895 131.50785) (xy 208.496895 131.49411) (xy 208.496895 131.48038)
			(xy 208.496895 131.46665) (xy 208.496895 131.45292) (xy 208.496895 131.43919) (xy 208.483165 131.43919)
			(xy 208.483165 131.42546) (xy 208.483165 131.41172) (xy 208.469435 131.41172) (xy 208.469435 131.39799)
			(xy 208.469435 131.38426) (xy 208.455705 131.38426) (xy 208.455705 131.37053) (xy 208.455705 131.3568)
			(xy 208.441965 131.3568) (xy 208.441965 131.34307) (xy 208.428235 131.34307) (xy 208.428235 131.32933)
			(xy 208.428235 131.3156) (xy 208.414505 131.3156) (xy 208.414505 131.30187) (xy 208.400775 131.30187)
			(xy 208.400775 131.28814) (xy 208.387045 131.28814) (xy 208.387045 131.27441) (xy 208.359575 131.27441)
			(xy 208.359575 131.26068) (xy 208.345845 131.26068) (xy 208.345845 131.24694) (xy 208.318385 131.24694)
			(xy 208.318385 131.23321) (xy 208.290925 131.23321) (xy 208.290925 131.21948) (xy 208.263455 131.21948)
			(xy 208.263455 131.20575) (xy 208.208535 131.20575) (xy 208.208535 131.19202) (xy 206.464595 131.19202)
			(xy 206.464595 131.17828) (xy 206.464595 131.16455) (xy 206.464595 131.15082) (xy 206.464595 131.13709)
			(xy 206.464595 131.12336) (xy 206.464595 131.10962) (xy 206.464595 131.09589) (xy 206.464595 131.08216)
			(xy 206.464595 131.06843) (xy 206.464595 131.0547) (xy 206.464595 131.04097) (xy 206.464595 131.02723)
			(xy 206.464595 131.0135) (xy 206.464595 130.99977) (xy 206.464595 130.98604) (xy 206.464595 130.97231)
			(xy 206.464595 130.95858) (xy 206.464595 130.94484) (xy 206.464595 130.93111) (xy 206.464595 130.91738)
			(xy 206.464595 130.90365) (xy 206.464595 130.88992) (xy 206.464595 130.87619) (xy 206.464595 130.86245)
			(xy 206.464595 130.84872) (xy 206.464595 130.83499) (xy 206.464595 130.82126) (xy 206.464595 130.80753)
			(xy 206.464595 130.7938) (xy 206.464595 130.78006) (xy 206.464595 130.76633) (xy 206.464595 130.7526)
			(xy 206.464595 130.73887) (xy 206.464595 130.72514) (xy 206.464595 130.71141) (xy 206.464595 130.69767)
			(xy 206.464595 130.68394) (xy 206.464595 130.67021) (xy 208.208535 130.67021)
		)
		(stroke
			(width 0)
			(type default)
		)
		(fill yes)
		(layer "F.Cu")
	)
	(gr_poly
		(pts
			(xy 226.869975 130.68394) (xy 227.021025 130.68394) (xy 227.021025 130.69767) (xy 227.075955 130.69767)
			(xy 227.075955 130.71141) (xy 227.130885 130.71141) (xy 227.130885 130.72514) (xy 227.172075 130.72514)
			(xy 227.172075 130.73887) (xy 227.213275 130.73887) (xy 227.213275 130.7526) (xy 227.240735 130.7526)
			(xy 227.240735 130.76633) (xy 227.268205 130.76633) (xy 227.268205 130.78006) (xy 227.295665 130.78006)
			(xy 227.295665 130.7938) (xy 227.323125 130.7938) (xy 227.323125 130.80753) (xy 227.350595 130.80753)
			(xy 227.350595 130.82126) (xy 227.364325 130.82126) (xy 227.364325 130.83499) (xy 227.391785 130.83499)
			(xy 227.391785 130.84872) (xy 227.405515 130.84872) (xy 227.405515 130.86245) (xy 227.419245 130.86245)
			(xy 227.419245 130.87619) (xy 227.446715 130.87619) (xy 227.446715 130.88992) (xy 227.460445 130.88992)
			(xy 227.460445 130.90365) (xy 227.474175 130.90365) (xy 227.474175 130.91738) (xy 227.487905 130.91738)
			(xy 227.487905 130.93111) (xy 227.501635 130.93111) (xy 227.501635 130.94484) (xy 227.515365 130.94484)
			(xy 227.515365 130.95858) (xy 227.529105 130.95858) (xy 227.529105 130.97231) (xy 227.542835 130.97231)
			(xy 227.542835 130.98604) (xy 227.556565 130.98604) (xy 227.556565 130.99977) (xy 227.570295 130.99977)
			(xy 227.570295 131.0135) (xy 227.584025 131.0135) (xy 227.584025 131.02723) (xy 227.584025 131.04097)
			(xy 227.597765 131.04097) (xy 227.597765 131.0547) (xy 227.611495 131.0547) (xy 227.611495 131.06843)
			(xy 227.625225 131.06843) (xy 227.625225 131.08216) (xy 227.625225 131.09589) (xy 227.638955 131.09589)
			(xy 227.638955 131.10962) (xy 227.638955 131.12336) (xy 227.652685 131.12336) (xy 227.652685 131.13709)
			(xy 227.666425 131.13709) (xy 227.666425 131.15082) (xy 227.666425 131.16455) (xy 227.680155 131.16455)
			(xy 227.680155 131.17828) (xy 227.680155 131.19202) (xy 227.693885 131.19202) (xy 227.693885 131.20575)
			(xy 227.693885 131.21948) (xy 227.707615 131.21948) (xy 227.707615 131.23321) (xy 227.707615 131.24694)
			(xy 227.707615 131.26068) (xy 227.721345 131.26068) (xy 227.721345 131.27441) (xy 227.721345 131.28814)
			(xy 227.721345 131.30187) (xy 227.735075 131.30187) (xy 227.735075 131.3156) (xy 227.735075 131.32933)
			(xy 227.735075 131.34307) (xy 227.748815 131.34307) (xy 227.748815 131.3568) (xy 227.748815 131.37053)
			(xy 227.748815 131.38426) (xy 227.748815 131.39799) (xy 227.762545 131.39799) (xy 227.762545 131.41172)
			(xy 227.762545 131.42546) (xy 227.762545 131.43919) (xy 227.762545 131.45292) (xy 227.762545 131.46665)
			(xy 227.762545 131.48038) (xy 227.776275 131.48038) (xy 227.776275 131.49411) (xy 227.776275 131.50785)
			(xy 227.776275 131.52158) (xy 227.776275 131.53531) (xy 227.776275 131.54904) (xy 227.776275 131.56277)
			(xy 227.776275 131.5765) (xy 227.776275 131.59024) (xy 227.776275 131.60397) (xy 227.776275 131.6177)
			(xy 227.776275 131.63143) (xy 227.762545 131.63143) (xy 227.762545 131.64516) (xy 227.776275 131.64516)
			(xy 227.776275 131.6589) (xy 227.762545 131.6589) (xy 227.762545 131.67263) (xy 227.762545 131.68636)
			(xy 227.762545 131.70009) (xy 227.762545 131.71382) (xy 227.762545 131.72756) (xy 227.762545 131.74129)
			(xy 227.762545 131.75502) (xy 227.748815 131.75502) (xy 227.748815 131.76875) (xy 227.748815 131.78248)
			(xy 227.748815 131.79621) (xy 227.748815 131.80995) (xy 227.735075 131.80995) (xy 227.735075 131.82368)
			(xy 227.735075 131.83741) (xy 227.735075 131.85114) (xy 227.721345 131.85114) (xy 227.721345 131.86487)
			(xy 227.721345 131.8786) (xy 227.721345 131.89233) (xy 227.707615 131.89233) (xy 227.707615 131.90607)
			(xy 227.707615 131.9198) (xy 227.707615 131.93353) (xy 227.693885 131.93353) (xy 227.693885 131.94726)
			(xy 227.693885 131.96099) (xy 227.680155 131.96099) (xy 227.680155 131.97472) (xy 227.680155 131.98846)
			(xy 227.666425 131.98846) (xy 227.666425 132.00219) (xy 227.666425 132.01592) (xy 227.652685 132.01592)
			(xy 227.652685 132.02965) (xy 227.638955 132.02965) (xy 227.638955 132.04338) (xy 227.638955 132.05711)
			(xy 227.625225 132.05711) (xy 227.625225 132.07085) (xy 227.611495 132.07085) (xy 227.611495 132.08458)
			(xy 227.611495 132.09831) (xy 227.597765 132.09831) (xy 227.597765 132.11204) (xy 227.584025 132.11204)
			(xy 227.584025 132.12577) (xy 227.570295 132.12577) (xy 227.570295 132.13951) (xy 227.570295 132.15324)
			(xy 227.556565 132.15324) (xy 227.556565 132.16697) (xy 227.542835 132.16697) (xy 227.542835 132.1807)
			(xy 227.529105 132.1807) (xy 227.529105 132.19443) (xy 227.515365 132.19443) (xy 227.515365 132.20817)
			(xy 227.501635 132.20817) (xy 227.501635 132.2219) (xy 227.487905 132.2219) (xy 227.487905 132.23563)
			(xy 227.474175 132.23563) (xy 227.474175 132.24936) (xy 227.460445 132.24936) (xy 227.460445 132.26309)
			(xy 227.432975 132.26309) (xy 227.432975 132.27682) (xy 227.419245 132.27682) (xy 227.419245 132.29056)
			(xy 227.405515 132.29056) (xy 227.405515 132.30429) (xy 227.378055 132.30429) (xy 227.378055 132.31802)
			(xy 227.364325 132.31802) (xy 227.364325 132.33175) (xy 227.336855 132.33175) (xy 227.336855 132.34548)
			(xy 227.323125 132.34548) (xy 227.323125 132.35921) (xy 227.295665 132.35921) (xy 227.295665 132.37295)
			(xy 227.268205 132.37295) (xy 227.268205 132.38668) (xy 227.240735 132.38668) (xy 227.240735 132.40041)
			(xy 227.199545 132.40041) (xy 227.199545 132.41414) (xy 227.172075 132.41414) (xy 227.172075 132.42787)
			(xy 227.117155 132.42787) (xy 227.117155 132.4416) (xy 227.075955 132.4416) (xy 227.075955 132.45534)
			(xy 226.993565 132.45534) (xy 226.993565 132.46907) (xy 224.920065 132.46907) (xy 224.920065 132.4828)
			(xy 224.810215 132.4828) (xy 224.810215 132.49653) (xy 224.755285 132.49653) (xy 224.755285 132.51026)
			(xy 224.700365 132.51026) (xy 224.700365 132.52399) (xy 224.672895 132.52399) (xy 224.672895 132.53773)
			(xy 224.631705 132.53773) (xy 224.631705 132.55146) (xy 224.604245 132.55146) (xy 224.604245 132.56519)
			(xy 224.576775 132.56519) (xy 224.576775 132.57892) (xy 224.549315 132.57892) (xy 224.549315 132.59265)
			(xy 224.521855 132.59265) (xy 224.521855 132.60638) (xy 224.508115 132.60638) (xy 224.508115 132.62012)
			(xy 224.480655 132.62012) (xy 224.480655 132.63385) (xy 224.453195 132.63385) (xy 224.453195 132.64758)
			(xy 224.439455 132.64758) (xy 224.439455 132.66131) (xy 224.425725 132.66131) (xy 224.425725 132.67504)
			(xy 224.411995 132.67504) (xy 224.411995 132.68878) (xy 224.384535 132.68878) (xy 224.384535 132.70251)
			(xy 224.370795 132.70251) (xy 224.370795 132.71624) (xy 224.357065 132.71624) (xy 224.357065 132.72997)
			(xy 224.343335 132.72997) (xy 224.343335 132.7437) (xy 224.329605 132.7437) (xy 224.329605 132.75744)
			(xy 224.315875 132.75744) (xy 224.315875 132.77117) (xy 224.302145 132.77117) (xy 224.302145 132.7849)
			(xy 224.288405 132.7849) (xy 224.288405 132.79863) (xy 224.288405 132.81236) (xy 224.274675 132.81236)
			(xy 224.274675 132.82609) (xy 224.260945 132.82609) (xy 224.260945 132.83983) (xy 224.247215 132.83983)
			(xy 224.247215 132.85356) (xy 224.247215 132.86729) (xy 224.233485 132.86729) (xy 224.233485 132.88102)
			(xy 224.219755 132.88102) (xy 224.219755 132.89475) (xy 224.219755 132.90848) (xy 224.206015 132.90848)
			(xy 224.206015 132.92222) (xy 224.192285 132.92222) (xy 224.192285 132.93595) (xy 224.192285 132.94968)
			(xy 224.178555 132.94968) (xy 224.178555 132.96341) (xy 224.178555 132.97714) (xy 224.164825 132.97714)
			(xy 224.164825 132.99087) (xy 224.164825 133.00461) (xy 224.151095 133.00461) (xy 224.151095 133.01834)
			(xy 224.151095 133.03207) (xy 224.151095 133.0458) (xy 224.137365 133.0458) (xy 224.137365 133.05953)
			(xy 224.137365 133.07326) (xy 224.123625 133.07326) (xy 224.123625 133.087) (xy 224.123625 133.10073)
			(xy 224.123625 133.11446) (xy 224.109895 133.11446) (xy 224.109895 133.12819) (xy 224.109895 133.14192)
			(xy 224.109895 133.15565) (xy 224.109895 133.16939) (xy 224.096165 133.16939) (xy 224.096165 133.18312)
			(xy 224.096165 133.19685) (xy 224.096165 133.21058) (xy 224.096165 133.22431) (xy 224.096165 133.23805)
			(xy 224.096165 133.25178) (xy 224.082435 133.25178) (xy 224.082435 133.26551) (xy 224.082435 133.27924)
			(xy 224.082435 133.29297) (xy 224.082435 133.30671) (xy 224.082435 133.32044) (xy 224.082435 133.33417)
			(xy 224.082435 133.3479) (xy 224.082435 133.36163) (xy 224.082435 133.37536) (xy 224.082435 133.3891)
			(xy 224.082435 133.40283) (xy 224.082435 133.41656) (xy 224.082435 133.43029) (xy 224.082435 133.44402)
			(xy 224.082435 133.45775) (xy 224.082435 133.47149) (xy 224.096165 133.47149) (xy 224.096165 133.48522)
			(xy 224.096165 133.49895) (xy 224.096165 133.51268) (xy 224.096165 133.52641) (xy 224.096165 133.54014)
			(xy 224.096165 133.55388) (xy 224.109895 133.55388) (xy 224.109895 133.56761) (xy 224.109895 133.58134)
			(xy 224.109895 133.59507) (xy 224.109895 133.6088) (xy 224.123625 133.6088) (xy 224.123625 133.62253)
			(xy 224.123625 133.63627) (xy 224.123625 133.65) (xy 224.137365 133.65) (xy 224.137365 133.66373)
			(xy 224.137365 133.67746) (xy 224.137365 133.69119) (xy 224.151095 133.69119) (xy 224.151095 133.70493)
			(xy 224.151095 133.71866) (xy 224.164825 133.71866) (xy 224.164825 133.73239) (xy 224.164825 133.74612)
			(xy 224.178555 133.74612) (xy 224.178555 133.75985) (xy 224.178555 133.77359) (xy 224.192285 133.77359)
			(xy 224.192285 133.78732) (xy 224.192285 133.80105) (xy 224.206015 133.80105) (xy 224.206015 133.81478)
			(xy 224.206015 133.82851) (xy 224.219755 133.82851) (xy 224.219755 133.84224) (xy 224.233485 133.84224)
			(xy 224.233485 133.85598) (xy 224.233485 133.86971) (xy 224.247215 133.86971) (xy 224.247215 133.88344)
			(xy 224.260945 133.88344) (xy 224.260945 133.89717) (xy 224.260945 133.9109) (xy 224.274675 133.9109)
			(xy 224.274675 133.92463) (xy 224.288405 133.92463) (xy 224.288405 133.93837) (xy 224.302145 133.93837)
			(xy 224.302145 133.9521) (xy 224.315875 133.9521) (xy 224.315875 133.96583) (xy 224.329605 133.96583)
			(xy 224.329605 133.97956) (xy 224.343335 133.97956) (xy 224.343335 133.99329) (xy 224.357065 133.99329)
			(xy 224.357065 134.00702) (xy 224.370795 134.00702) (xy 224.370795 134.02076) (xy 224.384535 134.02076)
			(xy 224.384535 134.03449) (xy 224.398265 134.03449) (xy 224.398265 134.04822) (xy 224.411995 134.04822)
			(xy 224.411995 134.06195) (xy 224.425725 134.06195) (xy 224.425725 134.07568) (xy 224.453195 134.07568)
			(xy 224.453195 134.08941) (xy 224.466925 134.08941) (xy 224.466925 134.10315) (xy 224.494385 134.10315)
			(xy 224.494385 134.11688) (xy 224.508115 134.11688) (xy 224.508115 134.13061) (xy 224.535585 134.13061)
			(xy 224.535585 134.14434) (xy 224.563045 134.14434) (xy 224.563045 134.15807) (xy 224.590505 134.15807)
			(xy 224.590505 134.1718) (xy 224.617975 134.1718) (xy 224.617975 134.18554) (xy 224.645435 134.18554)
			(xy 224.645435 134.19927) (xy 224.686635 134.19927) (xy 224.686635 134.213) (xy 224.727825 134.213)
			(xy 224.727825 134.22673) (xy 224.782755 134.22673) (xy 224.782755 134.24046) (xy 224.851415 134.24046)
			(xy 224.851415 134.2542) (xy 235.713225 134.2542) (xy 235.713225 134.26793) (xy 235.726955 134.26793)
			(xy 235.726955 134.2542) (xy 235.740695 134.2542) (xy 235.740695 134.26793) (xy 235.836815 134.26793)
			(xy 235.836815 134.28166) (xy 235.891735 134.28166) (xy 235.891735 134.29539) (xy 235.932935 134.29539)
			(xy 235.932935 134.30912) (xy 235.974125 134.30912) (xy 235.974125 134.32286) (xy 236.015325 134.32286)
			(xy 236.015325 134.33659) (xy 236.042785 134.33659) (xy 236.042785 134.35032) (xy 236.070255 134.35032)
			(xy 236.070255 134.36405) (xy 236.097715 134.36405) (xy 236.097715 134.37778) (xy 236.125185 134.37778)
			(xy 236.125185 134.39151) (xy 236.138915 134.39151) (xy 236.138915 134.40525) (xy 236.166375 134.40525)
			(xy 236.166375 134.41898) (xy 236.180105 134.41898) (xy 236.180105 134.43271) (xy 236.207575 134.43271)
			(xy 236.207575 134.44644) (xy 236.221305 134.44644) (xy 236.221305 134.46017) (xy 236.235035 134.46017)
			(xy 236.235035 134.4739) (xy 236.248765 134.4739) (xy 236.248765 134.48764) (xy 236.276225 134.48764)
			(xy 236.276225 134.50137) (xy 236.289955 134.50137) (xy 236.289955 134.5151) (xy 236.303695 134.5151)
			(xy 236.303695 134.52883) (xy 236.317425 134.52883) (xy 236.317425 134.54256) (xy 236.331155 134.54256)
			(xy 236.331155 134.55629) (xy 236.344885 134.55629) (xy 236.344885 134.57003) (xy 236.344885 134.58376)
			(xy 236.358615 134.58376) (xy 236.358615 134.59749) (xy 236.372345 134.59749) (xy 236.372345 134.61122)
			(xy 236.386085 134.61122) (xy 236.386085 134.62495) (xy 236.399815 134.62495) (xy 236.399815 134.63868)
			(xy 236.399815 134.65242) (xy 236.413545 134.65242) (xy 236.413545 134.66615) (xy 236.427275 134.66615)
			(xy 236.427275 134.67988) (xy 236.427275 134.69361) (xy 236.441005 134.69361) (xy 236.441005 134.70734)
			(xy 236.454735 134.70734) (xy 236.454735 134.72107) (xy 236.454735 134.73481) (xy 236.468475 134.73481)
			(xy 236.468475 134.74854) (xy 236.468475 134.76227) (xy 236.482205 134.76227) (xy 236.482205 134.776)
			(xy 236.482205 134.78973) (xy 236.495935 134.78973) (xy 236.495935 134.80347) (xy 236.495935 134.8172)
			(xy 236.495935 134.83093) (xy 236.509665 134.83093) (xy 236.509665 134.84466) (xy 236.509665 134.85839)
			(xy 236.523395 134.85839) (xy 236.523395 134.87213) (xy 236.523395 134.88586) (xy 236.523395 134.89959)
			(xy 236.537135 134.89959) (xy 236.537135 134.91332) (xy 236.537135 134.92705) (xy 236.537135 134.94078)
			(xy 236.537135 134.95452) (xy 236.550865 134.95452) (xy 236.550865 134.96825) (xy 236.550865 134.98198)
			(xy 236.550865 134.99571) (xy 236.550865 135.00944) (xy 236.550865 135.02317) (xy 236.564595 135.02317)
			(xy 236.564595 135.03691) (xy 236.564595 135.05064) (xy 236.564595 135.06437) (xy 236.564595 135.0781)
			(xy 236.564595 135.09183) (xy 236.564595 135.10556) (xy 236.564595 135.1193) (xy 236.564595 135.13303)
			(xy 236.564595 135.14676) (xy 236.564595 135.16049) (xy 236.564595 135.17422) (xy 236.564595 135.18795)
			(xy 236.564595 135.20169) (xy 236.564595 135.21542) (xy 236.564595 135.22915) (xy 236.564595 135.24288)
			(xy 236.564595 135.25661) (xy 236.564595 135.27034) (xy 236.564595 135.28408) (xy 236.550865 135.28408)
			(xy 236.550865 135.29781) (xy 236.550865 135.31154) (xy 236.550865 135.32527) (xy 236.550865 135.339)
			(xy 236.550865 135.35274) (xy 236.537135 135.35274) (xy 236.537135 135.36647) (xy 236.537135 135.3802)
			(xy 236.537135 135.39393) (xy 236.537135 135.40766) (xy 236.523395 135.40766) (xy 236.523395 135.4214)
			(xy 236.523395 135.43513) (xy 236.523395 135.44886) (xy 236.509665 135.44886) (xy 236.509665 135.46259)
			(xy 236.509665 135.47632) (xy 236.509665 135.49005) (xy 236.495935 135.49005) (xy 236.495935 135.50379)
			(xy 236.495935 135.51752) (xy 236.482205 135.51752) (xy 236.482205 135.53125) (xy 236.482205 135.54498)
			(xy 236.468475 135.54498) (xy 236.468475 135.55871) (xy 236.468475 135.57244) (xy 236.454735 135.57244)
			(xy 236.454735 135.58618) (xy 236.454735 135.59991) (xy 236.441005 135.59991) (xy 236.441005 135.61364)
			(xy 236.441005 135.62737) (xy 236.427275 135.62737) (xy 236.427275 135.6411) (xy 236.413545 135.6411)
			(xy 236.413545 135.65483) (xy 236.413545 135.66857) (xy 236.399815 135.66857) (xy 236.399815 135.6823)
			(xy 236.386085 135.6823) (xy 236.386085 135.69603) (xy 236.372345 135.69603) (xy 236.372345 135.70976)
			(xy 236.358615 135.70976) (xy 236.358615 135.72349) (xy 236.358615 135.73722) (xy 236.344885 135.73722)
			(xy 236.344885 135.75096) (xy 236.331155 135.75096) (xy 236.331155 135.76469) (xy 236.317425 135.76469)
			(xy 236.317425 135.77842) (xy 236.303695 135.77842) (xy 236.303695 135.79215) (xy 236.289955 135.79215)
			(xy 236.289955 135.80588) (xy 236.276225 135.80588) (xy 236.276225 135.81961) (xy 236.262495 135.81961)
			(xy 236.262495 135.83335) (xy 236.248765 135.83335) (xy 236.248765 135.84708) (xy 236.221305 135.84708)
			(xy 236.221305 135.86081) (xy 236.207575 135.86081) (xy 236.207575 135.87454) (xy 236.193835 135.87454)
			(xy 236.193835 135.88827) (xy 236.166375 135.88827) (xy 236.166375 135.90201) (xy 236.152645 135.90201)
			(xy 236.152645 135.91574) (xy 236.125185 135.91574) (xy 236.125185 135.92947) (xy 236.097715 135.92947)
			(xy 236.097715 135.9432) (xy 236.083985 135.9432) (xy 236.083985 135.95693) (xy 236.042785 135.95693)
			(xy 236.042785 135.97067) (xy 236.015325 135.97067) (xy 236.015325 135.9844) (xy 235.987865 135.9844)
			(xy 235.987865 135.99813) (xy 235.946665 135.99813) (xy 235.946665 136.01186) (xy 235.905475 136.01186)
			(xy 235.905475 136.02559) (xy 235.850545 136.02559) (xy 235.850545 136.03932) (xy 235.768155 136.03932)
			(xy 235.768155 136.05306) (xy 228.641375 136.05306) (xy 228.641375 136.06679) (xy 228.558985 136.06679)
			(xy 228.558985 136.08052) (xy 228.504055 136.08052) (xy 228.504055 136.09425) (xy 228.449125 136.09425)
			(xy 228.449125 136.10798) (xy 228.421665 136.10798) (xy 228.421665 136.12171) (xy 228.380475 136.12171)
			(xy 228.380475 136.13545) (xy 228.353005 136.13545) (xy 228.353005 136.14918) (xy 228.325545 136.14918)
			(xy 228.325545 136.16291) (xy 228.298085 136.16291) (xy 228.298085 136.17664) (xy 228.270615 136.17664)
			(xy 228.270615 136.19037) (xy 228.256885 136.19037) (xy 228.256885 136.2041) (xy 228.229425 136.2041)
			(xy 228.229425 136.21784) (xy 228.215695 136.21784) (xy 228.215695 136.23157) (xy 228.201955 136.23157)
			(xy 228.201955 136.2453) (xy 228.174495 136.2453) (xy 228.174495 136.25903) (xy 228.160765 136.25903)
			(xy 228.160765 136.27276) (xy 228.147035 136.27276) (xy 228.147035 136.28649) (xy 228.133295 136.28649)
			(xy 228.133295 136.30023) (xy 228.119565 136.30023) (xy 228.119565 136.31396) (xy 228.105835 136.31396)
			(xy 228.105835 136.32769) (xy 228.092105 136.32769) (xy 228.092105 136.34142) (xy 228.078375 136.34142)
			(xy 228.078375 136.35515) (xy 228.064635 136.35515) (xy 228.064635 136.36889) (xy 228.050905 136.36889)
			(xy 228.050905 136.38262) (xy 228.037175 136.38262) (xy 228.037175 136.39635) (xy 228.023445 136.39635)
			(xy 228.023445 136.41008) (xy 228.023445 136.42381) (xy 228.009715 136.42381) (xy 228.009715 136.43755)
			(xy 227.995985 136.43755) (xy 227.995985 136.45128) (xy 227.995985 136.46501) (xy 227.982245 136.46501)
			(xy 227.982245 136.47874) (xy 227.968515 136.47874) (xy 227.968515 136.49247) (xy 227.968515 136.5062)
			(xy 227.954785 136.5062) (xy 227.954785 136.51994) (xy 227.954785 136.53367) (xy 227.941055 136.53367)
			(xy 227.941055 136.5474) (xy 227.941055 136.56113) (xy 227.927325 136.56113) (xy 227.927325 136.57486)
			(xy 227.927325 136.58859) (xy 227.913595 136.58859) (xy 227.913595 136.60233) (xy 227.913595 136.61606)
			(xy 227.899855 136.61606) (xy 227.899855 136.62979) (xy 227.899855 136.64352) (xy 227.899855 136.65725)
			(xy 227.886125 136.65725) (xy 227.886125 136.67098) (xy 227.886125 136.68472) (xy 227.886125 136.69845)
			(xy 227.872395 136.69845) (xy 227.872395 136.71218) (xy 227.872395 136.72591) (xy 227.872395 136.73964)
			(xy 227.872395 136.75337) (xy 227.858665 136.75337) (xy 227.858665 136.76711) (xy 227.858665 136.78084)
			(xy 227.858665 136.79457) (xy 227.858665 136.8083) (xy 227.858665 136.82203) (xy 227.858665 136.83576)
			(xy 227.844935 136.83576) (xy 227.844935 136.8495) (xy 227.844935 136.86323) (xy 227.844935 136.87696)
			(xy 227.844935 136.89069) (xy 227.844935 136.90442) (xy 227.844935 136.91816) (xy 227.844935 136.93189)
			(xy 227.844935 136.94562) (xy 227.844935 136.95935) (xy 227.844935 136.97308) (xy 227.844935 136.98682)
			(xy 227.844935 137.00055) (xy 227.844935 137.01428) (xy 227.844935 137.02801) (xy 227.844935 137.04174)
			(xy 227.844935 137.05547) (xy 227.858665 137.05547) (xy 227.858665 137.06921) (xy 227.858665 137.08294)
			(xy 227.858665 137.09667) (xy 227.858665 137.1104) (xy 227.858665 137.12413) (xy 227.858665 137.13786)
			(xy 227.872395 137.13786) (xy 227.872395 137.1516) (xy 227.872395 137.16533) (xy 227.872395 137.17906)
			(xy 227.872395 137.19279) (xy 227.886125 137.19279) (xy 227.886125 137.20652) (xy 227.886125 137.22025)
			(xy 227.886125 137.23399) (xy 227.899855 137.23399) (xy 227.899855 137.24772) (xy 227.899855 137.26145)
			(xy 227.899855 137.27518) (xy 227.913595 137.27518) (xy 227.913595 137.28891) (xy 227.913595 137.30264)
			(xy 227.927325 137.30264) (xy 227.927325 137.31638) (xy 227.927325 137.33011) (xy 227.941055 137.33011)
			(xy 227.941055 137.34384) (xy 227.941055 137.35757) (xy 227.954785 137.35757) (xy 227.954785 137.3713)
			(xy 227.954785 137.38503) (xy 227.968515 137.38503) (xy 227.968515 137.39877) (xy 227.968515 137.4125)
			(xy 227.982245 137.4125) (xy 227.982245 137.42623) (xy 227.995985 137.42623) (xy 227.995985 137.43996)
			(xy 227.995985 137.45369) (xy 228.009715 137.45369) (xy 228.009715 137.46743) (xy 228.023445 137.46743)
			(xy 228.023445 137.48116) (xy 228.037175 137.48116) (xy 228.037175 137.49489) (xy 228.037175 137.50862)
			(xy 228.050905 137.50862) (xy 228.050905 137.52235) (xy 228.064635 137.52235) (xy 228.064635 137.53609)
			(xy 228.078375 137.53609) (xy 228.078375 137.54982) (xy 228.092105 137.54982) (xy 228.092105 137.56355)
			(xy 228.105835 137.56355) (xy 228.105835 137.57728) (xy 228.119565 137.57728) (xy 228.119565 137.59101)
			(xy 228.133295 137.59101) (xy 228.133295 137.60474) (xy 228.147035 137.60474) (xy 228.147035 137.61848)
			(xy 228.160765 137.61848) (xy 228.160765 137.63221) (xy 228.188225 137.63221) (xy 228.188225 137.64594)
			(xy 228.201955 137.64594) (xy 228.201955 137.65967) (xy 228.215695 137.65967) (xy 228.215695 137.6734)
			(xy 228.243155 137.6734) (xy 228.243155 137.68713) (xy 228.256885 137.68713) (xy 228.256885 137.70087)
			(xy 228.284345 137.70087) (xy 228.284345 137.7146) (xy 228.311815 137.7146) (xy 228.311815 137.72833)
			(xy 228.325545 137.72833) (xy 228.325545 137.74206) (xy 228.353005 137.74206) (xy 228.353005 137.75579)
			(xy 228.394205 137.75579) (xy 228.394205 137.76952) (xy 228.421665 137.76952) (xy 228.421665 137.78326)
			(xy 228.462865 137.78326) (xy 228.462865 137.79699) (xy 228.504055 137.79699) (xy 228.504055 137.81072)
			(xy 228.558985 137.81072) (xy 228.558985 137.82445) (xy 228.655105 137.82445) (xy 228.655105 137.83818)
			(xy 231.291605 137.83818) (xy 231.291605 137.85191) (xy 231.360265 137.85191) (xy 231.360265 137.86565)
			(xy 231.415185 137.86565) (xy 231.415185 137.87938) (xy 231.456385 137.87938) (xy 231.456385 137.89311)
			(xy 231.497575 137.89311) (xy 231.497575 137.90684) (xy 231.538775 137.90684) (xy 231.538775 137.92057)
			(xy 231.566235 137.92057) (xy 231.566235 137.9343) (xy 231.593705 137.9343) (xy 231.593705 137.94804)
			(xy 231.621165 137.94804) (xy 231.621165 137.96177) (xy 231.648625 137.96177) (xy 231.648625 137.9755)
			(xy 231.662355 137.9755) (xy 231.662355 137.98923) (xy 231.689825 137.98923) (xy 231.689825 138.00296)
			(xy 231.703555 138.00296) (xy 231.703555 138.0167) (xy 231.717285 138.0167) (xy 231.717285 138.03043)
			(xy 231.744745 138.03043) (xy 231.744745 138.04416) (xy 231.758485 138.04416) (xy 231.758485 138.05789)
			(xy 231.772215 138.05789) (xy 231.772215 138.07162) (xy 231.785945 138.07162) (xy 231.785945 138.08536)
			(xy 231.799675 138.08536) (xy 231.799675 138.09909) (xy 231.813405 138.09909) (xy 231.813405 138.11282)
			(xy 231.827145 138.11282) (xy 231.827145 138.12655) (xy 231.840875 138.12655) (xy 231.840875 138.14028)
			(xy 231.854605 138.14028) (xy 231.854605 138.15401) (xy 231.868335 138.15401) (xy 231.868335 138.16775)
			(xy 231.882065 138.16775) (xy 231.882065 138.18148) (xy 231.895805 138.18148) (xy 231.895805 138.19521)
			(xy 231.895805 138.20894) (xy 231.909535 138.20894) (xy 231.909535 138.22267) (xy 231.923265 138.22267)
			(xy 231.923265 138.2364) (xy 231.936995 138.2364) (xy 231.936995 138.25014) (xy 231.936995 138.26387)
			(xy 231.950725 138.26387) (xy 231.950725 138.2776) (xy 231.950725 138.29133) (xy 231.964455 138.29133)
			(xy 231.964455 138.30506) (xy 231.978195 138.30506) (xy 231.978195 138.31879) (xy 231.978195 138.33253)
			(xy 231.991925 138.33253) (xy 231.991925 138.34626) (xy 231.991925 138.35999) (xy 232.005655 138.35999)
			(xy 232.005655 138.37372) (xy 232.005655 138.38745) (xy 232.005655 138.40118) (xy 232.019385 138.40118)
			(xy 232.019385 138.41492) (xy 232.019385 138.42865) (xy 232.033115 138.42865) (xy 232.033115 138.44238)
			(xy 232.033115 138.45611) (xy 232.033115 138.46984) (xy 232.046845 138.46984) (xy 232.046845 138.48358)
			(xy 232.046845 138.49731) (xy 232.046845 138.51104) (xy 232.046845 138.52477) (xy 232.060585 138.52477)
			(xy 232.060585 138.5385) (xy 232.060585 138.55224) (xy 232.060585 138.56597) (xy 232.060585 138.5797)
			(xy 232.060585 138.59343) (xy 232.074315 138.59343) (xy 232.074315 138.60716) (xy 232.074315 138.62089)
			(xy 232.074315 138.63463) (xy 232.074315 138.64836) (xy 232.074315 138.66209) (xy 232.074315 138.67582)
			(xy 232.074315 138.68955) (xy 232.074315 138.70328) (xy 232.074315 138.71702) (xy 232.074315 138.73075)
			(xy 232.074315 138.74448) (xy 232.074315 138.75821) (xy 232.074315 138.77194) (xy 232.074315 138.78567)
			(xy 232.074315 138.79941) (xy 232.074315 138.81314) (xy 232.074315 138.82687) (xy 232.074315 138.8406)
			(xy 232.074315 138.85433) (xy 232.074315 138.86806) (xy 232.074315 138.8818) (xy 232.060585 138.8818)
			(xy 232.060585 138.89553) (xy 232.060585 138.90926) (xy 232.060585 138.92299) (xy 232.060585 138.93672)
			(xy 232.060585 138.95045) (xy 232.046845 138.95045) (xy 232.046845 138.96419) (xy 232.046845 138.97792)
			(xy 232.046845 138.99165) (xy 232.033115 138.99165) (xy 232.033115 139.00538) (xy 232.033115 139.01911)
			(xy 232.033115 139.03285) (xy 232.019385 139.03285) (xy 232.019385 139.04658) (xy 232.019385 139.06031)
			(xy 232.019385 139.07404) (xy 232.005655 139.07404) (xy 232.005655 139.08777) (xy 232.005655 139.10151)
			(xy 231.991925 139.10151) (xy 231.991925 139.11524) (xy 231.991925 139.12897) (xy 231.978195 139.12897)
			(xy 231.978195 139.1427) (xy 231.978195 139.15643) (xy 231.964455 139.15643) (xy 231.964455 139.17016)
			(xy 231.964455 139.1839) (xy 231.950725 139.1839) (xy 231.950725 139.19763) (xy 231.950725 139.21136)
			(xy 231.936995 139.21136) (xy 231.936995 139.22509) (xy 231.923265 139.22509) (xy 231.923265 139.23882)
			(xy 231.923265 139.25255) (xy 231.909535 139.25255) (xy 231.909535 139.26629) (xy 231.895805 139.26629)
			(xy 231.895805 139.28002) (xy 231.882065 139.28002) (xy 231.882065 139.29375) (xy 231.868335 139.29375)
			(xy 231.868335 139.30748) (xy 231.868335 139.32121) (xy 231.854605 139.32121) (xy 231.854605 139.33494)
			(xy 231.840875 139.33494) (xy 231.840875 139.34868) (xy 231.827145 139.34868) (xy 231.827145 139.36241)
			(xy 231.813405 139.36241) (xy 231.813405 139.37614) (xy 231.799675 139.37614) (xy 231.799675 139.38987)
			(xy 231.785945 139.38987) (xy 231.785945 139.4036) (xy 231.772215 139.4036) (xy 231.772215 139.41733)
			(xy 231.744745 139.41733) (xy 231.744745 139.43107) (xy 231.731015 139.43107) (xy 231.731015 139.4448)
			(xy 231.717285 139.4448) (xy 231.717285 139.45853) (xy 231.689825 139.45853) (xy 231.689825 139.47226)
			(xy 231.676095 139.47226) (xy 231.676095 139.48599) (xy 231.648625 139.48599) (xy 231.648625 139.49972)
			(xy 231.634895 139.49972) (xy 231.634895 139.51346) (xy 231.607435 139.51346) (xy 231.607435 139.52719)
			(xy 231.579965 139.52719) (xy 231.579965 139.54092) (xy 231.552505 139.54092) (xy 231.552505 139.55465)
			(xy 231.525045 139.55465) (xy 231.525045 139.56838) (xy 231.483845 139.56838) (xy 231.483845 139.58212)
			(xy 231.442655 139.58212) (xy 231.442655 139.59585) (xy 231.401455 139.59585) (xy 231.401455 139.60958)
			(xy 231.332795 139.60958) (xy 231.332795 139.62331) (xy 231.236675 139.62331) (xy 231.236675 139.63704)
			(xy 231.209215 139.63704) (xy 231.209215 139.62331) (xy 231.195475 139.62331) (xy 231.195475 139.63704)
			(xy 227.075955 139.63704) (xy 227.075955 139.62331) (xy 227.062225 139.62331) (xy 227.062225 139.63704)
			(xy 226.924905 139.63704) (xy 226.924905 139.65078) (xy 226.856245 139.65078) (xy 226.856245 139.66451)
			(xy 226.801325 139.66451) (xy 226.801325 139.67824) (xy 226.760125 139.67824) (xy 226.760125 139.69197)
			(xy 226.732665 139.69197) (xy 226.732665 139.7057) (xy 226.691465 139.7057) (xy 226.691465 139.71943)
			(xy 226.664005 139.71943) (xy 226.664005 139.73317) (xy 226.636545 139.73317) (xy 226.636545 139.7469)
			(xy 226.622805 139.7469) (xy 226.622805 139.76063) (xy 226.595345 139.76063) (xy 226.595345 139.77436)
			(xy 226.567885 139.77436) (xy 226.567885 139.78809) (xy 226.554145 139.78809) (xy 226.554145 139.80182)
			(xy 226.526685 139.80182) (xy 226.526685 139.81556) (xy 226.512955 139.81556) (xy 226.512955 139.82929)
			(xy 226.499225 139.82929) (xy 226.499225 139.84302) (xy 226.485485 139.84302) (xy 226.485485 139.85675)
			(xy 226.458025 139.85675) (xy 226.458025 139.87048) (xy 226.444295 139.87048) (xy 226.444295 139.88421)
			(xy 226.430565 139.88421) (xy 226.430565 139.89795) (xy 226.416835 139.89795) (xy 226.416835 139.91168)
			(xy 226.403095 139.91168) (xy 226.403095 139.92541) (xy 226.389365 139.92541) (xy 226.389365 139.93914)
			(xy 226.389365 139.95287) (xy 226.375635 139.95287) (xy 226.375635 139.9666) (xy 226.361905 139.9666)
			(xy 226.361905 139.98034) (xy 226.348175 139.98034) (xy 226.348175 139.99407) (xy 226.334445 139.99407)
			(xy 226.334445 140.0078) (xy 226.334445 140.02153) (xy 226.320705 140.02153) (xy 226.320705 140.03526)
			(xy 226.306975 140.03526) (xy 226.306975 140.04899) (xy 226.306975 140.06273) (xy 226.293245 140.06273)
			(xy 226.293245 140.07646) (xy 226.279515 140.07646) (xy 226.279515 140.09019) (xy 226.279515 140.10392)
			(xy 226.265785 140.10392) (xy 226.265785 140.11765) (xy 226.265785 140.13139) (xy 226.252055 140.13139)
			(xy 226.252055 140.14512) (xy 226.252055 140.15885) (xy 226.238315 140.15885) (xy 226.238315 140.17258)
			(xy 226.238315 140.18631) (xy 226.224585 140.18631) (xy 226.224585 140.20005) (xy 226.224585 140.21378)
			(xy 226.224585 140.22751) (xy 226.210855 140.22751) (xy 226.210855 140.24124) (xy 226.210855 140.25497)
			(xy 226.210855 140.2687) (xy 226.197125 140.2687) (xy 226.197125 140.28244) (xy 226.197125 140.29617)
			(xy 226.197125 140.3099) (xy 226.183395 140.3099) (xy 226.183395 140.32363) (xy 226.183395 140.33736)
			(xy 226.183395 140.35109) (xy 226.183395 140.36483) (xy 226.183395 140.37856) (xy 226.169665 140.37856)
			(xy 226.169665 140.39229) (xy 226.169665 140.40602) (xy 226.169665 140.41975) (xy 226.169665 140.43348)
			(xy 226.169665 140.44722) (xy 226.169665 140.46095) (xy 226.169665 140.47468) (xy 226.169665 140.48841)
			(xy 226.169665 140.50214) (xy 226.169665 140.51587) (xy 226.169665 140.5296) (xy 226.169665 140.54334)
			(xy 226.169665 140.55707) (xy 226.169665 140.5708) (xy 226.169665 140.58453) (xy 226.169665 140.59827)
			(xy 226.169665 140.612) (xy 226.169665 140.62573) (xy 226.169665 140.63946) (xy 226.169665 140.65319)
			(xy 226.169665 140.66693) (xy 226.183395 140.66693) (xy 226.183395 140.68066) (xy 226.183395 140.69439)
			(xy 226.183395 140.70812) (xy 226.183395 140.72185) (xy 226.183395 140.73558) (xy 226.197125 140.73558)
			(xy 226.197125 140.74931) (xy 226.197125 140.76305) (xy 226.197125 140.77678) (xy 226.210855 140.77678)
			(xy 226.210855 140.79051) (xy 226.210855 140.80424) (xy 226.210855 140.81797) (xy 226.224585 140.81797)
			(xy 226.224585 140.8317) (xy 226.224585 140.84544) (xy 226.224585 140.85917) (xy 226.238315 140.85917)
			(xy 226.238315 140.8729) (xy 226.238315 140.88663) (xy 226.252055 140.88663) (xy 226.252055 140.90036)
			(xy 226.252055 140.91409) (xy 226.265785 140.91409) (xy 226.265785 140.92783) (xy 226.265785 140.94156)
			(xy 226.279515 140.94156) (xy 226.279515 140.95529) (xy 226.279515 140.96902) (xy 226.293245 140.96902)
			(xy 226.293245 140.98275) (xy 226.293245 140.99648) (xy 226.306975 140.99648) (xy 226.306975 141.01022)
			(xy 226.320705 141.01022) (xy 226.320705 141.02395) (xy 226.320705 141.03768) (xy 226.334445 141.03768)
			(xy 226.334445 141.05141) (xy 226.348175 141.05141) (xy 226.348175 141.06514) (xy 226.361905 141.06514)
			(xy 226.361905 141.07888) (xy 226.361905 141.09261) (xy 226.375635 141.09261) (xy 226.375635 141.10634)
			(xy 226.389365 141.10634) (xy 226.389365 141.12007) (xy 226.403095 141.12007) (xy 226.403095 141.1338)
			(xy 226.416835 141.1338) (xy 226.416835 141.14754) (xy 226.430565 141.14754) (xy 226.430565 141.16127)
			(xy 226.444295 141.16127) (xy 226.444295 141.175) (xy 226.458025 141.175) (xy 226.458025 141.18873)
			(xy 226.471755 141.18873) (xy 226.471755 141.20246) (xy 226.485485 141.20246) (xy 226.485485 141.21619)
			(xy 226.512955 141.21619) (xy 226.512955 141.22993) (xy 226.526685 141.22993) (xy 226.526685 141.24366)
			(xy 226.540415 141.24366) (xy 226.540415 141.25739) (xy 226.567885 141.25739) (xy 226.567885 141.27112)
			(xy 226.581615 141.27112) (xy 226.581615 141.28485) (xy 226.609075 141.28485) (xy 226.609075 141.29858)
			(xy 226.636545 141.29858) (xy 226.636545 141.31232) (xy 226.664005 141.31232) (xy 226.664005 141.32605)
			(xy 226.691465 141.32605) (xy 226.691465 141.33978) (xy 226.718935 141.33978) (xy 226.718935 141.35351)
			(xy 226.760125 141.35351) (xy 226.760125 141.36724) (xy 226.787585 141.36724) (xy 226.787585 141.38097)
			(xy 226.842515 141.38097) (xy 226.842515 141.39471) (xy 226.911175 141.39471) (xy 226.911175 141.40844)
			(xy 227.034755 141.40844) (xy 227.034755 141.42217) (xy 229.877235 141.42217) (xy 229.877235 141.4359)
			(xy 229.945895 141.4359) (xy 229.945895 141.44963) (xy 229.987085 141.44963) (xy 229.987085 141.46336)
			(xy 230.028285 141.46336) (xy 230.028285 141.4771) (xy 230.069475 141.4771) (xy 230.069475 141.49083)
			(xy 230.110675 141.49083) (xy 230.110675 141.50456) (xy 230.138135 141.50456) (xy 230.138135 141.51829)
			(xy 230.165595 141.51829) (xy 230.165595 141.53202) (xy 230.179325 141.53202) (xy 230.179325 141.54575)
			(xy 230.206795 141.54575) (xy 230.206795 141.55949) (xy 230.234255 141.55949) (xy 230.234255 141.57322)
			(xy 230.247985 141.57322) (xy 230.247985 141.58695) (xy 230.275455 141.58695) (xy 230.275455 141.60068)
			(xy 230.289185 141.60068) (xy 230.289185 141.61441) (xy 230.302915 141.61441) (xy 230.302915 141.62815)
			(xy 230.316645 141.62815) (xy 230.316645 141.64188) (xy 230.344115 141.64188) (xy 230.344115 141.65561)
			(xy 230.357845 141.65561) (xy 230.357845 141.66934) (xy 230.371575 141.66934) (xy 230.371575 141.68307)
			(xy 230.385305 141.68307) (xy 230.385305 141.69681) (xy 230.399035 141.69681) (xy 230.399035 141.71054)
			(xy 230.412775 141.71054) (xy 230.412775 141.72427) (xy 230.412775 141.738) (xy 230.426505 141.738)
			(xy 230.426505 141.75173) (xy 230.440235 141.75173) (xy 230.440235 141.76546) (xy 230.453965 141.76546)
			(xy 230.453965 141.7792) (xy 230.467695 141.7792) (xy 230.467695 141.79293) (xy 230.467695 141.80666)
			(xy 230.481425 141.80666) (xy 230.481425 141.82039) (xy 230.495165 141.82039) (xy 230.495165 141.83412)
			(xy 230.495165 141.84785) (xy 230.508895 141.84785) (xy 230.508895 141.86159) (xy 230.522625 141.86159)
			(xy 230.522625 141.87532) (xy 230.522625 141.88905) (xy 230.536355 141.88905) (xy 230.536355 141.90278)
			(xy 230.536355 141.91651) (xy 230.550085 141.91651) (xy 230.550085 141.93024) (xy 230.550085 141.94398)
			(xy 230.563815 141.94398) (xy 230.563815 141.95771) (xy 230.563815 141.97144) (xy 230.577555 141.97144)
			(xy 230.577555 141.98517) (xy 230.577555 141.9989) (xy 230.577555 142.01263) (xy 230.591285 142.01263)
			(xy 230.591285 142.02637) (xy 230.591285 142.0401) (xy 230.591285 142.05383) (xy 230.605015 142.05383)
			(xy 230.605015 142.06756) (xy 230.605015 142.08129) (xy 230.605015 142.09502) (xy 230.618745 142.09502)
			(xy 230.618745 142.10876) (xy 230.618745 142.12249) (xy 230.618745 142.13622) (xy 230.618745 142.14995)
			(xy 230.618745 142.16368) (xy 230.618745 142.17742) (xy 230.632475 142.17742) (xy 230.632475 142.19115)
			(xy 230.632475 142.20488) (xy 230.632475 142.21861) (xy 230.632475 142.23234) (xy 230.632475 142.24608)
			(xy 230.632475 142.25981) (xy 230.632475 142.27354) (xy 230.632475 142.28727) (xy 230.632475 142.301)
			(xy 230.646205 142.301) (xy 230.646205 142.31473) (xy 230.646205 142.32847) (xy 230.632475 142.32847)
			(xy 230.632475 142.3422) (xy 230.632475 142.35593) (xy 230.632475 142.36966) (xy 230.632475 142.38339)
			(xy 230.632475 142.39712) (xy 230.632475 142.41086) (xy 230.632475 142.42459) (xy 230.632475 142.43832)
			(xy 230.632475 142.45205) (xy 230.632475 142.46578) (xy 230.618745 142.46578) (xy 230.618745 142.47951)
			(xy 230.618745 142.49325) (xy 230.618745 142.50698) (xy 230.618745 142.52071) (xy 230.618745 142.53444)
			(xy 230.605015 142.53444) (xy 230.605015 142.54817) (xy 230.605015 142.5619) (xy 230.605015 142.57564)
			(xy 230.591285 142.57564) (xy 230.591285 142.58937) (xy 230.591285 142.6031) (xy 230.591285 142.61683)
			(xy 230.577555 142.61683) (xy 230.577555 142.63056) (xy 230.577555 142.64429) (xy 230.577555 142.65803)
			(xy 230.563815 142.65803) (xy 230.563815 142.67176) (xy 230.563815 142.68549) (xy 230.563815 142.69922)
			(xy 230.550085 142.69922) (xy 230.550085 142.71295) (xy 230.550085 142.72669) (xy 230.536355 142.72669)
			(xy 230.536355 142.74042) (xy 230.536355 142.75415) (xy 230.522625 142.75415) (xy 230.522625 142.76788)
			(xy 230.522625 142.78161) (xy 230.508895 142.78161) (xy 230.508895 142.79535) (xy 230.495165 142.79535)
			(xy 230.495165 142.80908) (xy 230.495165 142.82281) (xy 230.481425 142.82281) (xy 230.481425 142.83654)
			(xy 230.467695 142.83654) (xy 230.467695 142.85027) (xy 230.467695 142.864) (xy 230.453965 142.864)
			(xy 230.453965 142.87774) (xy 230.440235 142.87774) (xy 230.440235 142.89147) (xy 230.426505 142.89147)
			(xy 230.426505 142.9052) (xy 230.426505 142.91893) (xy 230.412775 142.91893) (xy 230.412775 142.93266)
			(xy 230.399035 142.93266) (xy 230.399035 142.94639) (xy 230.385305 142.94639) (xy 230.385305 142.96013)
			(xy 230.371575 142.96013) (xy 230.371575 142.97386) (xy 230.357845 142.97386) (xy 230.357845 142.98759)
			(xy 230.344115 142.98759) (xy 230.344115 143.00132) (xy 230.330385 143.00132) (xy 230.330385 143.01505)
			(xy 230.316645 143.01505) (xy 230.316645 143.02878) (xy 230.302915 143.02878) (xy 230.302915 143.04252)
			(xy 230.289185 143.04252) (xy 230.289185 143.05625) (xy 230.261725 143.05625) (xy 230.261725 143.06998)
			(xy 230.247985 143.06998) (xy 230.247985 143.08371) (xy 230.234255 143.08371) (xy 230.234255 143.09744)
			(xy 230.206795 143.09744) (xy 230.206795 143.11117) (xy 230.193065 143.11117) (xy 230.193065 143.12491)
			(xy 230.165595 143.12491) (xy 230.165595 143.13864) (xy 230.138135 143.13864) (xy 230.138135 143.15237)
			(xy 230.110675 143.15237) (xy 230.110675 143.1661) (xy 230.083205 143.1661) (xy 230.083205 143.17983)
			(xy 230.042015 143.17983) (xy 230.042015 143.19357) (xy 229.987085 143.19357) (xy 229.987085 143.2073)
			(xy 220.100225 143.2073) (xy 220.100225 143.22103) (xy 220.072765 143.22103) (xy 220.072765 143.23476)
			(xy 220.059025 143.23476) (xy 220.059025 143.24849) (xy 220.045295 143.24849) (xy 220.045295 143.26223)
			(xy 220.031565 143.26223) (xy 220.031565 143.27596) (xy 220.031565 143.28969) (xy 220.017835 143.28969)
			(xy 220.017835 143.30342) (xy 220.017835 143.31715) (xy 220.017835 143.33088) (xy 220.017835 143.34462)
			(xy 220.017835 143.35835) (xy 220.017835 143.37208) (xy 220.017835 143.38581) (xy 220.017835 143.39954)
			(xy 220.017835 143.41327) (xy 220.017835 143.42701) (xy 220.017835 143.44074) (xy 220.017835 143.45447)
			(xy 220.017835 143.4682) (xy 220.017835 143.48193) (xy 220.017835 143.49566) (xy 220.017835 143.5094)
			(xy 220.017835 143.52313) (xy 220.017835 143.53686) (xy 220.017835 143.55059) (xy 220.017835 143.56432)
			(xy 220.017835 143.57805) (xy 220.017835 143.59179) (xy 220.017835 143.60552) (xy 220.017835 143.61925)
			(xy 220.017835 143.63298) (xy 220.017835 143.64671) (xy 220.017835 143.66044) (xy 220.017835 143.67418)
			(xy 220.017835 143.68791) (xy 220.017835 143.70164) (xy 220.017835 143.71537) (xy 220.017835 143.7291)
			(xy 220.017835 143.74284) (xy 220.017835 143.75657) (xy 220.017835 143.7703) (xy 220.017835 143.78403)
			(xy 220.017835 143.79776) (xy 220.017835 143.8115) (xy 220.017835 143.82523) (xy 220.017835 143.83896)
			(xy 220.017835 143.85269) (xy 220.017835 143.86642) (xy 220.017835 143.88015) (xy 220.017835 143.89389)
			(xy 220.017835 143.90762) (xy 220.017835 143.92135) (xy 220.017835 143.93508) (xy 220.017835 143.94881)
			(xy 220.017835 143.96254) (xy 220.017835 143.97628) (xy 220.017835 143.99001) (xy 220.017835 144.00374)
			(xy 220.017835 144.01747) (xy 220.017835 144.0312) (xy 220.017835 144.04493) (xy 220.017835 144.05867)
			(xy 220.017835 144.0724) (xy 220.017835 144.08613) (xy 220.017835 144.09986) (xy 220.017835 144.11359)
			(xy 220.017835 144.12732) (xy 220.017835 144.14106) (xy 220.017835 144.15479) (xy 220.017835 144.16852)
			(xy 220.017835 144.18225) (xy 220.017835 144.19598) (xy 220.017835 144.20971) (xy 220.017835 144.22345)
			(xy 220.017835 144.23718) (xy 220.017835 144.25091) (xy 220.017835 144.26464) (xy 220.017835 144.27837)
			(xy 220.017835 144.29211) (xy 220.017835 144.30584) (xy 220.017835 144.31957) (xy 220.017835 144.3333)
			(xy 220.017835 144.34703) (xy 220.017835 144.36077) (xy 220.017835 144.3745) (xy 220.017835 144.38823)
			(xy 220.017835 144.40196) (xy 220.017835 144.41569) (xy 220.017835 144.42942) (xy 220.017835 144.44316)
			(xy 220.017835 144.45689) (xy 220.017835 144.47062) (xy 220.017835 144.48435) (xy 220.017835 144.49808)
			(xy 220.017835 144.51181) (xy 220.017835 144.52555) (xy 220.017835 144.53928) (xy 220.017835 144.55301)
			(xy 220.017835 144.56674) (xy 220.017835 144.58047) (xy 220.017835 144.5942) (xy 220.017835 144.60794)
			(xy 220.017835 144.62167) (xy 220.017835 144.6354) (xy 220.017835 144.64913) (xy 220.004105 144.64913)
			(xy 220.004105 144.66286) (xy 220.004105 144.67659) (xy 219.990375 144.67659) (xy 219.990375 144.69033)
			(xy 219.990375 144.70406) (xy 219.976635 144.70406) (xy 219.976635 144.71779) (xy 219.949175 144.71779)
			(xy 219.949175 144.73152) (xy 219.921715 144.73152) (xy 219.921715 144.74525) (xy 217.298945 144.74525)
			(xy 217.298945 144.73152) (xy 217.257755 144.73152) (xy 217.257755 144.71779) (xy 217.244025 144.71779)
			(xy 217.244025 144.70406) (xy 217.230295 144.70406) (xy 217.230295 144.69033) (xy 217.216555 144.69033)
			(xy 217.216555 144.67659) (xy 217.216555 144.66286) (xy 217.202825 144.66286) (xy 217.202825 144.64913)
			(xy 217.202825 144.6354) (xy 217.202825 144.62167) (xy 217.202825 144.60794) (xy 217.202825 144.5942)
			(xy 217.202825 144.58047) (xy 217.202825 144.56674) (xy 217.202825 144.55301) (xy 217.202825 144.53928)
			(xy 217.202825 144.52555) (xy 217.202825 144.51181) (xy 217.202825 144.49808) (xy 217.202825 144.48435)
			(xy 217.202825 144.47062) (xy 217.202825 144.45689) (xy 217.202825 144.44316) (xy 217.202825 144.42942)
			(xy 217.202825 144.41569) (xy 217.202825 144.40196) (xy 217.202825 144.38823) (xy 217.202825 144.3745)
			(xy 217.202825 144.36077) (xy 217.202825 144.34703) (xy 217.202825 144.3333) (xy 217.202825 144.31957)
			(xy 217.202825 144.30584) (xy 217.202825 144.29211) (xy 217.202825 144.27837) (xy 217.202825 144.26464)
			(xy 217.202825 144.25091) (xy 217.202825 144.23718) (xy 217.202825 144.22345) (xy 217.202825 144.20971)
			(xy 217.202825 144.19598) (xy 217.202825 144.18225) (xy 217.202825 144.16852) (xy 217.202825 144.15479)
			(xy 217.202825 144.14106) (xy 217.202825 144.12732) (xy 217.202825 144.11359) (xy 217.202825 144.09986)
			(xy 217.202825 144.08613) (xy 217.202825 144.0724) (xy 217.202825 144.05867) (xy 217.202825 144.04493)
			(xy 217.202825 144.0312) (xy 217.202825 144.01747) (xy 217.202825 144.00374) (xy 217.202825 143.99001)
			(xy 217.202825 143.97628) (xy 217.202825 143.96254) (xy 217.202825 143.94881) (xy 217.202825 143.93508)
			(xy 217.202825 143.92135) (xy 217.202825 143.90762) (xy 217.202825 143.89389) (xy 217.202825 143.88015)
			(xy 217.202825 143.86642) (xy 217.202825 143.85269) (xy 217.202825 143.83896) (xy 217.202825 143.82523)
			(xy 217.189095 143.82523) (xy 217.189095 143.8115) (xy 217.189095 143.79776) (xy 217.189095 143.78403)
			(xy 217.175365 143.78403) (xy 217.175365 143.7703) (xy 217.175365 143.75657) (xy 217.161635 143.75657)
			(xy 217.161635 143.74284) (xy 217.134165 143.74284) (xy 217.134165 143.7291) (xy 217.092975 143.7291)
			(xy 217.092975 143.71537) (xy 217.051775 143.71537) (xy 217.051775 143.7291) (xy 217.010585 143.7291)
			(xy 217.010585 143.74284) (xy 216.996845 143.74284) (xy 216.996845 143.75657) (xy 216.983115 143.75657)
			(xy 216.983115 143.7703) (xy 216.969385 143.7703) (xy 216.969385 143.78403) (xy 216.955655 143.78403)
			(xy 216.955655 143.79776) (xy 216.955655 143.8115) (xy 216.955655 143.82523) (xy 216.955655 143.83896)
			(xy 216.941925 143.83896) (xy 216.941925 143.85269) (xy 216.941925 143.86642) (xy 216.941925 143.88015)
			(xy 216.941925 143.89389) (xy 216.941925 143.90762) (xy 216.941925 143.92135) (xy 216.941925 143.93508)
			(xy 216.941925 143.94881) (xy 216.941925 143.96254) (xy 216.941925 143.97628) (xy 216.941925 143.99001)
			(xy 216.941925 144.00374) (xy 216.941925 144.01747) (xy 216.941925 144.0312) (xy 216.941925 144.04493)
			(xy 216.941925 144.05867) (xy 216.941925 144.0724) (xy 216.941925 144.08613) (xy 216.941925 144.09986)
			(xy 216.941925 144.11359) (xy 216.941925 144.12732) (xy 216.941925 144.14106) (xy 216.941925 144.15479)
			(xy 216.941925 144.16852) (xy 216.941925 144.18225) (xy 216.941925 144.19598) (xy 216.941925 144.20971)
			(xy 216.941925 144.22345) (xy 216.941925 144.23718) (xy 216.941925 144.25091) (xy 216.941925 144.26464)
			(xy 216.941925 144.27837) (xy 216.941925 144.29211) (xy 216.941925 144.30584) (xy 216.941925 144.31957)
			(xy 216.941925 144.3333) (xy 216.941925 144.34703) (xy 216.941925 144.36077) (xy 216.941925 144.3745)
			(xy 216.941925 144.38823) (xy 216.941925 144.40196) (xy 216.941925 144.41569) (xy 216.941925 144.42942)
			(xy 216.941925 144.44316) (xy 216.941925 144.45689) (xy 216.941925 144.47062) (xy 216.941925 144.48435)
			(xy 216.941925 144.49808) (xy 216.941925 144.51181) (xy 216.941925 144.52555) (xy 216.941925 144.53928)
			(xy 216.941925 144.55301) (xy 216.941925 144.56674) (xy 216.941925 144.58047) (xy 216.941925 144.5942)
			(xy 216.941925 144.60794) (xy 216.941925 144.62167) (xy 216.941925 144.6354) (xy 216.941925 144.64913)
			(xy 216.941925 144.66286) (xy 216.941925 144.67659) (xy 216.928195 144.67659) (xy 216.928195 144.69033)
			(xy 216.914455 144.69033) (xy 216.914455 144.70406) (xy 216.900725 144.70406) (xy 216.900725 144.71779)
			(xy 216.886995 144.71779) (xy 216.886995 144.73152) (xy 216.845805 144.73152) (xy 216.845805 144.74525)
			(xy 215.500085 144.74525) (xy 215.500085 144.73152) (xy 215.472625 144.73152) (xy 215.472625 144.71779)
			(xy 215.445165 144.71779) (xy 215.445165 144.70406) (xy 215.431425 144.70406) (xy 215.431425 144.69033)
			(xy 215.431425 144.67659) (xy 215.417695 144.67659) (xy 215.417695 144.66286) (xy 215.417695 144.64913)
			(xy 215.417695 144.6354) (xy 215.403965 144.6354) (xy 215.403965 144.62167) (xy 215.403965 144.60794)
			(xy 215.403965 144.5942) (xy 215.403965 144.58047) (xy 215.403965 144.56674) (xy 215.403965 144.55301)
			(xy 215.403965 144.53928) (xy 215.403965 144.52555) (xy 215.403965 144.51181) (xy 215.403965 144.49808)
			(xy 215.403965 144.48435) (xy 215.403965 144.47062) (xy 215.403965 144.45689) (xy 215.403965 144.44316)
			(xy 215.403965 144.42942) (xy 215.403965 144.41569) (xy 215.403965 144.40196) (xy 215.403965 144.38823)
			(xy 215.403965 144.3745) (xy 215.403965 144.36077) (xy 215.403965 144.34703) (xy 215.403965 144.3333)
			(xy 215.403965 144.31957) (xy 215.403965 144.30584) (xy 215.403965 144.29211) (xy 215.403965 144.27837)
			(xy 215.403965 144.26464) (xy 215.403965 144.25091) (xy 215.403965 144.23718) (xy 215.403965 144.22345)
			(xy 215.403965 144.20971) (xy 215.403965 144.19598) (xy 215.403965 144.18225) (xy 215.403965 144.16852)
			(xy 215.403965 144.15479) (xy 215.403965 144.14106) (xy 215.403965 144.12732) (xy 215.403965 144.11359)
			(xy 215.403965 144.09986) (xy 215.403965 144.08613) (xy 215.403965 144.0724) (xy 215.403965 144.05867)
			(xy 215.403965 144.04493) (xy 215.403965 144.0312) (xy 215.403965 144.01747) (xy 215.403965 144.00374)
			(xy 215.403965 143.99001) (xy 215.403965 143.97628) (xy 215.403965 143.96254) (xy 215.403965 143.94881)
			(xy 215.403965 143.93508) (xy 215.403965 143.92135) (xy 215.403965 143.90762) (xy 215.403965 143.89389)
			(xy 215.403965 143.88015) (xy 215.403965 143.86642) (xy 215.403965 143.85269) (xy 215.403965 143.83896)
			(xy 215.403965 143.82523) (xy 215.403965 143.8115) (xy 215.403965 143.79776) (xy 215.403965 143.78403)
			(xy 215.403965 143.7703) (xy 215.403965 143.75657) (xy 215.403965 143.74284) (xy 215.403965 143.7291)
			(xy 215.403965 143.71537) (xy 215.403965 143.70164) (xy 215.403965 143.68791) (xy 215.403965 143.67418)
			(xy 215.403965 143.66044) (xy 215.403965 143.64671) (xy 215.403965 143.63298) (xy 215.403965 143.61925)
			(xy 215.403965 143.60552) (xy 215.403965 143.59179) (xy 215.403965 143.57805) (xy 215.403965 143.56432)
			(xy 215.403965 143.55059) (xy 215.403965 143.53686) (xy 215.403965 143.52313) (xy 215.417695 143.52313)
			(xy 215.417695 143.5094) (xy 215.403965 143.5094) (xy 215.403965 143.49566) (xy 215.403965 143.48193)
			(xy 215.403965 143.4682) (xy 215.403965 143.45447) (xy 215.403965 143.44074) (xy 215.403965 143.42701)
			(xy 215.403965 143.41327) (xy 215.403965 143.39954) (xy 215.403965 143.38581) (xy 215.390235 143.38581)
			(xy 215.390235 143.37208) (xy 215.390235 143.35835) (xy 215.376505 143.35835) (xy 215.376505 143.34462)
			(xy 215.376505 143.33088) (xy 215.362775 143.33088) (xy 215.362775 143.31715) (xy 215.362775 143.30342)
			(xy 215.349035 143.30342) (xy 215.349035 143.28969) (xy 215.335305 143.28969) (xy 215.335305 143.27596)
			(xy 215.321575 143.27596) (xy 215.321575 143.26223) (xy 215.307845 143.26223) (xy 215.307845 143.24849)
			(xy 215.280385 143.24849) (xy 215.280385 143.23476) (xy 215.252915 143.23476) (xy 215.252915 143.22103)
			(xy 215.211725 143.22103) (xy 215.211725 143.2073) (xy 215.101865 143.2073) (xy 215.101865 143.22103)
			(xy 215.060675 143.22103) (xy 215.060675 143.23476) (xy 215.033215 143.23476) (xy 215.033215 143.24849)
			(xy 215.005745 143.24849) (xy 215.005745 143.26223) (xy 214.992015 143.26223) (xy 214.992015 143.27596)
			(xy 214.978285 143.27596) (xy 214.978285 143.28969) (xy 214.964555 143.28969) (xy 214.964555 143.30342)
			(xy 214.950815 143.30342) (xy 214.950815 143.31715) (xy 214.937085 143.31715) (xy 214.937085 143.33088)
			(xy 214.937085 143.34462) (xy 214.923355 143.34462) (xy 214.923355 143.35835) (xy 214.923355 143.37208)
			(xy 214.909625 143.37208) (xy 214.909625 143.38581) (xy 214.909625 143.39954) (xy 214.909625 143.41327)
			(xy 214.909625 143.42701) (xy 214.909625 143.44074) (xy 214.909625 143.45447) (xy 214.895895 143.45447)
			(xy 214.895895 143.4682) (xy 214.909625 143.4682) (xy 214.909625 143.48193) (xy 214.909625 143.49566)
			(xy 214.895895 143.49566) (xy 214.895895 143.5094) (xy 214.909625 143.5094) (xy 214.909625 143.52313)
			(xy 214.909625 143.53686) (xy 214.909625 143.55059) (xy 214.909625 143.56432) (xy 214.909625 143.57805)
			(xy 214.909625 143.59179) (xy 214.909625 143.60552) (xy 214.909625 143.61925) (xy 214.909625 143.63298)
			(xy 214.909625 143.64671) (xy 214.909625 143.66044) (xy 214.909625 143.67418) (xy 214.909625 143.68791)
			(xy 214.909625 143.70164) (xy 214.909625 143.71537) (xy 214.909625 143.7291) (xy 214.909625 143.74284)
			(xy 214.909625 143.75657) (xy 214.909625 143.7703) (xy 214.909625 143.78403) (xy 214.909625 143.79776)
			(xy 214.909625 143.8115) (xy 214.909625 143.82523) (xy 214.909625 143.83896) (xy 214.909625 143.85269)
			(xy 214.909625 143.86642) (xy 214.909625 143.88015) (xy 214.909625 143.89389) (xy 214.909625 143.90762)
			(xy 214.909625 143.92135) (xy 214.909625 143.93508) (xy 214.909625 143.94881) (xy 214.909625 143.96254)
			(xy 214.909625 143.97628) (xy 214.909625 143.99001) (xy 214.909625 144.00374) (xy 214.909625 144.01747)
			(xy 214.909625 144.0312) (xy 214.909625 144.04493) (xy 214.909625 144.05867) (xy 214.909625 144.0724)
			(xy 214.909625 144.08613) (xy 214.909625 144.09986) (xy 214.895895 144.09986) (xy 214.895895 144.11359)
			(xy 214.895895 144.12732) (xy 214.895895 144.14106) (xy 214.895895 144.15479) (xy 214.882155 144.15479)
			(xy 214.882155 144.16852) (xy 214.868425 144.16852) (xy 214.868425 144.18225) (xy 214.854695 144.18225)
			(xy 214.854695 144.19598) (xy 214.840965 144.19598) (xy 214.840965 144.20971) (xy 214.799765 144.20971)
			(xy 214.799765 144.22345) (xy 213.975865 144.22345) (xy 213.975865 144.20971) (xy 213.934665 144.20971)
			(xy 213.934665 144.19598) (xy 213.920935 144.19598) (xy 213.920935 144.18225) (xy 213.907205 144.18225)
			(xy 213.907205 144.16852) (xy 213.893475 144.16852) (xy 213.893475 144.15479) (xy 213.879745 144.15479)
			(xy 213.879745 144.14106) (xy 213.879745 144.12732) (xy 213.879745 144.11359) (xy 213.866005 144.11359)
			(xy 213.866005 144.09986) (xy 213.866005 144.08613) (xy 213.866005 144.0724) (xy 213.866005 144.05867)
			(xy 213.866005 144.04493) (xy 213.866005 144.0312) (xy 213.866005 144.01747) (xy 213.866005 144.00374)
			(xy 213.866005 143.99001) (xy 213.866005 143.97628) (xy 213.866005 143.96254) (xy 213.866005 143.94881)
			(xy 213.866005 143.93508) (xy 213.866005 143.92135) (xy 213.866005 143.90762) (xy 213.866005 143.89389)
			(xy 213.866005 143.88015) (xy 213.866005 143.86642) (xy 213.866005 143.85269) (xy 213.866005 143.83896)
			(xy 213.866005 143.82523) (xy 213.866005 143.8115) (xy 213.866005 143.79776) (xy 213.866005 143.78403)
			(xy 213.866005 143.7703) (xy 213.866005 143.75657) (xy 213.866005 143.74284) (xy 213.866005 143.7291)
			(xy 213.866005 143.71537) (xy 213.866005 143.70164) (xy 213.866005 143.68791) (xy 213.866005 143.67418)
			(xy 213.866005 143.66044) (xy 213.866005 143.64671) (xy 213.866005 143.63298) (xy 213.866005 143.61925)
			(xy 213.866005 143.60552) (xy 213.866005 143.59179) (xy 213.866005 143.57805) (xy 213.866005 143.56432)
			(xy 213.866005 143.55059) (xy 213.866005 143.53686) (xy 213.866005 143.52313) (xy 213.866005 143.5094)
			(xy 213.866005 143.49566) (xy 213.866005 143.48193) (xy 213.866005 143.4682) (xy 213.866005 143.45447)
			(xy 213.866005 143.44074) (xy 213.866005 143.42701) (xy 213.866005 143.41327) (xy 213.879745 143.41327)
			(xy 213.879745 143.39954) (xy 213.879745 143.38581) (xy 213.866005 143.38581) (xy 213.866005 143.37208)
			(xy 213.879745 143.37208) (xy 213.879745 143.35835) (xy 213.866005 143.35835) (xy 213.866005 143.34462)
			(xy 213.866005 143.33088) (xy 213.866005 143.31715) (xy 213.866005 143.30342) (xy 213.866005 143.28969)
			(xy 213.866005 143.27596) (xy 213.852275 143.27596) (xy 213.852275 143.26223) (xy 213.852275 143.24849)
			(xy 213.838545 143.24849) (xy 213.838545 143.23476) (xy 213.811085 143.23476) (xy 213.811085 143.22103)
			(xy 213.783615 143.22103) (xy 213.783615 143.2073) (xy 211.655195 143.2073) (xy 211.655195 143.22103)
			(xy 211.627735 143.22103) (xy 211.627735 143.23476) (xy 211.614005 143.23476) (xy 211.614005 143.24849)
			(xy 211.600275 143.24849) (xy 211.600275 143.26223) (xy 211.586535 143.26223) (xy 211.586535 143.27596)
			(xy 211.586535 143.28969) (xy 211.572805 143.28969) (xy 211.572805 143.30342) (xy 211.572805 143.31715)
			(xy 211.572805 143.33088) (xy 211.572805 143.34462) (xy 211.572805 143.35835) (xy 211.572805 143.37208)
			(xy 211.572805 143.38581) (xy 211.572805 143.39954) (xy 211.572805 143.41327) (xy 211.572805 143.42701)
			(xy 211.572805 143.44074) (xy 211.572805 143.45447) (xy 211.572805 143.4682) (xy 211.572805 143.48193)
			(xy 211.572805 143.49566) (xy 211.572805 143.5094) (xy 211.572805 143.52313) (xy 211.572805 143.53686)
			(xy 211.572805 143.55059) (xy 211.572805 143.56432) (xy 211.572805 143.57805) (xy 211.572805 143.59179)
			(xy 211.572805 143.60552) (xy 211.572805 143.61925) (xy 211.572805 143.63298) (xy 211.572805 143.64671)
			(xy 211.572805 143.66044) (xy 211.572805 143.67418) (xy 211.572805 143.68791) (xy 211.572805 143.70164)
			(xy 211.572805 143.71537) (xy 211.572805 143.7291) (xy 211.572805 143.74284) (xy 211.572805 143.75657)
			(xy 211.572805 143.7703) (xy 211.572805 143.78403) (xy 211.572805 143.79776) (xy 211.572805 143.8115)
			(xy 211.572805 143.82523) (xy 211.572805 143.83896) (xy 211.572805 143.85269) (xy 211.572805 143.86642)
			(xy 211.572805 143.88015) (xy 211.572805 143.89389) (xy 211.572805 143.90762) (xy 211.572805 143.92135)
			(xy 211.572805 143.93508) (xy 211.572805 143.94881) (xy 211.572805 143.96254) (xy 211.572805 143.97628)
			(xy 211.572805 143.99001) (xy 211.572805 144.00374) (xy 211.572805 144.01747) (xy 211.572805 144.0312)
			(xy 211.572805 144.04493) (xy 211.572805 144.05867) (xy 211.572805 144.0724) (xy 211.572805 144.08613)
			(xy 211.572805 144.09986) (xy 211.572805 144.11359) (xy 211.572805 144.12732) (xy 211.572805 144.14106)
			(xy 211.572805 144.15479) (xy 211.572805 144.16852) (xy 211.572805 144.18225) (xy 211.572805 144.19598)
			(xy 211.572805 144.20971) (xy 211.572805 144.22345) (xy 211.572805 144.23718) (xy 211.572805 144.25091)
			(xy 211.572805 144.26464) (xy 211.572805 144.27837) (xy 211.572805 144.29211) (xy 211.572805 144.30584)
			(xy 211.572805 144.31957) (xy 211.572805 144.3333) (xy 211.572805 144.34703) (xy 211.572805 144.36077)
			(xy 211.572805 144.3745) (xy 211.572805 144.38823) (xy 211.572805 144.40196) (xy 211.572805 144.41569)
			(xy 211.572805 144.42942) (xy 211.572805 144.44316) (xy 211.572805 144.45689) (xy 211.572805 144.47062)
			(xy 211.572805 144.48435) (xy 209.526775 144.48435) (xy 209.526775 144.47062) (xy 209.526775 144.45689)
			(xy 209.526775 144.44316) (xy 209.526775 144.42942) (xy 209.526775 144.41569) (xy 209.526775 144.40196)
			(xy 209.526775 144.38823) (xy 209.526775 144.3745) (xy 209.526775 144.36077) (xy 209.526775 144.34703)
			(xy 209.526775 144.3333) (xy 209.526775 144.31957) (xy 209.526775 144.30584) (xy 209.526775 144.29211)
			(xy 209.526775 144.27837) (xy 209.526775 144.26464) (xy 209.526775 144.25091) (xy 209.526775 144.23718)
			(xy 209.526775 144.22345) (xy 209.526775 144.20971) (xy 209.526775 144.19598) (xy 209.526775 144.18225)
			(xy 209.526775 144.16852) (xy 209.526775 144.15479) (xy 209.526775 144.14106) (xy 209.526775 144.12732)
			(xy 209.526775 144.11359) (xy 209.526775 144.09986) (xy 209.526775 144.08613) (xy 209.526775 144.0724)
			(xy 209.526775 144.05867) (xy 209.526775 144.04493) (xy 209.526775 144.0312) (xy 209.526775 144.01747)
			(xy 209.526775 144.00374) (xy 209.526775 143.99001) (xy 209.526775 143.97628) (xy 209.526775 143.96254)
			(xy 209.526775 143.94881) (xy 209.526775 143.93508) (xy 209.526775 143.92135) (xy 209.526775 143.90762)
			(xy 209.526775 143.89389) (xy 209.526775 143.88015) (xy 209.526775 143.86642) (xy 209.526775 143.85269)
			(xy 209.526775 143.83896) (xy 209.526775 143.82523) (xy 209.526775 143.8115) (xy 209.526775 143.79776)
			(xy 209.526775 143.78403) (xy 209.526775 143.7703) (xy 209.526775 143.75657) (xy 209.526775 143.74284)
			(xy 209.526775 143.7291) (xy 209.526775 143.71537) (xy 209.526775 143.70164) (xy 209.526775 143.68791)
			(xy 209.526775 143.67418) (xy 209.526775 143.66044) (xy 209.526775 143.64671) (xy 209.526775 143.63298)
			(xy 209.526775 143.61925) (xy 209.526775 143.60552) (xy 209.526775 143.59179) (xy 209.526775 143.57805)
			(xy 209.526775 143.56432) (xy 209.526775 143.55059) (xy 209.526775 143.53686) (xy 209.526775 143.52313)
			(xy 209.526775 143.5094) (xy 209.526775 143.49566) (xy 209.526775 143.48193) (xy 209.526775 143.4682)
			(xy 209.526775 143.45447) (xy 209.526775 143.44074) (xy 209.526775 143.42701) (xy 209.526775 143.41327)
			(xy 209.526775 143.39954) (xy 209.526775 143.38581) (xy 209.526775 143.37208) (xy 209.526775 143.35835)
			(xy 209.526775 143.34462) (xy 209.526775 143.33088) (xy 209.526775 143.31715) (xy 209.526775 143.30342)
			(xy 209.526775 143.28969) (xy 209.526775 143.27596) (xy 209.526775 143.26223) (xy 209.526775 143.24849)
			(xy 210.858755 143.24849) (xy 210.858755 143.23476) (xy 210.858755 143.22103) (xy 210.858755 143.2073)
			(xy 210.858755 143.19357) (xy 210.858755 143.17983) (xy 210.858755 143.1661) (xy 210.858755 143.15237)
			(xy 210.858755 143.13864) (xy 210.858755 143.12491) (xy 210.858755 143.11117) (xy 210.858755 143.09744)
			(xy 210.858755 143.08371) (xy 210.858755 143.06998) (xy 210.858755 143.05625) (xy 210.858755 143.04252)
			(xy 210.858755 143.02878) (xy 210.858755 143.01505) (xy 210.858755 143.00132) (xy 210.858755 142.98759)
			(xy 210.858755 142.97386) (xy 210.858755 142.96013) (xy 210.858755 142.94639) (xy 210.858755 142.93266)
			(xy 210.858755 142.91893) (xy 210.858755 142.9052) (xy 210.858755 142.89147) (xy 210.858755 142.87774)
			(xy 210.858755 142.864) (xy 210.858755 142.85027) (xy 210.858755 142.83654) (xy 210.858755 142.82281)
			(xy 210.858755 142.80908) (xy 210.858755 142.79535) (xy 210.858755 142.78161) (xy 210.858755 142.76788)
			(xy 210.858755 142.75415) (xy 210.858755 142.74042) (xy 210.858755 142.72669) (xy 210.858755 142.71295)
			(xy 210.858755 142.69922) (xy 210.858755 142.68549) (xy 210.858755 142.67176) (xy 210.858755 142.65803)
			(xy 210.858755 142.64429) (xy 210.858755 142.63056) (xy 210.858755 142.61683) (xy 210.858755 142.6031)
			(xy 210.858755 142.58937) (xy 210.858755 142.57564) (xy 210.858755 142.5619) (xy 210.858755 142.54817)
			(xy 210.858755 142.53444) (xy 210.858755 142.52071) (xy 210.858755 142.50698) (xy 210.858755 142.49325)
			(xy 210.858755 142.47951) (xy 210.858755 142.46578) (xy 210.858755 142.45205) (xy 210.858755 142.43832)
			(xy 210.858755 142.42459) (xy 210.858755 142.41086) (xy 210.858755 142.39712) (xy 210.858755 142.38339)
			(xy 210.858755 142.36966) (xy 210.858755 142.35593) (xy 210.858755 142.3422) (xy 210.858755 142.32847)
			(xy 210.858755 142.31473) (xy 210.858755 142.301) (xy 210.858755 142.28727) (xy 210.858755 142.27354)
			(xy 210.858755 142.25981) (xy 210.858755 142.24608) (xy 210.858755 142.23234) (xy 210.858755 142.21861)
			(xy 210.858755 142.20488) (xy 210.858755 142.19115) (xy 210.858755 142.17742) (xy 210.858755 142.16368)
			(xy 210.858755 142.14995) (xy 210.858755 142.13622) (xy 210.858755 142.12249) (xy 210.858755 142.10876)
			(xy 210.858755 142.09502) (xy 210.858755 142.08129) (xy 210.858755 142.06756) (xy 210.858755 142.05383)
			(xy 210.858755 142.0401) (xy 210.858755 142.02637) (xy 210.858755 142.01263) (xy 210.858755 141.9989)
			(xy 210.858755 141.98517) (xy 210.858755 141.97144) (xy 210.858755 141.95771) (xy 210.858755 141.94398)
			(xy 210.858755 141.93024) (xy 210.858755 141.91651) (xy 210.858755 141.90278) (xy 210.858755 141.88905)
			(xy 210.858755 141.87532) (xy 210.858755 141.86159) (xy 210.858755 141.84785) (xy 210.858755 141.83412)
			(xy 210.858755 141.82039) (xy 210.858755 141.80666) (xy 210.858755 141.79293) (xy 210.858755 141.7792)
			(xy 210.858755 141.76546) (xy 210.858755 141.75173) (xy 210.858755 141.738) (xy 209.526775 141.738)
			(xy 209.526775 141.72427) (xy 209.526775 141.71054) (xy 209.526775 141.69681) (xy 209.526775 141.68307)
			(xy 209.526775 141.66934) (xy 209.526775 141.65561) (xy 209.526775 141.64188) (xy 209.526775 141.62815)
			(xy 209.526775 141.61441) (xy 209.526775 141.60068) (xy 209.526775 141.58695) (xy 209.526775 141.57322)
			(xy 209.526775 141.55949) (xy 209.526775 141.54575) (xy 209.526775 141.53202) (xy 209.526775 141.51829)
			(xy 209.526775 141.50456) (xy 209.526775 141.49083) (xy 209.526775 141.4771) (xy 209.526775 141.46336)
			(xy 209.526775 141.44963) (xy 209.526775 141.4359) (xy 209.526775 141.42217) (xy 209.526775 141.40844)
			(xy 209.526775 141.39471) (xy 210.858755 141.39471) (xy 210.858755 141.38097) (xy 210.858755 141.36724)
			(xy 210.858755 141.35351) (xy 210.858755 141.33978) (xy 210.858755 141.32605) (xy 210.858755 141.31232)
			(xy 210.858755 141.29858) (xy 210.858755 141.28485) (xy 210.858755 141.27112) (xy 210.858755 141.25739)
			(xy 210.858755 141.24366) (xy 210.858755 141.22993) (xy 210.858755 141.21619) (xy 210.858755 141.20246)
			(xy 210.858755 141.18873) (xy 210.858755 141.175) (xy 210.858755 141.16127) (xy 210.858755 141.14754)
			(xy 210.858755 141.1338) (xy 210.858755 141.12007) (xy 210.858755 141.10634) (xy 210.858755 141.09261)
			(xy 210.858755 141.07888) (xy 210.858755 141.06514) (xy 210.858755 141.05141) (xy 210.858755 141.03768)
			(xy 210.858755 141.02395) (xy 210.858755 141.01022) (xy 210.858755 140.99648) (xy 210.858755 140.98275)
			(xy 210.858755 140.96902) (xy 210.858755 140.95529) (xy 210.858755 140.94156) (xy 210.858755 140.92783)
			(xy 210.858755 140.91409) (xy 210.858755 140.90036) (xy 210.858755 140.88663) (xy 210.858755 140.8729)
			(xy 210.858755 140.85917) (xy 210.858755 140.84544) (xy 210.858755 140.8317) (xy 210.858755 140.81797)
			(xy 210.858755 140.80424) (xy 210.858755 140.79051) (xy 210.858755 140.77678) (xy 210.858755 140.76305)
			(xy 210.858755 140.74931) (xy 210.858755 140.73558) (xy 210.858755 140.72185) (xy 210.858755 140.70812)
			(xy 210.858755 140.69439) (xy 210.858755 140.68066) (xy 210.858755 140.66693) (xy 210.858755 140.65319)
			(xy 210.858755 140.63946) (xy 210.858755 140.62573) (xy 210.858755 140.612) (xy 210.858755 140.59827)
			(xy 210.858755 140.58453) (xy 210.858755 140.5708) (xy 210.858755 140.55707) (xy 210.858755 140.54334)
			(xy 210.858755 140.5296) (xy 210.858755 140.51587) (xy 210.858755 140.50214) (xy 210.858755 140.48841)
			(xy 210.858755 140.47468) (xy 210.858755 140.46095) (xy 210.858755 140.44722) (xy 210.858755 140.43348)
			(xy 210.858755 140.41975) (xy 210.858755 140.40602) (xy 210.858755 140.39229) (xy 210.858755 140.37856)
			(xy 210.858755 140.36483) (xy 210.858755 140.35109) (xy 210.858755 140.33736) (xy 210.858755 140.32363)
			(xy 210.858755 140.3099) (xy 210.858755 140.29617) (xy 210.858755 140.28244) (xy 210.858755 140.2687)
			(xy 210.858755 140.25497) (xy 210.858755 140.24124) (xy 210.858755 140.22751) (xy 210.858755 140.21378)
			(xy 210.858755 140.20005) (xy 210.858755 140.18631) (xy 210.858755 140.17258) (xy 210.858755 140.15885)
			(xy 210.858755 140.14512) (xy 210.858755 140.13139) (xy 210.858755 140.11765) (xy 210.858755 140.10392)
			(xy 210.858755 140.09019) (xy 210.858755 140.07646) (xy 210.858755 140.06273) (xy 210.858755 140.04899)
			(xy 210.858755 140.03526) (xy 210.858755 140.02153) (xy 210.858755 140.0078) (xy 210.858755 139.99407)
			(xy 210.858755 139.98034) (xy 210.858755 139.9666) (xy 210.858755 139.95287) (xy 210.858755 139.93914)
			(xy 210.858755 139.92541) (xy 210.858755 139.91168) (xy 210.858755 139.89795) (xy 210.858755 139.88421)
			(xy 209.540505 139.88421) (xy 209.540505 139.87048) (xy 209.526775 139.87048) (xy 209.526775 139.85675)
			(xy 209.526775 139.84302) (xy 209.526775 139.82929) (xy 209.526775 139.81556) (xy 209.526775 139.80182)
			(xy 209.526775 139.78809) (xy 209.526775 139.77436) (xy 209.526775 139.76063) (xy 209.526775 139.7469)
			(xy 209.526775 139.73317) (xy 209.526775 139.71943) (xy 209.526775 139.7057) (xy 209.526775 139.69197)
			(xy 209.526775 139.67824) (xy 209.526775 139.66451) (xy 209.526775 139.65078) (xy 209.526775 139.63704)
			(xy 209.526775 139.62331) (xy 209.526775 139.60958) (xy 209.526775 139.59585) (xy 209.526775 139.58212)
			(xy 209.526775 139.56838) (xy 209.526775 139.55465) (xy 209.526775 139.54092) (xy 210.858755 139.54092)
			(xy 210.858755 139.52719) (xy 210.858755 139.51346) (xy 210.858755 139.49972) (xy 210.858755 139.48599)
			(xy 210.858755 139.47226) (xy 210.858755 139.45853) (xy 210.858755 139.4448) (xy 210.858755 139.43107)
			(xy 210.858755 139.41733) (xy 210.858755 139.4036) (xy 210.858755 139.38987) (xy 210.858755 139.37614)
			(xy 210.858755 139.36241) (xy 210.858755 139.34868) (xy 210.858755 139.33494) (xy 210.858755 139.32121)
			(xy 210.858755 139.30748) (xy 210.858755 139.29375) (xy 210.858755 139.28002) (xy 210.858755 139.26629)
			(xy 210.858755 139.25255) (xy 210.858755 139.23882) (xy 210.858755 139.22509) (xy 210.858755 139.21136)
			(xy 210.858755 139.19763) (xy 210.858755 139.1839) (xy 210.858755 139.17016) (xy 210.858755 139.15643)
			(xy 210.858755 139.1427) (xy 210.858755 139.12897) (xy 210.858755 139.11524) (xy 210.858755 139.10151)
			(xy 210.858755 139.08777) (xy 210.858755 139.07404) (xy 210.858755 139.06031) (xy 210.858755 139.04658)
			(xy 210.858755 139.03285) (xy 210.858755 139.01911) (xy 210.858755 139.00538) (xy 210.858755 138.99165)
			(xy 210.858755 138.97792) (xy 210.858755 138.96419) (xy 210.858755 138.95045) (xy 210.858755 138.93672)
			(xy 210.858755 138.92299) (xy 210.858755 138.90926) (xy 210.858755 138.89553) (xy 210.858755 138.8818)
			(xy 210.858755 138.86806) (xy 210.858755 138.85433) (xy 210.858755 138.8406) (xy 210.858755 138.82687)
			(xy 210.858755 138.81314) (xy 210.858755 138.79941) (xy 210.858755 138.78567) (xy 210.858755 138.77194)
			(xy 210.858755 138.75821) (xy 210.858755 138.74448) (xy 210.858755 138.73075) (xy 210.858755 138.71702)
			(xy 210.858755 138.70328) (xy 210.858755 138.68955) (xy 210.858755 138.67582) (xy 210.858755 138.66209)
			(xy 210.858755 138.64836) (xy 210.858755 138.63463) (xy 210.858755 138.62089) (xy 210.858755 138.60716)
			(xy 210.858755 138.59343) (xy 210.858755 138.5797) (xy 210.858755 138.56597) (xy 210.858755 138.55224)
			(xy 210.858755 138.5385) (xy 210.858755 138.52477) (xy 210.858755 138.51104) (xy 210.858755 138.49731)
			(xy 210.858755 138.48358) (xy 210.858755 138.46984) (xy 210.858755 138.45611) (xy 210.858755 138.44238)
			(xy 210.858755 138.42865) (xy 210.858755 138.41492) (xy 210.858755 138.40118) (xy 210.858755 138.38745)
			(xy 210.858755 138.37372) (xy 210.858755 138.35999) (xy 210.858755 138.34626) (xy 210.858755 138.33253)
			(xy 210.858755 138.31879) (xy 210.858755 138.30506) (xy 210.858755 138.29133) (xy 210.858755 138.2776)
			(xy 210.858755 138.26387) (xy 210.858755 138.25014) (xy 210.858755 138.2364) (xy 210.858755 138.22267)
			(xy 210.858755 138.20894) (xy 210.858755 138.19521) (xy 210.858755 138.18148) (xy 210.858755 138.16775)
			(xy 210.858755 138.15401) (xy 210.858755 138.14028) (xy 210.858755 138.12655) (xy 210.858755 138.11282)
			(xy 210.858755 138.09909) (xy 210.858755 138.08536) (xy 210.858755 138.07162) (xy 210.858755 138.05789)
			(xy 210.858755 138.04416) (xy 210.858755 138.03043) (xy 210.858755 138.0167) (xy 209.526775 138.0167)
			(xy 209.526775 138.00296) (xy 209.526775 137.98923) (xy 209.526775 137.9755) (xy 209.526775 137.96177)
			(xy 209.526775 137.94804) (xy 209.526775 137.9343) (xy 209.526775 137.92057) (xy 209.526775 137.90684)
			(xy 209.526775 137.89311) (xy 209.526775 137.87938) (xy 209.526775 137.86565) (xy 209.526775 137.85191)
			(xy 209.526775 137.83818) (xy 209.526775 137.82445) (xy 209.526775 137.81072) (xy 209.526775 137.79699)
			(xy 209.526775 137.78326) (xy 209.526775 137.76952) (xy 209.526775 137.75579) (xy 209.526775 137.74206)
			(xy 209.526775 137.72833) (xy 209.526775 137.7146) (xy 209.526775 137.70087) (xy 209.526775 137.68713)
			(xy 209.540505 137.68713) (xy 209.540505 137.6734) (xy 210.858755 137.6734) (xy 210.858755 137.65967)
			(xy 210.858755 137.64594) (xy 210.858755 137.63221) (xy 210.858755 137.61848) (xy 210.858755 137.60474)
			(xy 210.858755 137.59101) (xy 210.858755 137.57728) (xy 210.858755 137.56355) (xy 210.858755 137.54982)
			(xy 210.858755 137.53609) (xy 210.858755 137.52235) (xy 210.858755 137.50862) (xy 210.858755 137.49489)
			(xy 210.858755 137.48116) (xy 210.858755 137.46743) (xy 210.858755 137.45369) (xy 210.858755 137.43996)
			(xy 210.858755 137.42623) (xy 210.858755 137.4125) (xy 210.858755 137.39877) (xy 210.858755 137.38503)
			(xy 210.858755 137.3713) (xy 210.858755 137.35757) (xy 210.858755 137.34384) (xy 210.858755 137.33011)
			(xy 210.858755 137.31638) (xy 210.858755 137.30264) (xy 210.858755 137.28891) (xy 212.698815 137.28891)
			(xy 212.698815 137.30264) (xy 212.698815 137.31638) (xy 212.698815 137.33011) (xy 212.698815 137.34384)
			(xy 212.698815 137.35757) (xy 212.698815 137.3713) (xy 212.698815 137.38503) (xy 212.698815 137.39877)
			(xy 212.698815 137.4125) (xy 212.698815 137.42623) (xy 212.712545 137.42623) (xy 212.712545 137.43996)
			(xy 212.712545 137.45369) (xy 212.712545 137.46743) (xy 212.712545 137.48116) (xy 212.712545 137.49489)
			(xy 212.712545 137.50862) (xy 212.712545 137.52235) (xy 212.712545 137.53609) (xy 212.712545 137.54982)
			(xy 212.712545 137.56355) (xy 212.712545 137.57728) (xy 212.726275 137.57728) (xy 212.726275 137.59101)
			(xy 212.712545 137.59101) (xy 212.712545 137.60474) (xy 212.726275 137.60474) (xy 212.726275 137.61848)
			(xy 212.726275 137.63221) (xy 212.726275 137.64594) (xy 212.726275 137.65967) (xy 212.726275 137.6734)
			(xy 212.726275 137.68713) (xy 212.726275 137.70087) (xy 212.726275 137.7146) (xy 212.726275 137.72833)
			(xy 212.726275 137.74206) (xy 212.740005 137.74206) (xy 212.740005 137.75579) (xy 212.740005 137.76952)
			(xy 212.740005 137.78326) (xy 212.740005 137.79699) (xy 212.740005 137.81072) (xy 212.740005 137.82445)
			(xy 212.740005 137.83818) (xy 212.740005 137.85191) (xy 212.753735 137.85191) (xy 212.753735 137.86565)
			(xy 212.753735 137.87938) (xy 212.753735 137.89311) (xy 212.753735 137.90684) (xy 212.753735 137.92057)
			(xy 212.753735 137.9343) (xy 212.753735 137.94804) (xy 212.767465 137.94804) (xy 212.767465 137.96177)
			(xy 212.767465 137.9755) (xy 212.767465 137.98923) (xy 212.767465 138.00296) (xy 212.767465 138.0167)
			(xy 212.767465 138.03043) (xy 212.781205 138.03043) (xy 212.781205 138.04416) (xy 212.781205 138.05789)
			(xy 212.781205 138.07162) (xy 212.781205 138.08536) (xy 212.781205 138.09909) (xy 212.794935 138.09909)
			(xy 212.794935 138.11282) (xy 212.794935 138.12655) (xy 212.794935 138.14028) (xy 212.794935 138.15401)
			(xy 212.794935 138.16775) (xy 212.808665 138.16775) (xy 212.808665 138.18148) (xy 212.808665 138.19521)
			(xy 212.808665 138.20894) (xy 212.808665 138.22267) (xy 212.808665 138.2364) (xy 212.822395 138.2364)
			(xy 212.822395 138.25014) (xy 212.822395 138.26387) (xy 212.822395 138.2776) (xy 212.822395 138.29133)
			(xy 212.822395 138.30506) (xy 212.836125 138.30506) (xy 212.836125 138.31879) (xy 212.836125 138.33253)
			(xy 212.836125 138.34626) (xy 212.836125 138.35999) (xy 212.849865 138.35999) (xy 212.849865 138.37372)
			(xy 212.849865 138.38745) (xy 212.849865 138.40118) (xy 212.849865 138.41492) (xy 212.863595 138.41492)
			(xy 212.863595 138.42865) (xy 212.863595 138.44238) (xy 212.863595 138.45611) (xy 212.863595 138.46984)
			(xy 212.877325 138.46984) (xy 212.877325 138.48358) (xy 212.877325 138.49731) (xy 212.877325 138.51104)
			(xy 212.877325 138.52477) (xy 212.891055 138.52477) (xy 212.891055 138.5385) (xy 212.891055 138.55224)
			(xy 212.891055 138.56597) (xy 212.904785 138.56597) (xy 212.904785 138.5797) (xy 212.904785 138.59343)
			(xy 212.904785 138.60716) (xy 212.904785 138.62089) (xy 212.918525 138.62089) (xy 212.918525 138.63463)
			(xy 212.918525 138.64836) (xy 212.918525 138.66209) (xy 212.932255 138.66209) (xy 212.932255 138.67582)
			(xy 212.932255 138.68955) (xy 212.932255 138.70328) (xy 212.945985 138.70328) (xy 212.945985 138.71702)
			(xy 212.945985 138.73075) (xy 212.945985 138.74448) (xy 212.959715 138.74448) (xy 212.959715 138.75821)
			(xy 212.959715 138.77194) (xy 212.959715 138.78567) (xy 212.973445 138.78567) (xy 212.973445 138.79941)
			(xy 212.973445 138.81314) (xy 212.973445 138.82687) (xy 212.987175 138.82687) (xy 212.987175 138.8406)
			(xy 212.987175 138.85433) (xy 212.987175 138.86806) (xy 213.000915 138.86806) (xy 213.000915 138.8818)
			(xy 213.000915 138.89553) (xy 213.000915 138.90926) (xy 213.014645 138.90926) (xy 213.014645 138.92299)
			(xy 213.014645 138.93672) (xy 213.014645 138.95045) (xy 213.028375 138.95045) (xy 213.028375 138.96419)
			(xy 213.028375 138.97792) (xy 213.028375 138.99165) (xy 213.042105 138.99165) (xy 213.042105 139.00538)
			(xy 213.042105 139.01911) (xy 213.055835 139.01911) (xy 213.055835 139.03285) (xy 213.055835 139.04658)
			(xy 213.055835 139.06031) (xy 213.069565 139.06031) (xy 213.069565 139.07404) (xy 213.069565 139.08777)
			(xy 213.083305 139.08777) (xy 213.083305 139.10151) (xy 213.083305 139.11524) (xy 213.083305 139.12897)
			(xy 213.097035 139.12897) (xy 213.097035 139.1427) (xy 213.097035 139.15643) (xy 213.110765 139.15643)
			(xy 213.110765 139.17016) (xy 213.110765 139.1839) (xy 213.110765 139.19763) (xy 213.124495 139.19763)
			(xy 213.124495 139.21136) (xy 213.124495 139.22509) (xy 213.138225 139.22509) (xy 213.138225 139.23882)
			(xy 213.138225 139.25255) (xy 213.151955 139.25255) (xy 213.151955 139.26629) (xy 213.151955 139.28002)
			(xy 213.151955 139.29375) (xy 213.165695 139.29375) (xy 213.165695 139.30748) (xy 213.165695 139.32121)
			(xy 213.179425 139.32121) (xy 213.179425 139.33494) (xy 213.179425 139.34868) (xy 213.193155 139.34868)
			(xy 213.193155 139.36241) (xy 213.193155 139.37614) (xy 213.206885 139.37614) (xy 213.206885 139.38987)
			(xy 213.206885 139.4036) (xy 213.220615 139.4036) (xy 213.220615 139.41733) (xy 213.220615 139.43107)
			(xy 213.234345 139.43107) (xy 213.234345 139.4448) (xy 213.234345 139.45853) (xy 213.248085 139.45853)
			(xy 213.248085 139.47226) (xy 213.248085 139.48599) (xy 213.261815 139.48599) (xy 213.261815 139.49972)
			(xy 213.261815 139.51346) (xy 213.275545 139.51346) (xy 213.275545 139.52719) (xy 213.275545 139.54092)
			(xy 213.289275 139.54092) (xy 213.289275 139.55465) (xy 213.289275 139.56838) (xy 213.303005 139.56838)
			(xy 213.303005 139.58212) (xy 213.303005 139.59585) (xy 213.316735 139.59585) (xy 213.316735 139.60958)
			(xy 213.316735 139.62331) (xy 213.330475 139.62331) (xy 213.330475 139.63704) (xy 213.330475 139.65078)
			(xy 213.344205 139.65078) (xy 213.344205 139.66451) (xy 213.357935 139.66451) (xy 213.357935 139.67824)
			(xy 213.357935 139.69197) (xy 213.371665 139.69197) (xy 213.371665 139.7057) (xy 213.371665 139.71943)
			(xy 213.385395 139.71943) (xy 213.385395 139.73317) (xy 213.385395 139.7469) (xy 213.399135 139.7469)
			(xy 213.399135 139.76063) (xy 213.399135 139.77436) (xy 213.412865 139.77436) (xy 213.412865 139.78809)
			(xy 213.426595 139.78809) (xy 213.426595 139.80182) (xy 213.426595 139.81556) (xy 213.440325 139.81556)
			(xy 213.440325 139.82929) (xy 213.440325 139.84302) (xy 213.454055 139.84302) (xy 213.454055 139.85675)
			(xy 213.454055 139.87048) (xy 213.467795 139.87048) (xy 213.467795 139.88421) (xy 213.481525 139.88421)
			(xy 213.481525 139.89795) (xy 213.481525 139.91168) (xy 213.495255 139.91168) (xy 213.495255 139.92541)
			(xy 213.508985 139.92541) (xy 213.508985 139.93914) (xy 213.508985 139.95287) (xy 213.522715 139.95287)
			(xy 213.522715 139.9666) (xy 213.522715 139.98034) (xy 213.536445 139.98034) (xy 213.536445 139.99407)
			(xy 213.550185 139.99407) (xy 213.550185 140.0078) (xy 213.550185 140.02153) (xy 213.563915 140.02153)
			(xy 213.563915 140.03526) (xy 213.577645 140.03526) (xy 213.577645 140.04899) (xy 213.577645 140.06273)
			(xy 213.591375 140.06273) (xy 213.591375 140.07646) (xy 213.605105 140.07646) (xy 213.605105 140.09019)
			(xy 213.605105 140.10392) (xy 213.618835 140.10392) (xy 213.618835 140.11765) (xy 213.632575 140.11765)
			(xy 213.632575 140.13139) (xy 213.632575 140.14512) (xy 213.646305 140.14512) (xy 213.646305 140.15885)
			(xy 213.660035 140.15885) (xy 213.660035 140.17258) (xy 213.673765 140.17258) (xy 213.673765 140.18631)
			(xy 213.673765 140.20005) (xy 213.687495 140.20005) (xy 213.687495 140.21378) (xy 213.701225 140.21378)
			(xy 213.701225 140.22751) (xy 213.701225 140.24124) (xy 213.714965 140.24124) (xy 213.714965 140.25497)
			(xy 213.728695 140.25497) (xy 213.728695 140.2687) (xy 213.742425 140.2687) (xy 213.742425 140.28244)
			(xy 213.742425 140.29617) (xy 213.756155 140.29617) (xy 213.756155 140.3099) (xy 213.769885 140.3099)
			(xy 213.769885 140.32363) (xy 213.783615 140.32363) (xy 213.783615 140.33736) (xy 213.783615 140.35109)
			(xy 213.797355 140.35109) (xy 213.797355 140.36483) (xy 213.811085 140.36483) (xy 213.811085 140.37856)
			(xy 213.824815 140.37856) (xy 213.824815 140.39229) (xy 213.838545 140.39229) (xy 213.838545 140.40602)
			(xy 213.838545 140.41975) (xy 213.852275 140.41975) (xy 213.852275 140.43348) (xy 213.866005 140.43348)
			(xy 213.866005 140.44722) (xy 213.879745 140.44722) (xy 213.879745 140.46095) (xy 213.893475 140.46095)
			(xy 213.893475 140.47468) (xy 213.893475 140.48841) (xy 213.907205 140.48841) (xy 213.907205 140.50214)
			(xy 213.920935 140.50214) (xy 213.920935 140.51587) (xy 213.934665 140.51587) (xy 213.934665 140.5296)
			(xy 213.948405 140.5296) (xy 213.948405 140.54334) (xy 213.948405 140.55707) (xy 213.962135 140.55707)
			(xy 213.962135 140.5708) (xy 213.975865 140.5708) (xy 213.975865 140.58453) (xy 213.989595 140.58453)
			(xy 213.989595 140.59827) (xy 214.003325 140.59827) (xy 214.003325 140.612) (xy 214.017065 140.612)
			(xy 214.017065 140.62573) (xy 214.030795 140.62573) (xy 214.030795 140.63946) (xy 214.044525 140.63946)
			(xy 214.044525 140.65319) (xy 214.044525 140.66693) (xy 214.058255 140.66693) (xy 214.058255 140.68066)
			(xy 214.071985 140.68066) (xy 214.071985 140.69439) (xy 214.085715 140.69439) (xy 214.085715 140.70812)
			(xy 214.099455 140.70812) (xy 214.099455 140.72185) (xy 214.113185 140.72185) (xy 214.113185 140.73558)
			(xy 214.126915 140.73558) (xy 214.126915 140.74931) (xy 214.140645 140.74931) (xy 214.140645 140.76305)
			(xy 214.154375 140.76305) (xy 214.154375 140.77678) (xy 214.168105 140.77678) (xy 214.168105 140.79051)
			(xy 214.181845 140.79051) (xy 214.181845 140.80424) (xy 214.195575 140.80424) (xy 214.195575 140.81797)
			(xy 214.209305 140.81797) (xy 214.209305 140.8317) (xy 214.223035 140.8317) (xy 214.223035 140.84544)
			(xy 214.236765 140.84544) (xy 214.236765 140.85917) (xy 214.250495 140.85917) (xy 214.250495 140.8729)
			(xy 214.264235 140.8729) (xy 214.264235 140.88663) (xy 214.277965 140.88663) (xy 214.277965 140.90036)
			(xy 214.291695 140.90036) (xy 214.291695 140.91409) (xy 214.305425 140.91409) (xy 214.305425 140.92783)
			(xy 214.319155 140.92783) (xy 214.319155 140.94156) (xy 214.332885 140.94156) (xy 214.332885 140.95529)
			(xy 214.346625 140.95529) (xy 214.346625 140.96902) (xy 214.360355 140.96902) (xy 214.360355 140.98275)
			(xy 214.374085 140.98275) (xy 214.374085 140.99648) (xy 214.387815 140.99648) (xy 214.387815 141.01022)
			(xy 214.401545 141.01022) (xy 214.401545 141.02395) (xy 214.415275 141.02395) (xy 214.415275 141.03768)
			(xy 214.429015 141.03768) (xy 214.429015 141.05141) (xy 214.442745 141.05141) (xy 214.442745 141.06514)
			(xy 214.456475 141.06514) (xy 214.456475 141.07888) (xy 214.483935 141.07888) (xy 214.483935 141.09261)
			(xy 214.497675 141.09261) (xy 214.497675 141.10634) (xy 214.511405 141.10634) (xy 214.511405 141.12007)
			(xy 214.525135 141.12007) (xy 214.525135 141.1338) (xy 214.538865 141.1338) (xy 214.538865 141.14754)
			(xy 214.552595 141.14754) (xy 214.552595 141.16127) (xy 214.566335 141.16127) (xy 214.566335 141.175)
			(xy 214.593795 141.175) (xy 214.593795 141.18873) (xy 214.607525 141.18873) (xy 214.607525 141.20246)
			(xy 214.621255 141.20246) (xy 214.621255 141.21619) (xy 214.634985 141.21619) (xy 214.634985 141.22993)
			(xy 214.648725 141.22993) (xy 214.648725 141.24366) (xy 214.676185 141.24366) (xy 214.676185 141.25739)
			(xy 214.689915 141.25739) (xy 214.689915 141.27112) (xy 214.703645 141.27112) (xy 214.703645 141.28485)
			(xy 214.717375 141.28485) (xy 214.717375 141.29858) (xy 214.744845 141.29858) (xy 214.744845 141.31232)
			(xy 214.758575 141.31232) (xy 214.758575 141.32605) (xy 214.772305 141.32605) (xy 214.772305 141.33978)
			(xy 214.799765 141.33978) (xy 214.799765 141.35351) (xy 214.813505 141.35351) (xy 214.813505 141.36724)
			(xy 214.827235 141.36724) (xy 214.827235 141.38097) (xy 214.854695 141.38097) (xy 214.854695 141.39471)
			(xy 214.868425 141.39471) (xy 214.868425 141.40844) (xy 214.882155 141.40844) (xy 214.882155 141.42217)
			(xy 214.909625 141.42217) (xy 214.909625 141.4359) (xy 214.923355 141.4359) (xy 214.923355 141.44963)
			(xy 214.950815 141.44963) (xy 214.950815 141.46336) (xy 214.964555 141.46336) (xy 214.964555 141.4771)
			(xy 214.978285 141.4771) (xy 214.978285 141.49083) (xy 215.005745 141.49083) (xy 215.005745 141.50456)
			(xy 215.019475 141.50456) (xy 215.019475 141.51829) (xy 215.046945 141.51829) (xy 215.046945 141.53202)
			(xy 215.060675 141.53202) (xy 215.060675 141.54575) (xy 215.088135 141.54575) (xy 215.088135 141.55949)
			(xy 215.101865 141.55949) (xy 215.101865 141.57322) (xy 215.129335 141.57322) (xy 215.129335 141.58695)
			(xy 215.143065 141.58695) (xy 215.143065 141.60068) (xy 215.170525 141.60068) (xy 215.170525 141.61441)
			(xy 215.197995 141.61441) (xy 215.197995 141.62815) (xy 215.211725 141.62815) (xy 215.211725 141.64188)
			(xy 215.239185 141.64188) (xy 215.239185 141.65561) (xy 215.252915 141.65561) (xy 215.252915 141.66934)
			(xy 215.280385 141.66934) (xy 215.280385 141.68307) (xy 215.307845 141.68307) (xy 215.307845 141.69681)
			(xy 215.321575 141.69681) (xy 215.321575 141.71054) (xy 215.349035 141.71054) (xy 215.349035 141.72427)
			(xy 215.376505 141.72427) (xy 215.376505 141.738) (xy 215.403965 141.738) (xy 215.403965 141.75173)
			(xy 215.417695 141.75173) (xy 215.417695 141.76546) (xy 215.445165 141.76546) (xy 215.445165 141.7792)
			(xy 215.472625 141.7792) (xy 215.472625 141.79293) (xy 215.500085 141.79293) (xy 215.500085 141.80666)
			(xy 215.527555 141.80666) (xy 215.527555 141.82039) (xy 215.555015 141.82039) (xy 215.555015 141.83412)
			(xy 215.582485 141.83412) (xy 215.582485 141.84785) (xy 215.609945 141.84785) (xy 215.609945 141.86159)
			(xy 215.637405 141.86159) (xy 215.637405 141.87532) (xy 215.664875 141.87532) (xy 215.664875 141.88905)
			(xy 215.692335 141.88905) (xy 215.692335 141.90278) (xy 215.719795 141.90278) (xy 215.719795 141.91651)
			(xy 215.747265 141.91651) (xy 215.747265 141.93024) (xy 215.774725 141.93024) (xy 215.774725 141.94398)
			(xy 215.802185 141.94398) (xy 215.802185 141.95771) (xy 215.829655 141.95771) (xy 215.829655 141.97144)
			(xy 215.870845 141.97144) (xy 215.870845 141.98517) (xy 215.898305 141.98517) (xy 215.898305 141.9989)
			(xy 215.925775 141.9989) (xy 215.925775 142.01263) (xy 215.966965 142.01263) (xy 215.966965 142.02637)
			(xy 215.994435 142.02637) (xy 215.994435 142.0401) (xy 216.035625 142.0401) (xy 216.035625 142.05383)
			(xy 216.063095 142.05383) (xy 216.063095 142.06756) (xy 216.104285 142.06756) (xy 216.104285 142.08129)
			(xy 216.131755 142.08129) (xy 216.131755 142.09502) (xy 216.172945 142.09502) (xy 216.172945 142.10876)
			(xy 216.214145 142.10876) (xy 216.214145 142.12249) (xy 216.255335 142.12249) (xy 216.255335 142.13622)
			(xy 216.282795 142.13622) (xy 216.282795 142.14995) (xy 216.323995 142.14995) (xy 216.323995 142.16368)
			(xy 216.365185 142.16368) (xy 216.365185 142.17742) (xy 216.420115 142.17742) (xy 216.420115 142.19115)
			(xy 216.461315 142.19115) (xy 216.461315 142.20488) (xy 216.502505 142.20488) (xy 216.502505 142.21861)
			(xy 216.557435 142.21861) (xy 216.557435 142.23234) (xy 216.598625 142.23234) (xy 216.598625 142.24608)
			(xy 216.653555 142.24608) (xy 216.653555 142.25981) (xy 216.708485 142.25981) (xy 216.708485 142.27354)
			(xy 216.763415 142.27354) (xy 216.763415 142.28727) (xy 216.818335 142.28727) (xy 216.818335 142.301)
			(xy 216.886995 142.301) (xy 216.886995 142.31473) (xy 216.941925 142.31473) (xy 216.941925 142.32847)
			(xy 217.010585 142.32847) (xy 217.010585 142.3422) (xy 217.092975 142.3422) (xy 217.092975 142.35593)
			(xy 217.175365 142.35593) (xy 217.175365 142.36966) (xy 217.271485 142.36966) (xy 217.271485 142.38339)
			(xy 217.367605 142.38339) (xy 217.367605 142.39712) (xy 217.504925 142.39712) (xy 217.504925 142.41086)
			(xy 217.669705 142.41086) (xy 217.669705 142.42459) (xy 218.328835 142.42459) (xy 218.328835 142.41086)
			(xy 218.507345 142.41086) (xy 218.507345 142.39712) (xy 218.630925 142.39712) (xy 218.630925 142.38339)
			(xy 218.740785 142.38339) (xy 218.740785 142.36966) (xy 218.836905 142.36966) (xy 218.836905 142.35593)
			(xy 218.919295 142.35593) (xy 218.919295 142.3422) (xy 218.987955 142.3422) (xy 218.987955 142.32847)
			(xy 219.070345 142.32847) (xy 219.070345 142.31473) (xy 219.125265 142.31473) (xy 219.125265 142.301)
			(xy 219.180195 142.301) (xy 219.180195 142.28727) (xy 219.248855 142.28727) (xy 219.248855 142.27354)
			(xy 219.303785 142.27354) (xy 219.303785 142.25981) (xy 219.358715 142.25981) (xy 219.358715 142.24608)
			(xy 219.413635 142.24608) (xy 219.413635 142.23234) (xy 219.454835 142.23234) (xy 219.454835 142.21861)
			(xy 219.509755 142.21861) (xy 219.509755 142.20488) (xy 219.550955 142.20488) (xy 219.550955 142.19115)
			(xy 219.592145 142.19115) (xy 219.592145 142.17742) (xy 219.633345 142.17742) (xy 219.633345 142.16368)
			(xy 219.674545 142.16368) (xy 219.674545 142.14995) (xy 219.715735 142.14995) (xy 219.715735 142.13622)
			(xy 219.756935 142.13622) (xy 219.756935 142.12249) (xy 219.798125 142.12249) (xy 219.798125 142.10876)
			(xy 219.839325 142.10876) (xy 219.839325 142.09502) (xy 219.880515 142.09502) (xy 219.880515 142.08129)
			(xy 219.907985 142.08129) (xy 219.907985 142.06756) (xy 219.949175 142.06756) (xy 219.949175 142.05383)
			(xy 219.976635 142.05383) (xy 219.976635 142.0401) (xy 220.017835 142.0401) (xy 220.017835 142.02637)
			(xy 220.045295 142.02637) (xy 220.045295 142.01263) (xy 220.086495 142.01263) (xy 220.086495 141.9989)
			(xy 220.113955 141.9989) (xy 220.113955 141.98517) (xy 220.141415 141.98517) (xy 220.141415 141.97144)
			(xy 220.182615 141.97144) (xy 220.182615 141.95771) (xy 220.210075 141.95771) (xy 220.210075 141.94398)
			(xy 220.237545 141.94398) (xy 220.237545 141.93024) (xy 220.265005 141.93024) (xy 220.265005 141.91651)
			(xy 220.292475 141.91651) (xy 220.292475 141.90278) (xy 220.319935 141.90278) (xy 220.319935 141.88905)
			(xy 220.347395 141.88905) (xy 220.347395 141.87532) (xy 220.374865 141.87532) (xy 220.374865 141.86159)
			(xy 220.402325 141.86159) (xy 220.402325 141.84785) (xy 220.429785 141.84785) (xy 220.429785 141.83412)
			(xy 220.457255 141.83412) (xy 220.457255 141.82039) (xy 220.484715 141.82039) (xy 220.484715 141.80666)
			(xy 220.512175 141.80666) (xy 220.512175 141.79293) (xy 220.539645 141.79293) (xy 220.539645 141.7792)
			(xy 220.567105 141.7792) (xy 220.567105 141.76546) (xy 220.580835 141.76546) (xy 220.580835 141.75173)
			(xy 220.608295 141.75173) (xy 220.608295 141.738) (xy 220.635765 141.738) (xy 220.635765 141.72427)
			(xy 220.663225 141.72427) (xy 220.663225 141.71054) (xy 220.676955 141.71054) (xy 220.676955 141.69681)
			(xy 220.704425 141.69681) (xy 220.704425 141.68307) (xy 220.731885 141.68307) (xy 220.731885 141.66934)
			(xy 220.745615 141.66934) (xy 220.745615 141.65561) (xy 220.773085 141.65561) (xy 220.773085 141.64188)
			(xy 220.800545 141.64188) (xy 220.800545 141.62815) (xy 220.814275 141.62815) (xy 220.814275 141.61441)
			(xy 220.841745 141.61441) (xy 220.841745 141.60068) (xy 220.855475 141.60068) (xy 220.855475 141.58695)
			(xy 220.882935 141.58695) (xy 220.882935 141.57322) (xy 220.910395 141.57322) (xy 220.910395 141.55949)
			(xy 220.924135 141.55949) (xy 220.924135 141.54575) (xy 220.951595 141.54575) (xy 220.951595 141.53202)
			(xy 220.965325 141.53202) (xy 220.965325 141.51829) (xy 220.992785 141.51829) (xy 220.992785 141.50456)
			(xy 221.006525 141.50456) (xy 221.006525 141.49083) (xy 221.020255 141.49083) (xy 221.020255 141.4771)
			(xy 221.047715 141.4771) (xy 221.047715 141.46336) (xy 221.061445 141.46336) (xy 221.061445 141.44963)
			(xy 221.088915 141.44963) (xy 221.088915 141.4359) (xy 221.102645 141.4359) (xy 221.102645 141.42217)
			(xy 221.130105 141.42217) (xy 221.130105 141.40844) (xy 221.143835 141.40844) (xy 221.143835 141.39471)
			(xy 221.157565 141.39471) (xy 221.157565 141.38097) (xy 221.185035 141.38097) (xy 221.185035 141.36724)
			(xy 221.198765 141.36724) (xy 221.198765 141.35351) (xy 221.212495 141.35351) (xy 221.212495 141.33978)
			(xy 221.239955 141.33978) (xy 221.239955 141.32605) (xy 221.253695 141.32605) (xy 221.253695 141.31232)
			(xy 221.267425 141.31232) (xy 221.267425 141.29858) (xy 221.281155 141.29858) (xy 221.281155 141.28485)
			(xy 221.308615 141.28485) (xy 221.308615 141.27112) (xy 221.322355 141.27112) (xy 221.322355 141.25739)
			(xy 221.336085 141.25739) (xy 221.336085 141.24366) (xy 221.349815 141.24366) (xy 221.349815 141.22993)
			(xy 221.377275 141.22993) (xy 221.377275 141.21619) (xy 221.391015 141.21619) (xy 221.391015 141.20246)
			(xy 221.404745 141.20246) (xy 221.404745 141.18873) (xy 221.418475 141.18873) (xy 221.418475 141.175)
			(xy 221.432205 141.175) (xy 221.432205 141.16127) (xy 221.459665 141.16127) (xy 221.459665 141.14754)
			(xy 221.473405 141.14754) (xy 221.473405 141.1338) (xy 221.487135 141.1338) (xy 221.487135 141.12007)
			(xy 221.500865 141.12007) (xy 221.500865 141.10634) (xy 221.514595 141.10634) (xy 221.514595 141.09261)
			(xy 221.528325 141.09261) (xy 221.528325 141.07888) (xy 221.542055 141.07888) (xy 221.542055 141.06514)
			(xy 221.569525 141.06514) (xy 221.569525 141.05141) (xy 221.583255 141.05141) (xy 221.583255 141.03768)
			(xy 221.596985 141.03768) (xy 221.596985 141.02395) (xy 221.610715 141.02395) (xy 221.610715 141.01022)
			(xy 221.624445 141.01022) (xy 221.624445 140.99648) (xy 221.638185 140.99648) (xy 221.638185 140.98275)
			(xy 221.651915 140.98275) (xy 221.651915 140.96902) (xy 221.665645 140.96902) (xy 221.665645 140.95529)
			(xy 221.679375 140.95529) (xy 221.679375 140.94156) (xy 221.693105 140.94156) (xy 221.693105 140.92783)
			(xy 221.706835 140.92783) (xy 221.706835 140.91409) (xy 221.720575 140.91409) (xy 221.720575 140.90036)
			(xy 221.734305 140.90036) (xy 221.734305 140.88663) (xy 221.748035 140.88663) (xy 221.748035 140.8729)
			(xy 221.761765 140.8729) (xy 221.761765 140.85917) (xy 221.775495 140.85917) (xy 221.775495 140.84544)
			(xy 221.789235 140.84544) (xy 221.789235 140.8317) (xy 221.802965 140.8317) (xy 221.802965 140.81797)
			(xy 221.816695 140.81797) (xy 221.816695 140.80424) (xy 221.830425 140.80424) (xy 221.830425 140.79051)
			(xy 221.844155 140.79051) (xy 221.844155 140.77678) (xy 221.857895 140.77678) (xy 221.857895 140.76305)
			(xy 221.871625 140.76305) (xy 221.871625 140.74931) (xy 221.885355 140.74931) (xy 221.885355 140.73558)
			(xy 221.899085 140.73558) (xy 221.899085 140.72185) (xy 221.912815 140.72185) (xy 221.912815 140.70812)
			(xy 221.926545 140.70812) (xy 221.926545 140.69439) (xy 221.940285 140.69439) (xy 221.940285 140.68066)
			(xy 221.954015 140.68066) (xy 221.954015 140.66693) (xy 221.954015 140.65319) (xy 221.967745 140.65319)
			(xy 221.967745 140.63946) (xy 221.981475 140.63946) (xy 221.981475 140.62573) (xy 221.995205 140.62573)
			(xy 221.995205 140.612) (xy 222.008935 140.612) (xy 222.008935 140.59827) (xy 222.022675 140.59827)
			(xy 222.022675 140.58453) (xy 222.036405 140.58453) (xy 222.036405 140.5708) (xy 222.050135 140.5708)
			(xy 222.050135 140.55707) (xy 222.050135 140.54334) (xy 222.063865 140.54334) (xy 222.063865 140.5296)
			(xy 221.844155 140.5296) (xy 221.844155 140.54334) (xy 221.830425 140.54334) (xy 221.830425 140.55707)
			(xy 221.816695 140.55707) (xy 221.816695 140.5708) (xy 221.816695 140.58453) (xy 221.802965 140.58453)
			(xy 221.802965 140.59827) (xy 221.789235 140.59827) (xy 221.789235 140.612) (xy 221.775495 140.612)
			(xy 221.775495 140.62573) (xy 221.761765 140.62573) (xy 221.761765 140.63946) (xy 221.748035 140.63946)
			(xy 221.748035 140.65319) (xy 221.734305 140.65319) (xy 221.734305 140.66693) (xy 221.720575 140.66693)
			(xy 221.720575 140.68066) (xy 221.706835 140.68066) (xy 221.706835 140.69439) (xy 221.693105 140.69439)
			(xy 221.693105 140.70812) (xy 221.679375 140.70812) (xy 221.679375 140.72185) (xy 221.665645 140.72185)
			(xy 221.665645 140.73558) (xy 221.651915 140.73558) (xy 221.651915 140.74931) (xy 221.638185 140.74931)
			(xy 221.638185 140.76305) (xy 221.624445 140.76305) (xy 221.624445 140.77678) (xy 221.610715 140.77678)
			(xy 221.610715 140.79051) (xy 221.596985 140.79051) (xy 221.596985 140.80424) (xy 221.583255 140.80424)
			(xy 221.583255 140.81797) (xy 221.569525 140.81797) (xy 221.569525 140.8317) (xy 221.555795 140.8317)
			(xy 221.555795 140.84544) (xy 221.542055 140.84544) (xy 221.542055 140.85917) (xy 221.528325 140.85917)
			(xy 221.528325 140.8729) (xy 221.514595 140.8729) (xy 221.514595 140.88663) (xy 221.500865 140.88663)
			(xy 221.500865 140.90036) (xy 221.487135 140.90036) (xy 221.487135 140.91409) (xy 221.473405 140.91409)
			(xy 221.473405 140.92783) (xy 221.445935 140.92783) (xy 221.445935 140.94156) (xy 221.432205 140.94156)
			(xy 221.432205 140.95529) (xy 221.418475 140.95529) (xy 221.418475 140.96902) (xy 221.404745 140.96902)
			(xy 221.404745 140.98275) (xy 221.391015 140.98275) (xy 221.391015 140.99648) (xy 221.377275 140.99648)
			(xy 221.377275 141.01022) (xy 221.363545 141.01022) (xy 221.363545 141.02395) (xy 221.336085 141.02395)
			(xy 221.336085 141.03768) (xy 221.322355 141.03768) (xy 221.322355 141.05141) (xy 221.308615 141.05141)
			(xy 221.308615 141.06514) (xy 221.294885 141.06514) (xy 221.294885 141.07888) (xy 221.281155 141.07888)
			(xy 221.281155 141.09261) (xy 221.253695 141.09261) (xy 221.253695 141.10634) (xy 221.239955 141.10634)
			(xy 221.239955 141.12007) (xy 221.226225 141.12007) (xy 221.226225 141.1338) (xy 221.212495 141.1338)
			(xy 221.212495 141.14754) (xy 221.185035 141.14754) (xy 221.185035 141.16127) (xy 221.171305 141.16127)
			(xy 221.171305 141.175) (xy 221.157565 141.175) (xy 221.157565 141.18873) (xy 221.143835 141.18873)
			(xy 221.143835 141.20246) (xy 221.116375 141.20246) (xy 221.116375 141.21619) (xy 221.102645 141.21619)
			(xy 221.102645 141.22993) (xy 221.088915 141.22993) (xy 221.088915 141.24366) (xy 221.061445 141.24366)
			(xy 221.061445 141.25739) (xy 221.047715 141.25739) (xy 221.047715 141.27112) (xy 221.033985 141.27112)
			(xy 221.033985 141.28485) (xy 221.006525 141.28485) (xy 221.006525 141.29858) (xy 220.992785 141.29858)
			(xy 220.992785 141.31232) (xy 220.965325 141.31232) (xy 220.965325 141.32605) (xy 220.951595 141.32605)
			(xy 220.951595 141.33978) (xy 220.937865 141.33978) (xy 220.937865 141.35351) (xy 220.910395 141.35351)
			(xy 220.910395 141.36724) (xy 220.896665 141.36724) (xy 220.896665 141.38097) (xy 220.869205 141.38097)
			(xy 220.869205 141.39471) (xy 220.855475 141.39471) (xy 220.855475 141.40844) (xy 220.828005 141.40844)
			(xy 220.828005 141.42217) (xy 220.814275 141.42217) (xy 220.814275 141.4359) (xy 220.786815 141.4359)
			(xy 220.786815 141.44963) (xy 220.773085 141.44963) (xy 220.773085 141.46336) (xy 220.745615 141.46336)
			(xy 220.745615 141.4771) (xy 220.718155 141.4771) (xy 220.718155 141.49083) (xy 220.704425 141.49083)
			(xy 220.704425 141.50456) (xy 220.676955 141.50456) (xy 220.676955 141.51829) (xy 220.649495 141.51829)
			(xy 220.649495 141.53202) (xy 220.635765 141.53202) (xy 220.635765 141.54575) (xy 220.608295 141.54575)
			(xy 220.608295 141.55949) (xy 220.580835 141.55949) (xy 220.580835 141.57322) (xy 220.567105 141.57322)
			(xy 220.567105 141.58695) (xy 220.539645 141.58695) (xy 220.539645 141.60068) (xy 220.512175 141.60068)
			(xy 220.512175 141.61441) (xy 220.484715 141.61441) (xy 220.484715 141.62815) (xy 220.470985 141.62815)
			(xy 220.470985 141.64188) (xy 220.443515 141.64188) (xy 220.443515 141.65561) (xy 220.416055 141.65561)
			(xy 220.416055 141.66934) (xy 220.388595 141.66934) (xy 220.388595 141.68307) (xy 220.361125 141.68307)
			(xy 220.361125 141.69681) (xy 220.333665 141.69681) (xy 220.333665 141.71054) (xy 220.306205 141.71054)
			(xy 220.306205 141.72427) (xy 220.278735 141.72427) (xy 220.278735 141.738) (xy 220.251275 141.738)
			(xy 220.251275 141.75173) (xy 220.223815 141.75173) (xy 220.223815 141.76546) (xy 220.196345 141.76546)
			(xy 220.196345 141.7792) (xy 220.168885 141.7792) (xy 220.168885 141.79293) (xy 220.141415 141.79293)
			(xy 220.141415 141.80666) (xy 220.113955 141.80666) (xy 220.113955 141.82039) (xy 220.072765 141.82039)
			(xy 220.072765 141.83412) (xy 220.045295 141.83412) (xy 220.045295 141.84785) (xy 220.004105 141.84785)
			(xy 220.004105 141.86159) (xy 219.976635 141.86159) (xy 219.976635 141.87532) (xy 219.949175 141.87532)
			(xy 219.949175 141.88905) (xy 219.907985 141.88905) (xy 219.907985 141.90278) (xy 219.880515 141.90278)
			(xy 219.880515 141.91651) (xy 219.839325 141.91651) (xy 219.839325 141.93024) (xy 219.798125 141.93024)
			(xy 219.798125 141.94398) (xy 219.770665 141.94398) (xy 219.770665 141.95771) (xy 219.729465 141.95771)
			(xy 219.729465 141.97144) (xy 219.688275 141.97144) (xy 219.688275 141.98517) (xy 219.647075 141.98517)
			(xy 219.647075 141.9989) (xy 219.605885 141.9989) (xy 219.605885 142.01263) (xy 219.564685 142.01263)
			(xy 219.564685 142.02637) (xy 219.523495 142.02637) (xy 219.523495 142.0401) (xy 219.482295 142.0401)
			(xy 219.482295 142.05383) (xy 219.427365 142.05383) (xy 219.427365 142.06756) (xy 219.386175 142.06756)
			(xy 219.386175 142.08129) (xy 219.331245 142.08129) (xy 219.331245 142.09502) (xy 219.276325 142.09502)
			(xy 219.276325 142.10876) (xy 219.221395 142.10876) (xy 219.221395 142.12249) (xy 219.166465 142.12249)
			(xy 219.166465 142.13622) (xy 219.097805 142.13622) (xy 219.097805 142.14995) (xy 219.042875 142.14995)
			(xy 219.042875 142.16368) (xy 218.974225 142.16368) (xy 218.974225 142.17742) (xy 218.891835 142.17742)
			(xy 218.891835 142.19115) (xy 218.809445 142.19115) (xy 218.809445 142.20488) (xy 218.713315 142.20488)
			(xy 218.713315 142.21861) (xy 218.630925 142.21861) (xy 218.630925 142.23234) (xy 218.466145 142.23234)
			(xy 218.466145 142.24608) (xy 218.315095 142.24608) (xy 218.315095 142.25981) (xy 218.301365 142.25981)
			(xy 218.301365 142.24608) (xy 218.273905 142.24608) (xy 218.273905 142.25981) (xy 217.738365 142.25981)
			(xy 217.738365 142.24608) (xy 217.532385 142.24608) (xy 217.532385 142.23234) (xy 217.408805 142.23234)
			(xy 217.408805 142.21861) (xy 217.298945 142.21861) (xy 217.298945 142.20488) (xy 217.202825 142.20488)
			(xy 217.202825 142.19115) (xy 217.120435 142.19115) (xy 217.120435 142.17742) (xy 217.038045 142.17742)
			(xy 217.038045 142.16368) (xy 216.969385 142.16368) (xy 216.969385 142.14995) (xy 216.900725 142.14995)
			(xy 216.900725 142.13622) (xy 216.845805 142.13622) (xy 216.845805 142.12249) (xy 216.790875 142.12249)
			(xy 216.790875 142.10876) (xy 216.735945 142.10876) (xy 216.735945 142.09502) (xy 216.681025 142.09502)
			(xy 216.681025 142.08129) (xy 216.626095 142.08129) (xy 216.626095 142.06756) (xy 216.584895 142.06756)
			(xy 216.584895 142.05383) (xy 216.529965 142.05383) (xy 216.529965 142.0401) (xy 216.488775 142.0401)
			(xy 216.488775 142.02637) (xy 216.447575 142.02637) (xy 216.447575 142.01263) (xy 216.406385 142.01263)
			(xy 216.406385 141.9989) (xy 216.365185 141.9989) (xy 216.365185 141.98517) (xy 216.323995 141.98517)
			(xy 216.323995 141.97144) (xy 216.282795 141.97144) (xy 216.282795 141.95771) (xy 216.241605 141.95771)
			(xy 216.241605 141.94398) (xy 216.200405 141.94398) (xy 216.200405 141.93024) (xy 216.172945 141.93024)
			(xy 216.172945 141.91651) (xy 216.131755 141.91651) (xy 216.131755 141.90278) (xy 216.104285 141.90278)
			(xy 216.104285 141.88905) (xy 216.063095 141.88905) (xy 216.063095 141.87532) (xy 216.035625 141.87532)
			(xy 216.035625 141.86159) (xy 215.994435 141.86159) (xy 215.994435 141.84785) (xy 215.966965 141.84785)
			(xy 215.966965 141.83412) (xy 215.939505 141.83412) (xy 215.939505 141.82039) (xy 215.912045 141.82039)
			(xy 215.912045 141.80666) (xy 215.870845 141.80666) (xy 215.870845 141.79293) (xy 215.843385 141.79293)
			(xy 215.843385 141.7792) (xy 215.815915 141.7792) (xy 215.815915 141.76546) (xy 215.788455 141.76546)
			(xy 215.788455 141.75173) (xy 215.760995 141.75173) (xy 215.760995 141.738) (xy 215.733525 141.738)
			(xy 215.733525 141.72427) (xy 215.706065 141.72427) (xy 215.706065 141.71054) (xy 215.678605 141.71054)
			(xy 215.678605 141.69681) (xy 215.651135 141.69681) (xy 215.651135 141.68307) (xy 215.623675 141.68307)
			(xy 215.623675 141.66934) (xy 215.596215 141.66934) (xy 215.596215 141.65561) (xy 215.568745 141.65561)
			(xy 215.568745 141.64188) (xy 215.541285 141.64188) (xy 215.541285 141.62815) (xy 215.527555 141.62815)
			(xy 215.527555 141.61441) (xy 215.500085 141.61441) (xy 215.500085 141.60068) (xy 215.472625 141.60068)
			(xy 215.472625 141.58695) (xy 215.445165 141.58695) (xy 215.445165 141.57322) (xy 215.417695 141.57322)
			(xy 215.417695 141.55949) (xy 215.403965 141.55949) (xy 215.403965 141.54575) (xy 215.376505 141.54575)
			(xy 215.376505 141.53202) (xy 215.349035 141.53202) (xy 215.349035 141.51829) (xy 215.335305 141.51829)
			(xy 215.335305 141.50456) (xy 215.307845 141.50456) (xy 215.307845 141.49083) (xy 215.294115 141.49083)
			(xy 215.294115 141.4771) (xy 215.266645 141.4771) (xy 215.266645 141.46336) (xy 215.239185 141.46336)
			(xy 215.239185 141.44963) (xy 215.225455 141.44963) (xy 215.225455 141.4359) (xy 215.197995 141.4359)
			(xy 215.197995 141.42217) (xy 215.184255 141.42217) (xy 215.184255 141.40844) (xy 215.156795 141.40844)
			(xy 215.156795 141.39471) (xy 215.143065 141.39471) (xy 215.143065 141.38097) (xy 215.115605 141.38097)
			(xy 215.115605 141.36724) (xy 215.101865 141.36724) (xy 215.101865 141.35351) (xy 215.074405 141.35351)
			(xy 215.074405 141.33978) (xy 215.060675 141.33978) (xy 215.060675 141.32605) (xy 215.033215 141.32605)
			(xy 215.033215 141.31232) (xy 215.019475 141.31232) (xy 215.019475 141.29858) (xy 215.005745 141.29858)
			(xy 215.005745 141.28485) (xy 214.978285 141.28485) (xy 214.978285 141.27112) (xy 214.964555 141.27112)
			(xy 214.964555 141.25739) (xy 214.950815 141.25739) (xy 214.950815 141.24366) (xy 214.923355 141.24366)
			(xy 214.923355 141.22993) (xy 214.909625 141.22993) (xy 214.909625 141.21619) (xy 214.895895 141.21619)
			(xy 214.895895 141.20246) (xy 214.868425 141.20246) (xy 214.868425 141.18873) (xy 214.854695 141.18873)
			(xy 214.854695 141.175) (xy 214.840965 141.175) (xy 214.840965 141.16127) (xy 214.813505 141.16127)
			(xy 214.813505 141.14754) (xy 214.799765 141.14754) (xy 214.799765 141.1338) (xy 214.786035 141.1338)
			(xy 214.786035 141.12007) (xy 214.772305 141.12007) (xy 214.772305 141.10634) (xy 214.744845 141.10634)
			(xy 214.744845 141.09261) (xy 214.731115 141.09261) (xy 214.731115 141.07888) (xy 214.717375 141.07888)
			(xy 214.717375 141.06514) (xy 214.703645 141.06514) (xy 214.703645 141.05141) (xy 214.689915 141.05141)
			(xy 214.689915 141.03768) (xy 214.662455 141.03768) (xy 214.662455 141.02395) (xy 214.648725 141.02395)
			(xy 214.648725 141.01022) (xy 214.634985 141.01022) (xy 214.634985 140.99648) (xy 214.621255 140.99648)
			(xy 214.621255 140.98275) (xy 214.607525 140.98275) (xy 214.607525 140.96902) (xy 214.593795 140.96902)
			(xy 214.593795 140.95529) (xy 214.580065 140.95529) (xy 214.580065 140.94156) (xy 214.552595 140.94156)
			(xy 214.552595 140.92783) (xy 214.538865 140.92783) (xy 214.538865 140.91409) (xy 214.525135 140.91409)
			(xy 214.525135 140.90036) (xy 214.511405 140.90036) (xy 214.511405 140.88663) (xy 214.497675 140.88663)
			(xy 214.497675 140.8729) (xy 214.483935 140.8729) (xy 214.483935 140.85917) (xy 214.470205 140.85917)
			(xy 214.470205 140.84544) (xy 214.456475 140.84544) (xy 214.456475 140.8317) (xy 214.442745 140.8317)
			(xy 214.442745 140.81797) (xy 214.429015 140.81797) (xy 214.429015 140.80424) (xy 214.415275 140.80424)
			(xy 214.415275 140.79051) (xy 214.401545 140.79051) (xy 214.401545 140.77678) (xy 214.387815 140.77678)
			(xy 214.387815 140.76305) (xy 214.374085 140.76305) (xy 214.374085 140.74931) (xy 214.360355 140.74931)
			(xy 214.360355 140.73558) (xy 214.346625 140.73558) (xy 214.346625 140.72185) (xy 214.332885 140.72185)
			(xy 214.332885 140.70812) (xy 214.319155 140.70812) (xy 214.319155 140.69439) (xy 214.305425 140.69439)
			(xy 214.305425 140.68066) (xy 214.291695 140.68066) (xy 214.291695 140.66693) (xy 214.277965 140.66693)
			(xy 214.277965 140.65319) (xy 214.264235 140.65319) (xy 214.264235 140.63946) (xy 214.250495 140.63946)
			(xy 214.250495 140.62573) (xy 214.236765 140.62573) (xy 214.236765 140.612) (xy 214.223035 140.612)
			(xy 214.223035 140.59827) (xy 214.209305 140.59827) (xy 214.209305 140.58453) (xy 214.195575 140.58453)
			(xy 214.195575 140.5708) (xy 214.181845 140.5708) (xy 214.181845 140.55707) (xy 214.181845 140.54334)
			(xy 214.168105 140.54334) (xy 214.168105 140.5296) (xy 214.154375 140.5296) (xy 214.154375 140.51587)
			(xy 214.140645 140.51587) (xy 214.140645 140.50214) (xy 214.126915 140.50214) (xy 214.126915 140.48841)
			(xy 214.113185 140.48841) (xy 214.113185 140.47468) (xy 214.099455 140.47468) (xy 214.099455 140.46095)
			(xy 214.085715 140.46095) (xy 214.085715 140.44722) (xy 214.085715 140.43348) (xy 214.071985 140.43348)
			(xy 214.071985 140.41975) (xy 214.058255 140.41975) (xy 214.058255 140.40602) (xy 214.044525 140.40602)
			(xy 214.044525 140.39229) (xy 214.030795 140.39229) (xy 214.030795 140.37856) (xy 214.017065 140.37856)
			(xy 214.017065 140.36483) (xy 214.017065 140.35109) (xy 214.003325 140.35109) (xy 214.003325 140.33736)
			(xy 213.989595 140.33736) (xy 213.989595 140.32363) (xy 213.975865 140.32363) (xy 213.975865 140.3099)
			(xy 213.962135 140.3099) (xy 213.962135 140.29617) (xy 213.962135 140.28244) (xy 213.948405 140.28244)
			(xy 213.948405 140.2687) (xy 213.934665 140.2687) (xy 213.934665 140.25497) (xy 213.920935 140.25497)
			(xy 213.920935 140.24124) (xy 213.920935 140.22751) (xy 213.907205 140.22751) (xy 213.907205 140.21378)
			(xy 213.893475 140.21378) (xy 213.893475 140.20005) (xy 213.879745 140.20005) (xy 213.879745 140.18631)
			(xy 213.879745 140.17258) (xy 213.866005 140.17258) (xy 213.866005 140.15885) (xy 213.852275 140.15885)
			(xy 213.852275 140.14512) (xy 213.838545 140.14512) (xy 213.838545 140.13139) (xy 213.838545 140.11765)
			(xy 213.824815 140.11765) (xy 213.824815 140.10392) (xy 213.811085 140.10392) (xy 213.811085 140.09019)
			(xy 213.797355 140.09019) (xy 213.797355 140.07646) (xy 213.797355 140.06273) (xy 213.783615 140.06273)
			(xy 213.783615 140.04899) (xy 213.769885 140.04899) (xy 213.769885 140.03526) (xy 213.769885 140.02153)
			(xy 213.756155 140.02153) (xy 213.756155 140.0078) (xy 213.742425 140.0078) (xy 213.742425 139.99407)
			(xy 213.742425 139.98034) (xy 213.728695 139.98034) (xy 213.728695 139.9666) (xy 213.714965 139.9666)
			(xy 213.714965 139.95287) (xy 213.714965 139.93914) (xy 213.701225 139.93914) (xy 213.701225 139.92541)
			(xy 213.687495 139.92541) (xy 213.687495 139.91168) (xy 213.687495 139.89795) (xy 213.673765 139.89795)
			(xy 213.673765 139.88421) (xy 213.660035 139.88421) (xy 213.660035 139.87048) (xy 213.660035 139.85675)
			(xy 213.646305 139.85675) (xy 213.646305 139.84302) (xy 213.646305 139.82929) (xy 213.632575 139.82929)
			(xy 213.632575 139.81556) (xy 213.618835 139.81556) (xy 213.618835 139.80182) (xy 213.618835 139.78809)
			(xy 213.605105 139.78809) (xy 213.605105 139.77436) (xy 213.591375 139.77436) (xy 213.591375 139.76063)
			(xy 213.591375 139.7469) (xy 213.577645 139.7469) (xy 213.577645 139.73317) (xy 213.577645 139.71943)
			(xy 213.563915 139.71943) (xy 213.563915 139.7057) (xy 213.563915 139.69197) (xy 213.550185 139.69197)
			(xy 213.550185 139.67824) (xy 213.536445 139.67824) (xy 213.536445 139.66451) (xy 213.536445 139.65078)
			(xy 213.522715 139.65078) (xy 213.522715 139.63704) (xy 213.522715 139.62331) (xy 213.508985 139.62331)
			(xy 213.508985 139.60958) (xy 213.508985 139.59585) (xy 213.495255 139.59585) (xy 213.495255 139.58212)
			(xy 213.481525 139.58212) (xy 213.481525 139.56838) (xy 213.481525 139.55465) (xy 213.467795 139.55465)
			(xy 213.467795 139.54092) (xy 213.467795 139.52719) (xy 213.454055 139.52719) (xy 213.454055 139.51346)
			(xy 213.454055 139.49972) (xy 213.440325 139.49972) (xy 213.440325 139.48599) (xy 213.440325 139.47226)
			(xy 213.426595 139.47226) (xy 213.426595 139.45853) (xy 213.426595 139.4448) (xy 213.412865 139.4448)
			(xy 213.412865 139.43107) (xy 213.412865 139.41733) (xy 213.399135 139.41733) (xy 213.399135 139.4036)
			(xy 213.399135 139.38987) (xy 213.385395 139.38987) (xy 213.385395 139.37614) (xy 213.385395 139.36241)
			(xy 213.371665 139.36241) (xy 213.371665 139.34868) (xy 213.371665 139.33494) (xy 213.357935 139.33494)
			(xy 213.357935 139.32121) (xy 213.357935 139.30748) (xy 213.344205 139.30748) (xy 213.344205 139.29375)
			(xy 213.344205 139.28002) (xy 213.330475 139.28002) (xy 213.330475 139.26629) (xy 213.330475 139.25255)
			(xy 213.316735 139.25255) (xy 213.316735 139.23882) (xy 213.316735 139.22509) (xy 213.316735 139.21136)
			(xy 213.303005 139.21136) (xy 213.303005 139.19763) (xy 213.303005 139.1839) (xy 213.289275 139.1839)
			(xy 213.289275 139.17016) (xy 213.289275 139.15643) (xy 213.275545 139.15643) (xy 213.275545 139.1427)
			(xy 213.275545 139.12897) (xy 213.275545 139.11524) (xy 213.261815 139.11524) (xy 213.261815 139.10151)
			(xy 213.261815 139.08777) (xy 213.248085 139.08777) (xy 213.248085 139.07404) (xy 213.248085 139.06031)
			(xy 213.234345 139.06031) (xy 213.234345 139.04658) (xy 213.234345 139.03285) (xy 213.234345 139.01911)
			(xy 213.220615 139.01911) (xy 213.220615 139.00538) (xy 213.220615 138.99165) (xy 213.206885 138.99165)
			(xy 213.206885 138.97792) (xy 213.206885 138.96419) (xy 213.206885 138.95045) (xy 213.193155 138.95045)
			(xy 213.193155 138.93672) (xy 213.193155 138.92299) (xy 213.193155 138.90926) (xy 213.179425 138.90926)
			(xy 213.179425 138.89553) (xy 213.179425 138.8818) (xy 213.165695 138.8818) (xy 213.165695 138.86806)
			(xy 213.165695 138.85433) (xy 213.165695 138.8406) (xy 213.151955 138.8406) (xy 213.151955 138.82687)
			(xy 213.151955 138.81314) (xy 213.151955 138.79941) (xy 213.138225 138.79941) (xy 213.138225 138.78567)
			(xy 213.138225 138.77194) (xy 213.138225 138.75821) (xy 213.124495 138.75821) (xy 213.124495 138.74448)
			(xy 213.124495 138.73075) (xy 213.124495 138.71702) (xy 213.110765 138.71702) (xy 213.110765 138.70328)
			(xy 213.110765 138.68955) (xy 213.110765 138.67582) (xy 213.097035 138.67582) (xy 213.097035 138.66209)
			(xy 213.097035 138.64836) (xy 213.097035 138.63463) (xy 213.083305 138.63463) (xy 213.083305 138.62089)
			(xy 213.083305 138.60716) (xy 213.083305 138.59343) (xy 213.069565 138.59343) (xy 213.069565 138.5797)
			(xy 213.069565 138.56597) (xy 213.069565 138.55224) (xy 213.069565 138.5385) (xy 213.055835 138.5385)
			(xy 213.055835 138.52477) (xy 213.055835 138.51104) (xy 213.055835 138.49731) (xy 213.042105 138.49731)
			(xy 213.042105 138.48358) (xy 213.042105 138.46984) (xy 213.042105 138.45611) (xy 213.042105 138.44238)
			(xy 213.028375 138.44238) (xy 213.028375 138.42865) (xy 213.028375 138.41492) (xy 213.028375 138.40118)
			(xy 213.028375 138.38745) (xy 213.014645 138.38745) (xy 213.014645 138.37372) (xy 213.014645 138.35999)
			(xy 213.014645 138.34626) (xy 213.014645 138.33253) (xy 213.000915 138.33253) (xy 213.000915 138.31879)
			(xy 213.000915 138.30506) (xy 213.000915 138.29133) (xy 213.000915 138.2776) (xy 212.987175 138.2776)
			(xy 212.987175 138.26387) (xy 212.987175 138.25014) (xy 212.987175 138.2364) (xy 212.987175 138.22267)
			(xy 212.987175 138.20894) (xy 212.973445 138.20894) (xy 212.973445 138.19521) (xy 212.973445 138.18148)
			(xy 212.973445 138.16775) (xy 212.973445 138.15401) (xy 212.973445 138.14028) (xy 212.959715 138.14028)
			(xy 212.959715 138.12655) (xy 212.959715 138.11282) (xy 212.959715 138.09909) (xy 212.959715 138.08536)
			(xy 212.959715 138.07162) (xy 212.945985 138.07162) (xy 212.945985 138.05789) (xy 212.945985 138.04416)
			(xy 212.945985 138.03043) (xy 212.945985 138.0167) (xy 212.945985 138.00296) (xy 212.932255 138.00296)
			(xy 212.932255 137.98923) (xy 212.932255 137.9755) (xy 212.932255 137.96177) (xy 212.932255 137.94804)
			(xy 212.932255 137.9343) (xy 212.932255 137.92057) (xy 212.918525 137.92057) (xy 212.918525 137.90684)
			(xy 212.918525 137.89311) (xy 212.918525 137.87938) (xy 212.918525 137.86565) (xy 212.918525 137.85191)
			(xy 212.918525 137.83818) (xy 212.918525 137.82445) (xy 212.904785 137.82445) (xy 212.904785 137.81072)
			(xy 212.904785 137.79699) (xy 212.904785 137.78326) (xy 212.904785 137.76952) (xy 214.126915 137.76952)
			(xy 214.126915 137.78326) (xy 214.126915 137.79699) (xy 214.126915 137.81072) (xy 214.126915 137.82445)
			(xy 214.126915 137.83818) (xy 214.126915 137.85191) (xy 214.126915 137.86565) (xy 214.126915 137.87938)
			(xy 214.126915 137.89311) (xy 214.126915 137.90684) (xy 214.126915 137.92057) (xy 214.126915 137.9343)
			(xy 214.126915 137.94804) (xy 214.126915 137.96177) (xy 214.126915 137.9755) (xy 214.126915 137.98923)
			(xy 214.126915 138.00296) (xy 214.126915 138.0167) (xy 214.126915 138.03043) (xy 214.126915 138.04416)
			(xy 214.126915 138.05789) (xy 214.126915 138.07162) (xy 214.126915 138.08536) (xy 214.126915 138.09909)
			(xy 214.126915 138.11282) (xy 214.126915 138.12655) (xy 214.126915 138.14028) (xy 214.126915 138.15401)
			(xy 214.126915 138.16775) (xy 214.126915 138.18148) (xy 214.126915 138.19521) (xy 214.126915 138.20894)
			(xy 214.126915 138.22267) (xy 214.126915 138.2364) (xy 214.126915 138.25014) (xy 214.126915 138.26387)
			(xy 214.126915 138.2776) (xy 214.126915 138.29133) (xy 214.126915 138.30506) (xy 214.126915 138.31879)
			(xy 214.126915 138.33253) (xy 214.126915 138.34626) (xy 214.126915 138.35999) (xy 214.126915 138.37372)
			(xy 214.126915 138.38745) (xy 214.126915 138.40118) (xy 214.126915 138.41492) (xy 214.126915 138.42865)
			(xy 214.126915 138.44238) (xy 214.126915 138.45611) (xy 214.126915 138.46984) (xy 214.126915 138.48358)
			(xy 214.126915 138.49731) (xy 214.126915 138.51104) (xy 214.126915 138.52477) (xy 214.126915 138.5385)
			(xy 214.126915 138.55224) (xy 214.126915 138.56597) (xy 214.126915 138.5797) (xy 214.126915 138.59343)
			(xy 214.126915 138.60716) (xy 214.126915 138.62089) (xy 214.126915 138.63463) (xy 214.126915 138.64836)
			(xy 214.126915 138.66209) (xy 214.126915 138.67582) (xy 214.126915 138.68955) (xy 214.126915 138.70328)
			(xy 214.126915 138.71702) (xy 214.126915 138.73075) (xy 214.126915 138.74448) (xy 214.126915 138.75821)
			(xy 214.126915 138.77194) (xy 214.126915 138.78567) (xy 214.126915 138.79941) (xy 214.126915 138.81314)
			(xy 214.126915 138.82687) (xy 214.126915 138.8406) (xy 214.126915 138.85433) (xy 214.126915 138.86806)
			(xy 214.126915 138.8818) (xy 214.126915 138.89553) (xy 214.126915 138.90926) (xy 214.126915 138.92299)
			(xy 214.126915 138.93672) (xy 214.126915 138.95045) (xy 214.126915 138.96419) (xy 214.126915 138.97792)
			(xy 214.126915 138.99165) (xy 214.126915 139.00538) (xy 214.126915 139.01911) (xy 214.126915 139.03285)
			(xy 214.126915 139.04658) (xy 214.126915 139.06031) (xy 214.126915 139.07404) (xy 214.126915 139.08777)
			(xy 214.126915 139.10151) (xy 214.126915 139.11524) (xy 214.126915 139.12897) (xy 214.126915 139.1427)
			(xy 214.126915 139.15643) (xy 214.126915 139.17016) (xy 214.126915 139.1839) (xy 214.126915 139.19763)
			(xy 214.126915 139.21136) (xy 214.126915 139.22509) (xy 214.126915 139.23882) (xy 214.126915 139.25255)
			(xy 214.126915 139.26629) (xy 214.126915 139.28002) (xy 214.126915 139.29375) (xy 214.126915 139.30748)
			(xy 214.126915 139.32121) (xy 214.126915 139.33494) (xy 214.126915 139.34868) (xy 214.126915 139.36241)
			(xy 214.126915 139.37614) (xy 214.126915 139.38987) (xy 214.126915 139.4036) (xy 214.126915 139.41733)
			(xy 214.126915 139.43107) (xy 214.126915 139.4448) (xy 214.126915 139.45853) (xy 214.126915 139.47226)
			(xy 214.126915 139.48599) (xy 214.126915 139.49972) (xy 214.126915 139.51346) (xy 214.126915 139.52719)
			(xy 214.126915 139.54092) (xy 214.126915 139.55465) (xy 214.126915 139.56838) (xy 214.126915 139.58212)
			(xy 214.126915 139.59585) (xy 214.126915 139.60958) (xy 214.126915 139.62331) (xy 214.126915 139.63704)
			(xy 214.126915 139.65078) (xy 214.126915 139.66451) (xy 214.126915 139.67824) (xy 214.126915 139.69197)
			(xy 214.126915 139.7057) (xy 214.126915 139.71943) (xy 214.126915 139.73317) (xy 214.126915 139.7469)
			(xy 214.126915 139.76063) (xy 214.140645 139.76063) (xy 214.140645 139.77436) (xy 214.140645 139.78809)
			(xy 214.140645 139.80182) (xy 214.154375 139.80182) (xy 214.154375 139.81556) (xy 214.154375 139.82929)
			(xy 214.168105 139.82929) (xy 214.168105 139.84302) (xy 214.181845 139.84302) (xy 214.181845 139.85675)
			(xy 214.195575 139.85675) (xy 214.195575 139.87048) (xy 214.209305 139.87048) (xy 214.209305 139.88421)
			(xy 214.223035 139.88421) (xy 214.223035 139.89795) (xy 214.236765 139.89795) (xy 214.236765 139.91168)
			(xy 214.250495 139.91168) (xy 214.250495 139.92541) (xy 214.264235 139.92541) (xy 214.264235 139.93914)
			(xy 214.277965 139.93914) (xy 214.277965 139.95287) (xy 214.291695 139.95287) (xy 214.291695 139.9666)
			(xy 214.305425 139.9666) (xy 214.305425 139.98034) (xy 214.319155 139.98034) (xy 214.319155 139.99407)
			(xy 214.332885 139.99407) (xy 214.332885 140.0078) (xy 214.346625 140.0078) (xy 214.346625 140.02153)
			(xy 214.360355 140.02153) (xy 214.360355 140.03526) (xy 214.374085 140.03526) (xy 214.374085 140.04899)
			(xy 214.387815 140.04899) (xy 214.387815 140.06273) (xy 214.401545 140.06273) (xy 214.401545 140.07646)
			(xy 214.415275 140.07646) (xy 214.415275 140.09019) (xy 214.429015 140.09019) (xy 214.429015 140.10392)
			(xy 214.442745 140.10392) (xy 214.442745 140.11765) (xy 214.456475 140.11765) (xy 214.456475 140.13139)
			(xy 214.470205 140.13139) (xy 214.470205 140.14512) (xy 214.483935 140.14512) (xy 214.483935 140.15885)
			(xy 214.497675 140.15885) (xy 214.497675 140.17258) (xy 214.511405 140.17258) (xy 214.511405 140.18631)
			(xy 214.525135 140.18631) (xy 214.525135 140.20005) (xy 214.538865 140.20005) (xy 214.538865 140.21378)
			(xy 214.552595 140.21378) (xy 214.552595 140.22751) (xy 214.580065 140.22751) (xy 214.580065 140.24124)
			(xy 214.621255 140.24124) (xy 214.621255 140.25497) (xy 216.365185 140.25497) (xy 216.365185 140.24124)
			(xy 216.378925 140.24124) (xy 216.378925 140.22751) (xy 216.392655 140.22751) (xy 216.392655 140.21378)
			(xy 216.406385 140.21378) (xy 216.406385 140.20005) (xy 216.406385 140.18631) (xy 216.406385 140.17258)
			(xy 216.406385 140.15885) (xy 216.406385 140.14512) (xy 216.406385 140.13139) (xy 216.406385 140.11765)
			(xy 216.406385 140.10392) (xy 216.406385 140.09019) (xy 216.406385 140.07646) (xy 216.406385 140.06273)
			(xy 216.406385 140.04899) (xy 216.406385 140.03526) (xy 216.406385 140.02153) (xy 216.406385 140.0078)
			(xy 216.406385 139.99407) (xy 216.406385 139.98034) (xy 216.406385 139.9666) (xy 216.406385 139.95287)
			(xy 216.406385 139.93914) (xy 216.406385 139.92541) (xy 216.406385 139.91168) (xy 216.406385 139.89795)
			(xy 216.406385 139.88421) (xy 216.406385 139.87048) (xy 216.406385 139.85675) (xy 216.406385 139.84302)
			(xy 216.406385 139.82929) (xy 216.406385 139.81556) (xy 216.406385 139.80182) (xy 216.406385 139.78809)
			(xy 216.406385 139.77436) (xy 216.406385 139.76063) (xy 216.406385 139.7469) (xy 216.406385 139.73317)
			(xy 216.406385 139.71943) (xy 216.406385 139.7057) (xy 216.406385 139.69197) (xy 216.406385 139.67824)
			(xy 216.406385 139.66451) (xy 216.406385 139.65078) (xy 216.406385 139.63704) (xy 216.406385 139.62331)
			(xy 216.406385 139.60958) (xy 216.406385 139.59585) (xy 216.406385 139.58212) (xy 216.406385 139.56838)
			(xy 216.392655 139.56838) (xy 216.392655 139.55465) (xy 216.378925 139.55465) (xy 216.378925 139.54092)
			(xy 216.351455 139.54092) (xy 216.351455 139.52719) (xy 214.923355 139.52719) (xy 214.923355 139.51346)
			(xy 214.895895 139.51346) (xy 214.895895 139.49972) (xy 214.895895 139.48599) (xy 214.882155 139.48599)
			(xy 214.882155 139.47226) (xy 214.882155 139.45853) (xy 214.882155 139.4448) (xy 214.882155 139.43107)
			(xy 214.882155 139.41733) (xy 214.882155 139.4036) (xy 214.882155 139.38987) (xy 214.882155 139.37614)
			(xy 214.882155 139.36241) (xy 214.882155 139.34868) (xy 214.882155 139.33494) (xy 214.882155 139.32121)
			(xy 214.882155 139.30748) (xy 214.882155 139.29375) (xy 214.882155 139.28002) (xy 214.882155 139.26629)
			(xy 214.882155 139.25255) (xy 214.882155 139.23882) (xy 214.882155 139.22509) (xy 214.882155 139.21136)
			(xy 214.882155 139.19763) (xy 214.882155 139.1839) (xy 214.882155 139.17016) (xy 214.882155 139.15643)
			(xy 214.882155 139.1427) (xy 214.882155 139.12897) (xy 214.882155 139.11524) (xy 214.882155 139.10151)
			(xy 214.882155 139.08777) (xy 214.882155 139.07404) (xy 214.882155 139.06031) (xy 214.882155 139.04658)
			(xy 214.882155 139.03285) (xy 214.882155 139.01911) (xy 214.882155 139.00538) (xy 214.882155 138.99165)
			(xy 214.882155 138.97792) (xy 214.882155 138.96419) (xy 214.882155 138.95045) (xy 214.882155 138.93672)
			(xy 214.882155 138.92299) (xy 214.882155 138.90926) (xy 214.882155 138.89553) (xy 214.882155 138.8818)
			(xy 214.882155 138.86806) (xy 214.882155 138.85433) (xy 214.882155 138.8406) (xy 214.882155 138.82687)
			(xy 214.882155 138.81314) (xy 214.882155 138.79941) (xy 214.882155 138.78567) (xy 214.882155 138.77194)
			(xy 214.882155 138.75821) (xy 214.882155 138.74448) (xy 214.882155 138.73075) (xy 214.882155 138.71702)
			(xy 214.882155 138.70328) (xy 214.882155 138.68955) (xy 214.882155 138.67582) (xy 214.882155 138.66209)
			(xy 214.882155 138.64836) (xy 214.882155 138.63463) (xy 214.882155 138.62089) (xy 214.882155 138.60716)
			(xy 214.882155 138.59343) (xy 214.882155 138.5797) (xy 214.882155 138.56597) (xy 214.882155 138.55224)
			(xy 214.882155 138.5385) (xy 214.882155 138.52477) (xy 214.882155 138.51104) (xy 214.882155 138.49731)
			(xy 214.882155 138.48358) (xy 214.882155 138.46984) (xy 214.882155 138.45611) (xy 214.882155 138.44238)
			(xy 214.882155 138.42865) (xy 214.882155 138.41492) (xy 214.882155 138.40118) (xy 216.076825 138.40118)
			(xy 216.076825 138.41492) (xy 216.076825 138.42865) (xy 216.076825 138.44238) (xy 216.076825 138.45611)
			(xy 216.076825 138.46984) (xy 216.076825 138.48358) (xy 216.076825 138.49731) (xy 216.076825 138.51104)
			(xy 216.076825 138.52477) (xy 216.076825 138.5385) (xy 216.076825 138.55224) (xy 216.076825 138.56597)
			(xy 216.076825 138.5797) (xy 216.076825 138.59343) (xy 216.076825 138.60716) (xy 216.076825 138.62089)
			(xy 216.076825 138.63463) (xy 216.076825 138.64836) (xy 216.076825 138.66209) (xy 216.076825 138.67582)
			(xy 216.076825 138.68955) (xy 216.076825 138.70328) (xy 216.076825 138.71702) (xy 216.076825 138.73075)
			(xy 216.076825 138.74448) (xy 216.076825 138.75821) (xy 216.076825 138.77194) (xy 216.076825 138.78567)
			(xy 216.076825 138.79941) (xy 216.076825 138.81314) (xy 216.076825 138.82687) (xy 216.076825 138.8406)
			(xy 216.076825 138.85433) (xy 216.076825 138.86806) (xy 216.076825 138.8818) (xy 216.076825 138.89553)
			(xy 216.076825 138.90926) (xy 216.076825 138.92299) (xy 216.076825 138.93672) (xy 216.076825 138.95045)
			(xy 216.076825 138.96419) (xy 216.076825 138.97792) (xy 216.076825 138.99165) (xy 216.076825 139.00538)
			(xy 216.076825 139.01911) (xy 216.090555 139.01911) (xy 216.090555 139.03285) (xy 216.104285 139.03285)
			(xy 216.104285 139.04658) (xy 216.104285 139.06031) (xy 216.118015 139.06031) (xy 216.118015 139.07404)
			(xy 216.131755 139.07404) (xy 216.131755 139.08777) (xy 216.131755 139.10151) (xy 216.145485 139.10151)
			(xy 216.145485 139.11524) (xy 216.159215 139.11524) (xy 216.159215 139.12897) (xy 216.172945 139.12897)
			(xy 216.172945 139.1427) (xy 216.186675 139.1427) (xy 216.186675 139.15643) (xy 216.200405 139.15643)
			(xy 216.200405 139.17016) (xy 216.214145 139.17016) (xy 216.214145 139.1839) (xy 216.227875 139.1839)
			(xy 216.227875 139.19763) (xy 216.241605 139.19763) (xy 216.241605 139.21136) (xy 216.255335 139.21136)
			(xy 216.255335 139.22509) (xy 216.282795 139.22509) (xy 216.282795 139.21136) (xy 216.296535 139.21136)
			(xy 216.296535 139.19763) (xy 216.310265 139.19763) (xy 216.310265 139.1839) (xy 216.323995 139.1839)
			(xy 216.323995 139.17016) (xy 216.337725 139.17016) (xy 216.337725 139.15643) (xy 216.351455 139.15643)
			(xy 216.351455 139.1427) (xy 216.365185 139.1427) (xy 216.365185 139.12897) (xy 216.378925 139.12897)
			(xy 216.378925 139.11524) (xy 216.392655 139.11524) (xy 216.749675 139.11524) (xy 216.749675 139.12897)
			(xy 216.749675 139.1427) (xy 216.749675 139.15643) (xy 216.749675 139.17016) (xy 216.749675 139.1839)
			(xy 216.749675 139.19763) (xy 216.749675 139.21136) (xy 216.749675 139.22509) (xy 216.749675 139.23882)
			(xy 216.749675 139.25255) (xy 216.749675 139.26629) (xy 216.749675 139.28002) (xy 216.749675 139.29375)
			(xy 216.749675 139.30748) (xy 216.749675 139.32121) (xy 216.749675 139.33494) (xy 216.749675 139.34868)
			(xy 216.749675 139.36241) (xy 216.749675 139.37614) (xy 216.749675 139.38987) (xy 216.749675 139.4036)
			(xy 216.749675 139.41733) (xy 216.749675 139.43107) (xy 216.749675 139.4448) (xy 216.749675 139.45853)
			(xy 216.749675 139.47226) (xy 216.749675 139.48599) (xy 216.749675 139.49972) (xy 216.749675 139.51346)
			(xy 216.749675 139.52719) (xy 216.749675 139.54092) (xy 216.749675 139.55465) (xy 216.749675 139.56838)
			(xy 216.749675 139.58212) (xy 216.749675 139.59585) (xy 216.749675 139.60958) (xy 216.749675 139.62331)
			(xy 216.749675 139.63704) (xy 216.749675 139.65078) (xy 216.749675 139.66451) (xy 216.749675 139.67824)
			(xy 216.749675 139.69197) (xy 216.749675 139.7057) (xy 216.749675 139.71943) (xy 216.749675 139.73317)
			(xy 216.749675 139.7469) (xy 216.749675 139.76063) (xy 216.749675 139.77436) (xy 216.749675 139.78809)
			(xy 216.749675 139.80182) (xy 216.749675 139.81556) (xy 216.749675 139.82929) (xy 216.749675 139.84302)
			(xy 216.749675 139.85675) (xy 216.749675 139.87048) (xy 216.749675 139.88421) (xy 216.749675 139.89795)
			(xy 216.749675 139.91168) (xy 216.749675 139.92541) (xy 216.749675 139.93914) (xy 216.749675 139.95287)
			(xy 216.749675 139.9666) (xy 216.749675 139.98034) (xy 216.749675 139.99407) (xy 216.749675 140.0078)
			(xy 216.749675 140.02153) (xy 216.749675 140.03526) (xy 216.749675 140.04899) (xy 216.749675 140.06273)
			(xy 216.749675 140.07646) (xy 216.749675 140.09019) (xy 216.749675 140.10392) (xy 216.749675 140.11765)
			(xy 216.749675 140.13139) (xy 216.749675 140.14512) (xy 216.749675 140.15885) (xy 216.749675 140.17258)
			(xy 216.749675 140.18631) (xy 216.749675 140.20005) (xy 216.749675 140.21378) (xy 216.763415 140.21378)
			(xy 216.763415 140.22751) (xy 216.777145 140.22751) (xy 216.777145 140.24124) (xy 216.804605 140.24124)
			(xy 216.804605 140.25497) (xy 217.449995 140.25497) (xy 217.449995 140.24124) (xy 217.477465 140.24124)
			(xy 217.477465 140.22751) (xy 217.491195 140.22751) (xy 217.491195 140.21378) (xy 217.491195 140.20005)
			(xy 217.504925 140.20005) (xy 217.504925 140.18631) (xy 217.504925 140.17258) (xy 217.504925 140.15885)
			(xy 217.504925 140.14512) (xy 217.504925 140.13139) (xy 217.504925 140.11765) (xy 217.504925 140.10392)
			(xy 217.504925 140.09019) (xy 217.504925 140.07646) (xy 217.504925 140.06273) (xy 217.504925 140.04899)
			(xy 217.504925 140.03526) (xy 217.504925 140.02153) (xy 217.504925 140.0078) (xy 217.504925 139.99407)
			(xy 217.504925 139.98034) (xy 217.504925 139.9666) (xy 217.504925 139.95287) (xy 217.504925 139.93914)
			(xy 217.504925 139.92541) (xy 217.504925 139.91168) (xy 217.504925 139.89795) (xy 217.504925 139.88421)
			(xy 217.504925 139.87048) (xy 217.504925 139.85675) (xy 217.504925 139.84302) (xy 217.504925 139.82929)
			(xy 217.504925 139.81556) (xy 217.504925 139.80182) (xy 217.504925 139.78809) (xy 217.504925 139.77436)
			(xy 217.504925 139.76063) (xy 217.504925 139.7469) (xy 217.504925 139.73317) (xy 217.504925 139.71943)
			(xy 217.504925 139.7057) (xy 217.504925 139.69197) (xy 217.504925 139.67824) (xy 217.504925 139.66451)
			(xy 217.504925 139.65078) (xy 217.504925 139.63704) (xy 217.504925 139.62331) (xy 217.504925 139.60958)
			(xy 217.504925 139.59585) (xy 217.504925 139.58212) (xy 217.504925 139.56838) (xy 217.504925 139.55465)
			(xy 217.504925 139.54092) (xy 217.504925 139.52719) (xy 217.504925 139.51346) (xy 217.504925 139.49972)
			(xy 217.504925 139.48599) (xy 217.504925 139.47226) (xy 217.504925 139.45853) (xy 217.504925 139.4448)
			(xy 217.504925 139.43107) (xy 217.504925 139.41733) (xy 217.504925 139.4036) (xy 217.504925 139.38987)
			(xy 217.504925 139.37614) (xy 217.518655 139.37614) (xy 217.518655 139.36241) (xy 217.518655 139.34868)
			(xy 217.546115 139.34868) (xy 217.546115 139.33494) (xy 218.466145 139.33494) (xy 218.466145 139.34868)
			(xy 218.493615 139.34868) (xy 218.493615 139.36241) (xy 218.493615 139.37614) (xy 218.507345 139.37614)
			(xy 218.507345 139.38987) (xy 218.507345 139.4036) (xy 218.507345 139.41733) (xy 218.507345 139.43107)
			(xy 218.507345 139.4448) (xy 218.507345 139.45853) (xy 218.507345 139.47226) (xy 218.507345 139.48599)
			(xy 218.507345 139.49972) (xy 218.507345 139.51346) (xy 218.507345 139.52719) (xy 218.507345 139.54092)
			(xy 218.507345 139.55465) (xy 218.507345 139.56838) (xy 218.507345 139.58212) (xy 218.507345 139.59585)
			(xy 218.507345 139.60958) (xy 218.507345 139.62331) (xy 218.507345 139.63704) (xy 218.507345 139.65078)
			(xy 218.507345 139.66451) (xy 218.507345 139.67824) (xy 218.507345 139.69197) (xy 218.507345 139.7057)
			(xy 218.507345 139.71943) (xy 218.507345 139.73317) (xy 218.507345 139.7469) (xy 218.507345 139.76063)
			(xy 218.507345 139.77436) (xy 218.507345 139.78809) (xy 218.507345 139.80182) (xy 218.507345 139.81556)
			(xy 218.507345 139.82929) (xy 218.507345 139.84302) (xy 218.507345 139.85675) (xy 218.507345 139.87048)
			(xy 218.507345 139.88421) (xy 218.507345 139.89795) (xy 218.507345 139.91168) (xy 218.507345 139.92541)
			(xy 218.507345 139.93914) (xy 218.507345 139.95287) (xy 218.507345 139.9666) (xy 218.507345 139.98034)
			(xy 218.507345 139.99407) (xy 218.507345 140.0078) (xy 218.507345 140.02153) (xy 218.507345 140.03526)
			(xy 218.507345 140.04899) (xy 218.507345 140.06273) (xy 218.507345 140.07646) (xy 218.507345 140.09019)
			(xy 218.507345 140.10392) (xy 218.507345 140.11765) (xy 218.507345 140.13139) (xy 218.507345 140.14512)
			(xy 218.507345 140.15885) (xy 218.507345 140.17258) (xy 218.507345 140.18631) (xy 218.507345 140.20005)
			(xy 218.507345 140.21378) (xy 218.521075 140.21378) (xy 218.521075 140.22751) (xy 218.534805 140.22751)
			(xy 218.534805 140.24124) (xy 218.562265 140.24124) (xy 218.562265 140.25497) (xy 219.207665 140.25497)
			(xy 219.207665 140.24124) (xy 219.235125 140.24124) (xy 219.235125 140.22751) (xy 219.248855 140.22751)
			(xy 219.248855 140.21378) (xy 219.248855 140.20005) (xy 219.262585 140.20005) (xy 219.262585 140.18631)
			(xy 219.262585 140.17258) (xy 219.262585 140.15885) (xy 219.262585 140.14512) (xy 219.262585 140.13139)
			(xy 219.262585 140.11765) (xy 219.262585 140.10392) (xy 219.262585 140.09019) (xy 219.262585 140.07646)
			(xy 219.262585 140.06273) (xy 219.262585 140.04899) (xy 219.262585 140.03526) (xy 219.262585 140.02153)
			(xy 219.262585 140.0078) (xy 219.262585 139.99407) (xy 219.262585 139.98034) (xy 219.262585 139.9666)
			(xy 219.262585 139.95287) (xy 219.262585 139.93914) (xy 219.262585 139.92541) (xy 219.262585 139.91168)
			(xy 219.262585 139.89795) (xy 219.262585 139.88421) (xy 219.262585 139.87048) (xy 219.262585 139.85675)
			(xy 219.262585 139.84302) (xy 219.262585 139.82929) (xy 219.262585 139.81556) (xy 219.262585 139.80182)
			(xy 219.262585 139.78809) (xy 219.262585 139.77436) (xy 219.262585 139.76063) (xy 219.262585 139.7469)
			(xy 219.262585 139.73317) (xy 219.262585 139.71943) (xy 219.262585 139.7057) (xy 219.262585 139.69197)
			(xy 219.262585 139.67824) (xy 219.262585 139.66451) (xy 219.262585 139.65078) (xy 219.262585 139.63704)
			(xy 219.262585 139.62331) (xy 219.262585 139.60958) (xy 219.262585 139.59585) (xy 219.262585 139.58212)
			(xy 219.262585 139.56838) (xy 219.262585 139.55465) (xy 219.262585 139.54092) (xy 219.262585 139.52719)
			(xy 219.262585 139.51346) (xy 219.262585 139.49972) (xy 219.262585 139.48599) (xy 219.262585 139.47226)
			(xy 219.262585 139.45853) (xy 219.262585 139.4448) (xy 219.262585 139.43107) (xy 219.262585 139.41733)
			(xy 219.262585 139.4036) (xy 219.262585 139.38987) (xy 219.262585 139.37614) (xy 219.262585 139.36241)
			(xy 219.262585 139.34868) (xy 219.262585 139.33494) (xy 219.262585 139.32121) (xy 219.262585 139.30748)
			(xy 219.262585 139.29375) (xy 219.262585 139.28002) (xy 219.262585 139.26629) (xy 219.262585 139.25255)
			(xy 219.262585 139.23882) (xy 219.262585 139.22509) (xy 219.262585 139.21136) (xy 219.262585 139.19763)
			(xy 219.262585 139.1839) (xy 219.262585 139.17016) (xy 219.262585 139.15643) (xy 219.262585 139.1427)
			(xy 219.262585 139.12897) (xy 219.262585 139.11524) (xy 219.262585 139.10151) (xy 219.262585 139.08777)
			(xy 219.262585 139.07404) (xy 219.262585 139.06031) (xy 219.262585 139.04658) (xy 219.262585 139.03285)
			(xy 219.262585 139.01911) (xy 219.262585 139.00538) (xy 219.262585 138.99165) (xy 219.262585 138.97792)
			(xy 219.262585 138.96419) (xy 219.262585 138.95045) (xy 219.262585 138.93672) (xy 219.262585 138.92299)
			(xy 219.262585 138.90926) (xy 219.262585 138.89553) (xy 219.262585 138.8818) (xy 219.262585 138.86806)
			(xy 219.262585 138.85433) (xy 219.262585 138.8406) (xy 219.262585 138.82687) (xy 219.262585 138.81314)
			(xy 219.262585 138.79941) (xy 219.262585 138.78567) (xy 219.262585 138.77194) (xy 219.262585 138.75821)
			(xy 219.262585 138.74448) (xy 219.262585 138.73075) (xy 219.262585 138.71702) (xy 219.262585 138.70328)
			(xy 219.262585 138.68955) (xy 219.262585 138.67582) (xy 219.262585 138.66209) (xy 219.262585 138.64836)
			(xy 219.262585 138.63463) (xy 219.262585 138.62089) (xy 219.262585 138.60716) (xy 219.262585 138.59343)
			(xy 219.262585 138.5797) (xy 219.262585 138.56597) (xy 219.262585 138.55224) (xy 219.262585 138.5385)
			(xy 219.262585 138.52477) (xy 219.262585 138.51104) (xy 219.262585 138.49731) (xy 219.262585 138.48358)
			(xy 219.262585 138.46984) (xy 219.262585 138.45611) (xy 219.262585 138.44238) (xy 219.262585 138.42865)
			(xy 219.262585 138.41492) (xy 219.262585 138.40118) (xy 219.262585 138.38745) (xy 219.262585 138.37372)
			(xy 219.262585 138.35999) (xy 219.262585 138.34626) (xy 219.262585 138.33253) (xy 219.262585 138.31879)
			(xy 219.262585 138.30506) (xy 219.262585 138.29133) (xy 219.262585 138.2776) (xy 219.262585 138.26387)
			(xy 219.262585 138.25014) (xy 219.262585 138.2364) (xy 219.262585 138.22267) (xy 219.262585 138.20894)
			(xy 219.262585 138.19521) (xy 219.262585 138.18148) (xy 219.262585 138.16775) (xy 219.262585 138.15401)
			(xy 219.262585 138.14028) (xy 219.262585 138.12655) (xy 219.262585 138.11282) (xy 219.262585 138.09909)
			(xy 219.262585 138.08536) (xy 219.262585 138.07162) (xy 219.262585 138.05789) (xy 219.262585 138.04416)
			(xy 219.262585 138.03043) (xy 219.262585 138.0167) (xy 219.262585 138.00296) (xy 219.262585 137.98923)
			(xy 219.262585 137.9755) (xy 219.262585 137.96177) (xy 219.262585 137.94804) (xy 219.262585 137.9343)
			(xy 219.262585 137.92057) (xy 219.262585 137.90684) (xy 219.262585 137.89311) (xy 219.262585 137.87938)
			(xy 219.262585 137.86565) (xy 219.262585 137.85191) (xy 219.262585 137.83818) (xy 219.262585 137.82445)
			(xy 219.262585 137.81072) (xy 219.262585 137.79699) (xy 219.262585 137.78326) (xy 219.248855 137.78326)
			(xy 219.248855 137.76952) (xy 219.248855 137.75579) (xy 219.248855 137.74206) (xy 219.248855 137.72833)
			(xy 219.235125 137.72833) (xy 219.235125 137.7146) (xy 219.235125 137.70087) (xy 219.235125 137.68713)
			(xy 219.221395 137.68713) (xy 219.221395 137.6734) (xy 219.207665 137.6734) (xy 219.207665 137.65967)
			(xy 219.193925 137.65967) (xy 219.193925 137.64594) (xy 219.180195 137.64594) (xy 219.180195 137.63221)
			(xy 219.166465 137.63221) (xy 219.166465 137.61848) (xy 219.152735 137.61848) (xy 219.152735 137.60474)
			(xy 219.139005 137.60474) (xy 219.139005 137.59101) (xy 219.125265 137.59101) (xy 219.125265 137.57728)
			(xy 219.111535 137.57728) (xy 219.111535 137.56355) (xy 219.097805 137.56355) (xy 219.097805 137.54982)
			(xy 219.084075 137.54982) (xy 219.084075 137.53609) (xy 219.070345 137.53609) (xy 219.070345 137.52235)
			(xy 219.056615 137.52235) (xy 219.056615 137.50862) (xy 219.042875 137.50862) (xy 219.042875 137.49489)
			(xy 219.029145 137.49489) (xy 219.029145 137.48116) (xy 219.015415 137.48116) (xy 219.015415 137.46743)
			(xy 219.001685 137.46743) (xy 219.001685 137.45369) (xy 218.987955 137.45369) (xy 218.987955 137.43996)
			(xy 218.974225 137.43996) (xy 218.974225 137.42623) (xy 218.960485 137.42623) (xy 218.960485 137.4125)
			(xy 218.946755 137.4125) (xy 218.946755 137.39877) (xy 218.933025 137.39877) (xy 218.933025 137.38503)
			(xy 218.919295 137.38503) (xy 218.919295 137.3713) (xy 218.905565 137.3713) (xy 218.905565 137.35757)
			(xy 218.891835 137.35757) (xy 218.891835 137.34384) (xy 219.550955 137.34384) (xy 219.550955 137.35757)
			(xy 219.550955 137.3713) (xy 219.550955 137.38503) (xy 219.550955 137.39877) (xy 219.550955 137.4125)
			(xy 219.550955 137.42623) (xy 219.550955 137.43996) (xy 219.550955 137.45369) (xy 219.550955 137.46743)
			(xy 219.550955 137.48116) (xy 219.550955 137.49489) (xy 219.550955 137.50862) (xy 219.550955 137.52235)
			(xy 219.550955 137.53609) (xy 219.550955 137.54982) (xy 219.550955 137.56355) (xy 219.550955 137.57728)
			(xy 219.550955 137.59101) (xy 219.550955 137.60474) (xy 219.550955 137.61848) (xy 219.550955 137.63221)
			(xy 219.550955 137.64594) (xy 219.550955 137.65967) (xy 219.550955 137.6734) (xy 219.550955 137.68713)
			(xy 219.550955 137.70087) (xy 219.550955 137.7146) (xy 219.550955 137.72833) (xy 219.550955 137.74206)
			(xy 219.550955 137.75579) (xy 219.550955 137.76952) (xy 219.550955 137.78326) (xy 219.550955 137.79699)
			(xy 219.550955 137.81072) (xy 219.550955 137.82445) (xy 219.550955 137.83818) (xy 219.550955 137.85191)
			(xy 219.550955 137.86565) (xy 219.550955 137.87938) (xy 219.550955 137.89311) (xy 219.550955 137.90684)
			(xy 219.550955 137.92057) (xy 219.550955 137.9343) (xy 219.550955 137.94804) (xy 219.550955 137.96177)
			(xy 219.550955 137.9755) (xy 219.550955 137.98923) (xy 219.550955 138.00296) (xy 219.550955 138.0167)
			(xy 219.550955 138.03043) (xy 219.550955 138.04416) (xy 219.550955 138.05789) (xy 219.550955 138.07162)
			(xy 219.550955 138.08536) (xy 219.550955 138.09909) (xy 219.550955 138.11282) (xy 219.550955 138.12655)
			(xy 219.550955 138.14028) (xy 219.550955 138.15401) (xy 219.550955 138.16775) (xy 219.550955 138.18148)
			(xy 219.550955 138.19521) (xy 219.550955 138.20894) (xy 219.550955 138.22267) (xy 219.550955 138.2364)
			(xy 219.550955 138.25014) (xy 219.550955 138.26387) (xy 219.550955 138.2776) (xy 219.550955 138.29133)
			(xy 219.550955 138.30506) (xy 219.550955 138.31879) (xy 219.550955 138.33253) (xy 219.550955 138.34626)
			(xy 219.550955 138.35999) (xy 219.550955 138.37372) (xy 219.550955 138.38745) (xy 219.550955 138.40118)
			(xy 219.550955 138.41492) (xy 219.550955 138.42865) (xy 219.550955 138.44238) (xy 219.550955 138.45611)
			(xy 219.550955 138.46984) (xy 219.550955 138.48358) (xy 219.550955 138.49731) (xy 219.550955 138.51104)
			(xy 219.550955 138.52477) (xy 219.550955 138.5385) (xy 219.550955 138.55224) (xy 219.550955 138.56597)
			(xy 219.550955 138.5797) (xy 219.550955 138.59343) (xy 219.550955 138.60716) (xy 219.550955 138.62089)
			(xy 219.550955 138.63463) (xy 219.550955 138.64836) (xy 219.550955 138.66209) (xy 219.550955 138.67582)
			(xy 219.550955 138.68955) (xy 219.550955 138.70328) (xy 219.550955 138.71702) (xy 219.550955 138.73075)
			(xy 219.550955 138.74448) (xy 219.550955 138.75821) (xy 219.550955 138.77194) (xy 219.550955 138.78567)
			(xy 219.550955 138.79941) (xy 219.550955 138.81314) (xy 219.550955 138.82687) (xy 219.550955 138.8406)
			(xy 219.550955 138.85433) (xy 219.550955 138.86806) (xy 219.550955 138.8818) (xy 219.550955 138.89553)
			(xy 219.550955 138.90926) (xy 219.550955 138.92299) (xy 219.550955 138.93672) (xy 219.550955 138.95045)
			(xy 219.550955 138.96419) (xy 219.550955 138.97792) (xy 219.550955 138.99165) (xy 219.550955 139.00538)
			(xy 219.550955 139.01911) (xy 219.550955 139.03285) (xy 219.550955 139.04658) (xy 219.550955 139.06031)
			(xy 219.550955 139.07404) (xy 219.550955 139.08777) (xy 219.550955 139.10151) (xy 219.550955 139.11524)
			(xy 219.550955 139.12897) (xy 219.550955 139.1427) (xy 219.550955 139.15643) (xy 219.550955 139.17016)
			(xy 219.550955 139.1839) (xy 219.550955 139.19763) (xy 219.550955 139.21136) (xy 219.550955 139.22509)
			(xy 219.550955 139.23882) (xy 219.550955 139.25255) (xy 219.550955 139.26629) (xy 219.550955 139.28002)
			(xy 219.550955 139.29375) (xy 219.550955 139.30748) (xy 219.550955 139.32121) (xy 219.550955 139.33494)
			(xy 219.550955 139.34868) (xy 219.550955 139.36241) (xy 219.550955 139.37614) (xy 219.550955 139.38987)
			(xy 219.550955 139.4036) (xy 219.550955 139.41733) (xy 219.550955 139.43107) (xy 219.550955 139.4448)
			(xy 219.550955 139.45853) (xy 219.550955 139.47226) (xy 219.550955 139.48599) (xy 219.550955 139.49972)
			(xy 219.550955 139.51346) (xy 219.550955 139.52719) (xy 219.550955 139.54092) (xy 219.550955 139.55465)
			(xy 219.550955 139.56838) (xy 219.550955 139.58212) (xy 219.550955 139.59585) (xy 219.550955 139.60958)
			(xy 219.550955 139.62331) (xy 219.550955 139.63704) (xy 219.550955 139.65078) (xy 219.550955 139.66451)
			(xy 219.550955 139.67824) (xy 219.550955 139.69197) (xy 219.550955 139.7057) (xy 219.550955 139.71943)
			(xy 219.550955 139.73317) (xy 219.550955 139.7469) (xy 219.550955 139.76063) (xy 219.550955 139.77436)
			(xy 219.550955 139.78809) (xy 219.550955 139.80182) (xy 219.550955 139.81556) (xy 219.550955 139.82929)
			(xy 219.550955 139.84302) (xy 219.550955 139.85675) (xy 219.550955 139.87048) (xy 219.550955 139.88421)
			(xy 219.550955 139.89795) (xy 219.550955 139.91168) (xy 219.550955 139.92541) (xy 219.550955 139.93914)
			(xy 219.550955 139.95287) (xy 219.550955 139.9666) (xy 219.550955 139.98034) (xy 219.550955 139.99407)
			(xy 219.550955 140.0078) (xy 219.550955 140.02153) (xy 219.550955 140.03526) (xy 219.550955 140.04899)
			(xy 219.550955 140.06273) (xy 219.550955 140.07646) (xy 219.550955 140.09019) (xy 219.550955 140.10392)
			(xy 219.550955 140.11765) (xy 219.550955 140.13139) (xy 219.550955 140.14512) (xy 219.550955 140.15885)
			(xy 219.564685 140.15885) (xy 219.564685 140.17258) (xy 219.550955 140.17258) (xy 219.550955 140.18631)
			(xy 219.564685 140.18631) (xy 219.564685 140.20005) (xy 219.564685 140.21378) (xy 219.564685 140.22751)
			(xy 219.578415 140.22751) (xy 219.578415 140.24124) (xy 219.605885 140.24124) (xy 219.605885 140.25497)
			(xy 220.278735 140.25497) (xy 220.278735 140.24124) (xy 220.292475 140.24124) (xy 220.292475 140.22751)
			(xy 220.306205 140.22751) (xy 220.306205 140.21378) (xy 220.306205 140.20005) (xy 220.306205 140.18631)
			(xy 220.319935 140.18631) (xy 220.319935 140.17258) (xy 220.319935 140.15885) (xy 220.319935 140.14512)
			(xy 220.319935 140.13139) (xy 220.319935 140.11765) (xy 220.319935 140.10392) (xy 220.319935 140.09019)
			(xy 220.319935 140.07646) (xy 220.319935 140.06273) (xy 220.319935 140.04899) (xy 220.319935 140.03526)
			(xy 220.319935 140.02153) (xy 220.319935 140.0078) (xy 220.319935 139.99407) (xy 220.319935 139.98034)
			(xy 220.319935 139.9666) (xy 220.319935 139.95287) (xy 220.319935 139.93914) (xy 220.319935 139.92541)
			(xy 220.319935 139.91168) (xy 220.319935 139.89795) (xy 220.319935 139.88421) (xy 220.319935 139.87048)
			(xy 220.319935 139.85675) (xy 220.319935 139.84302) (xy 220.319935 139.82929) (xy 220.319935 139.81556)
			(xy 220.319935 139.80182) (xy 220.319935 139.78809) (xy 220.319935 139.77436) (xy 220.319935 139.76063)
			(xy 220.319935 139.7469) (xy 220.319935 139.73317) (xy 220.319935 139.71943) (xy 220.319935 139.7057)
			(xy 220.319935 139.69197) (xy 220.319935 139.67824) (xy 220.319935 139.66451) (xy 220.319935 139.65078)
			(xy 220.319935 139.63704) (xy 220.319935 139.62331) (xy 220.319935 139.60958) (xy 220.319935 139.59585)
			(xy 220.319935 139.58212) (xy 220.319935 139.56838) (xy 220.319935 139.55465) (xy 220.319935 139.54092)
			(xy 220.319935 139.52719) (xy 220.319935 139.51346) (xy 220.319935 139.49972) (xy 220.319935 139.48599)
			(xy 220.319935 139.47226) (xy 220.319935 139.45853) (xy 220.319935 139.4448) (xy 220.306205 139.4448)
			(xy 220.306205 139.43107) (xy 220.319935 139.43107) (xy 220.319935 139.41733) (xy 220.319935 139.4036)
			(xy 220.319935 139.38987) (xy 220.319935 139.37614) (xy 220.319935 139.36241) (xy 220.841745 139.36241)
			(xy 220.841745 139.37614) (xy 220.841745 139.38987) (xy 220.855475 139.38987) (xy 220.855475 139.4036)
			(xy 220.855475 139.41733) (xy 220.869205 139.41733) (xy 220.869205 139.43107) (xy 220.882935 139.43107)
			(xy 220.882935 139.4448) (xy 220.882935 139.45853) (xy 220.896665 139.45853) (xy 220.896665 139.47226)
			(xy 220.896665 139.48599) (xy 220.910395 139.48599) (xy 220.910395 139.49972) (xy 220.924135 139.49972)
			(xy 220.924135 139.51346) (xy 220.924135 139.52719) (xy 220.937865 139.52719) (xy 220.937865 139.54092)
			(xy 220.937865 139.55465) (xy 220.951595 139.55465) (xy 220.951595 139.56838) (xy 220.951595 139.58212)
			(xy 220.965325 139.58212) (xy 220.965325 139.59585) (xy 220.979055 139.59585) (xy 220.979055 139.60958)
			(xy 220.979055 139.62331) (xy 220.992785 139.62331) (xy 220.992785 139.63704) (xy 220.992785 139.65078)
			(xy 221.006525 139.65078) (xy 221.006525 139.66451) (xy 221.020255 139.66451) (xy 221.020255 139.67824)
			(xy 221.020255 139.69197) (xy 221.033985 139.69197) (xy 221.033985 139.7057) (xy 221.033985 139.71943)
			(xy 221.047715 139.71943) (xy 221.047715 139.73317) (xy 221.061445 139.73317) (xy 221.061445 139.7469)
			(xy 221.061445 139.76063) (xy 221.075175 139.76063) (xy 221.075175 139.77436) (xy 221.075175 139.78809)
			(xy 221.088915 139.78809) (xy 221.088915 139.80182) (xy 221.088915 139.81556) (xy 221.102645 139.81556)
			(xy 221.102645 139.82929) (xy 221.116375 139.82929) (xy 221.116375 139.84302) (xy 221.116375 139.85675)
			(xy 221.130105 139.85675) (xy 221.130105 139.87048) (xy 221.130105 139.88421) (xy 221.143835 139.88421)
			(xy 221.143835 139.89795) (xy 221.157565 139.89795) (xy 221.157565 139.91168) (xy 221.157565 139.92541)
			(xy 221.171305 139.92541) (xy 221.171305 139.93914) (xy 221.171305 139.95287) (xy 221.185035 139.95287)
			(xy 221.185035 139.9666) (xy 221.198765 139.9666) (xy 221.198765 139.98034) (xy 221.198765 139.99407)
			(xy 221.212495 139.99407) (xy 221.212495 140.0078) (xy 221.212495 140.02153) (xy 221.226225 140.02153)
			(xy 221.226225 140.03526) (xy 221.239955 140.03526) (xy 221.239955 140.04899) (xy 221.239955 140.06273)
			(xy 221.253695 140.06273) (xy 221.253695 140.07646) (xy 221.253695 140.09019) (xy 221.267425 140.09019)
			(xy 221.267425 140.10392) (xy 221.267425 140.11765) (xy 221.281155 140.11765) (xy 221.281155 140.13139)
			(xy 221.294885 140.13139) (xy 221.294885 140.14512) (xy 221.294885 140.15885) (xy 221.308615 140.15885)
			(xy 221.308615 140.17258) (xy 221.308615 140.18631) (xy 221.322355 140.18631) (xy 221.322355 140.20005)
			(xy 221.336085 140.20005) (xy 221.336085 140.21378) (xy 221.349815 140.21378) (xy 221.349815 140.22751)
			(xy 221.363545 140.22751) (xy 221.363545 140.24124) (xy 221.391015 140.24124) (xy 221.391015 140.25497)
			(xy 222.159985 140.25497) (xy 222.159985 140.24124) (xy 222.173715 140.24124) (xy 222.173715 140.22751)
			(xy 222.173715 140.21378) (xy 222.173715 140.20005) (xy 222.173715 140.18631) (xy 222.159985 140.18631)
			(xy 222.159985 140.17258) (xy 222.146255 140.17258) (xy 222.146255 140.15885) (xy 222.146255 140.14512)
			(xy 222.132525 140.14512) (xy 222.132525 140.13139) (xy 222.132525 140.11765) (xy 222.118795 140.11765)
			(xy 222.118795 140.10392) (xy 222.105065 140.10392) (xy 222.105065 140.09019) (xy 222.105065 140.07646)
			(xy 222.091325 140.07646) (xy 222.091325 140.06273) (xy 222.091325 140.04899) (xy 222.077595 140.04899)
			(xy 222.077595 140.03526) (xy 222.063865 140.03526) (xy 222.063865 140.02153) (xy 222.063865 140.0078)
			(xy 222.050135 140.0078) (xy 222.050135 139.99407) (xy 222.050135 139.98034) (xy 222.036405 139.98034)
			(xy 222.036405 139.9666) (xy 222.022675 139.9666) (xy 222.022675 139.95287) (xy 222.022675 139.93914)
			(xy 222.008935 139.93914) (xy 222.008935 139.92541) (xy 222.008935 139.91168) (xy 221.995205 139.91168)
			(xy 221.995205 139.89795) (xy 221.981475 139.89795) (xy 221.981475 139.88421) (xy 221.981475 139.87048)
			(xy 221.967745 139.87048) (xy 221.967745 139.85675) (xy 221.967745 139.84302) (xy 221.954015 139.84302)
			(xy 221.954015 139.82929) (xy 221.940285 139.82929) (xy 221.940285 139.81556) (xy 221.940285 139.80182)
			(xy 221.926545 139.80182) (xy 221.926545 139.78809) (xy 221.926545 139.77436) (xy 221.912815 139.77436)
			(xy 221.912815 139.76063) (xy 221.899085 139.76063) (xy 221.899085 139.7469) (xy 221.899085 139.73317)
			(xy 221.885355 139.73317) (xy 221.885355 139.71943) (xy 221.885355 139.7057) (xy 221.871625 139.7057)
			(xy 221.871625 139.69197) (xy 221.857895 139.69197) (xy 221.857895 139.67824) (xy 221.857895 139.66451)
			(xy 221.844155 139.66451) (xy 221.844155 139.65078) (xy 221.844155 139.63704) (xy 221.830425 139.63704)
			(xy 221.830425 139.62331) (xy 221.816695 139.62331) (xy 221.816695 139.60958) (xy 221.816695 139.59585)
			(xy 221.802965 139.59585) (xy 221.802965 139.58212) (xy 221.802965 139.56838) (xy 221.789235 139.56838)
			(xy 221.789235 139.55465) (xy 221.775495 139.55465) (xy 221.775495 139.54092) (xy 221.775495 139.52719)
			(xy 221.761765 139.52719) (xy 221.761765 139.51346) (xy 221.761765 139.49972) (xy 221.748035 139.49972)
			(xy 221.748035 139.48599) (xy 221.734305 139.48599) (xy 221.734305 139.47226) (xy 221.734305 139.45853)
			(xy 221.720575 139.45853) (xy 221.720575 139.4448) (xy 221.720575 139.43107) (xy 221.706835 139.43107)
			(xy 221.706835 139.41733) (xy 221.706835 139.4036) (xy 221.693105 139.4036) (xy 221.693105 139.38987)
			(xy 221.679375 139.38987) (xy 221.679375 139.37614) (xy 221.679375 139.36241) (xy 221.665645 139.36241)
			(xy 221.665645 139.34868) (xy 221.665645 139.33494) (xy 221.651915 139.33494) (xy 221.651915 139.32121)
			(xy 221.638185 139.32121) (xy 221.638185 139.30748) (xy 221.638185 139.29375) (xy 221.651915 139.29375)
			(xy 221.651915 139.28002) (xy 221.665645 139.28002) (xy 221.665645 139.26629) (xy 221.679375 139.26629)
			(xy 221.679375 139.25255) (xy 221.693105 139.25255) (xy 221.693105 139.23882) (xy 221.706835 139.23882)
			(xy 221.706835 139.22509) (xy 221.720575 139.22509) (xy 221.720575 139.21136) (xy 221.734305 139.21136)
			(xy 221.734305 139.19763) (xy 221.748035 139.19763) (xy 221.748035 139.1839) (xy 221.761765 139.1839)
			(xy 221.761765 139.17016) (xy 221.775495 139.17016) (xy 221.775495 139.15643) (xy 221.789235 139.15643)
			(xy 221.789235 139.1427) (xy 221.802965 139.1427) (xy 221.802965 139.12897) (xy 221.816695 139.12897)
			(xy 221.816695 139.11524) (xy 221.830425 139.11524) (xy 221.830425 139.10151) (xy 221.844155 139.10151)
			(xy 221.844155 139.08777) (xy 221.857895 139.08777) (xy 221.857895 139.07404) (xy 221.871625 139.07404)
			(xy 221.871625 139.06031) (xy 221.885355 139.06031) (xy 221.885355 139.04658) (xy 221.899085 139.04658)
			(xy 221.899085 139.03285) (xy 221.912815 139.03285) (xy 221.912815 139.01911) (xy 221.926545 139.01911)
			(xy 221.926545 139.00538) (xy 221.940285 139.00538) (xy 221.940285 138.99165) (xy 221.954015 138.99165)
			(xy 221.954015 138.97792) (xy 221.954015 138.96419) (xy 221.967745 138.96419) (xy 221.967745 138.95045)
			(xy 221.981475 138.95045) (xy 221.981475 138.93672) (xy 221.995205 138.93672) (xy 221.995205 138.92299)
			(xy 222.008935 138.92299) (xy 222.008935 138.90926) (xy 222.022675 138.90926) (xy 222.022675 138.89553)
			(xy 222.036405 138.89553) (xy 222.036405 138.8818) (xy 222.036405 138.86806) (xy 222.050135 138.86806)
			(xy 222.050135 138.85433) (xy 222.050135 138.8406) (xy 222.063865 138.8406) (xy 222.063865 138.82687)
			(xy 222.063865 138.81314) (xy 222.063865 138.79941) (xy 222.063865 138.78567) (xy 222.063865 138.77194)
			(xy 222.063865 138.75821) (xy 222.063865 138.74448) (xy 222.063865 138.73075) (xy 222.063865 138.71702)
			(xy 222.063865 138.70328) (xy 222.063865 138.68955) (xy 222.063865 138.67582) (xy 222.063865 138.66209)
			(xy 222.063865 138.64836) (xy 222.063865 138.63463) (xy 222.063865 138.62089) (xy 222.063865 138.60716)
			(xy 222.063865 138.59343) (xy 222.063865 138.5797) (xy 222.063865 138.56597) (xy 222.063865 138.55224)
			(xy 222.063865 138.5385) (xy 222.063865 138.52477) (xy 222.063865 138.51104) (xy 222.063865 138.49731)
			(xy 222.063865 138.48358) (xy 222.063865 138.46984) (xy 222.063865 138.45611) (xy 222.063865 138.44238)
			(xy 222.063865 138.42865) (xy 222.063865 138.41492) (xy 222.063865 138.40118) (xy 222.063865 138.38745)
			(xy 222.063865 138.37372) (xy 222.063865 138.35999) (xy 222.063865 138.34626) (xy 222.063865 138.33253)
			(xy 222.063865 138.31879) (xy 222.063865 138.30506) (xy 222.063865 138.29133) (xy 222.063865 138.2776)
			(xy 222.063865 138.26387) (xy 222.063865 138.25014) (xy 222.063865 138.2364) (xy 222.063865 138.22267)
			(xy 222.063865 138.20894) (xy 222.063865 138.19521) (xy 222.063865 138.18148) (xy 222.063865 138.16775)
			(xy 222.063865 138.15401) (xy 222.063865 138.14028) (xy 222.063865 138.12655) (xy 222.063865 138.11282)
			(xy 222.063865 138.09909) (xy 222.063865 138.08536) (xy 222.063865 138.07162) (xy 222.063865 138.05789)
			(xy 222.063865 138.04416) (xy 222.063865 138.03043) (xy 222.063865 138.0167) (xy 222.063865 138.00296)
			(xy 222.063865 137.98923) (xy 222.063865 137.9755) (xy 222.063865 137.96177) (xy 222.063865 137.94804)
			(xy 222.063865 137.9343) (xy 222.063865 137.92057) (xy 222.063865 137.90684) (xy 222.063865 137.89311)
			(xy 222.063865 137.87938) (xy 222.063865 137.86565) (xy 222.063865 137.85191) (xy 222.063865 137.83818)
			(xy 222.063865 137.82445) (xy 222.063865 137.81072) (xy 222.063865 137.79699) (xy 222.063865 137.78326)
			(xy 222.063865 137.76952) (xy 222.063865 137.75579) (xy 222.050135 137.75579) (xy 222.050135 137.74206)
			(xy 222.050135 137.72833) (xy 222.050135 137.7146) (xy 222.036405 137.7146) (xy 222.036405 137.70087)
			(xy 222.036405 137.68713) (xy 222.022675 137.68713) (xy 222.022675 137.6734) (xy 222.008935 137.6734)
			(xy 222.008935 137.65967) (xy 221.995205 137.65967) (xy 221.995205 137.64594) (xy 221.981475 137.64594)
			(xy 221.981475 137.63221) (xy 221.967745 137.63221) (xy 221.967745 137.61848) (xy 221.954015 137.61848)
			(xy 221.954015 137.60474) (xy 221.940285 137.60474) (xy 221.940285 137.59101) (xy 221.926545 137.59101)
			(xy 221.926545 137.57728) (xy 221.912815 137.57728) (xy 221.912815 137.56355) (xy 221.899085 137.56355)
			(xy 221.899085 137.54982) (xy 221.885355 137.54982) (xy 221.885355 137.53609) (xy 221.871625 137.53609)
			(xy 221.871625 137.52235) (xy 221.857895 137.52235) (xy 221.857895 137.50862) (xy 221.844155 137.50862)
			(xy 221.844155 137.49489) (xy 221.830425 137.49489) (xy 221.830425 137.48116) (xy 221.816695 137.48116)
			(xy 221.816695 137.46743) (xy 221.802965 137.46743) (xy 221.802965 137.45369) (xy 221.789235 137.45369)
			(xy 221.789235 137.43996) (xy 221.775495 137.43996) (xy 221.775495 137.42623) (xy 221.761765 137.42623)
			(xy 221.761765 137.4125) (xy 221.748035 137.4125) (xy 221.748035 137.39877) (xy 221.734305 137.39877)
			(xy 221.734305 137.38503) (xy 221.720575 137.38503) (xy 221.720575 137.3713) (xy 221.706835 137.3713)
			(xy 221.706835 137.35757) (xy 221.693105 137.35757) (xy 221.693105 137.34384) (xy 221.679375 137.34384)
			(xy 221.679375 137.33011) (xy 221.665645 137.33011) (xy 221.665645 137.31638) (xy 222.475815 137.31638)
			(xy 222.475815 137.33011) (xy 222.475815 137.34384) (xy 222.475815 137.35757) (xy 222.475815 137.3713)
			(xy 222.475815 137.38503) (xy 222.475815 137.39877) (xy 222.475815 137.4125) (xy 222.475815 137.42623)
			(xy 222.475815 137.43996) (xy 222.475815 137.45369) (xy 222.475815 137.46743) (xy 222.475815 137.48116)
			(xy 222.475815 137.49489) (xy 222.475815 137.50862) (xy 222.475815 137.52235) (xy 222.475815 137.53609)
			(xy 222.475815 137.54982) (xy 222.475815 137.56355) (xy 222.475815 137.57728) (xy 222.475815 137.59101)
			(xy 222.475815 137.60474) (xy 222.475815 137.61848) (xy 222.475815 137.63221) (xy 222.475815 137.64594)
			(xy 222.475815 137.65967) (xy 222.475815 137.6734) (xy 222.475815 137.68713) (xy 222.475815 137.70087)
			(xy 222.475815 137.7146) (xy 222.475815 137.72833) (xy 222.475815 137.74206) (xy 222.475815 137.75579)
			(xy 222.475815 137.76952) (xy 222.475815 137.78326) (xy 222.475815 137.79699) (xy 222.475815 137.81072)
			(xy 222.475815 137.82445) (xy 222.475815 137.83818) (xy 222.475815 137.85191) (xy 222.475815 137.86565)
			(xy 222.475815 137.87938) (xy 222.475815 137.89311) (xy 222.475815 137.90684) (xy 222.475815 137.92057)
			(xy 222.475815 137.9343) (xy 222.475815 137.94804) (xy 222.475815 137.96177) (xy 222.475815 137.9755)
			(xy 222.475815 137.98923) (xy 222.475815 138.00296) (xy 222.475815 138.0167) (xy 222.475815 138.03043)
			(xy 222.475815 138.04416) (xy 222.475815 138.05789) (xy 222.475815 138.07162) (xy 222.475815 138.08536)
			(xy 222.475815 138.09909) (xy 222.475815 138.11282) (xy 222.475815 138.12655) (xy 222.475815 138.14028)
			(xy 222.475815 138.15401) (xy 222.475815 138.16775) (xy 222.475815 138.18148) (xy 222.475815 138.19521)
			(xy 222.475815 138.20894) (xy 222.475815 138.22267) (xy 222.475815 138.2364) (xy 222.475815 138.25014)
			(xy 222.475815 138.26387) (xy 222.475815 138.2776) (xy 222.475815 138.29133) (xy 222.475815 138.30506)
			(xy 222.475815 138.31879) (xy 222.475815 138.33253) (xy 222.475815 138.34626) (xy 222.475815 138.35999)
			(xy 222.475815 138.37372) (xy 222.475815 138.38745) (xy 222.475815 138.40118) (xy 222.475815 138.41492)
			(xy 222.475815 138.42865) (xy 222.475815 138.44238) (xy 222.475815 138.45611) (xy 222.475815 138.46984)
			(xy 222.475815 138.48358) (xy 222.475815 138.49731) (xy 222.475815 138.51104) (xy 222.475815 138.52477)
			(xy 222.475815 138.5385) (xy 222.475815 138.55224) (xy 222.475815 138.56597) (xy 222.475815 138.5797)
			(xy 222.475815 138.59343) (xy 222.475815 138.60716) (xy 222.475815 138.62089) (xy 222.475815 138.63463)
			(xy 222.475815 138.64836) (xy 222.475815 138.66209) (xy 222.475815 138.67582) (xy 222.475815 138.68955)
			(xy 222.475815 138.70328) (xy 222.475815 138.71702) (xy 222.475815 138.73075) (xy 222.475815 138.74448)
			(xy 222.475815 138.75821) (xy 222.475815 138.77194) (xy 222.475815 138.78567) (xy 222.475815 138.79941)
			(xy 222.475815 138.81314) (xy 222.475815 138.82687) (xy 222.475815 138.8406) (xy 222.475815 138.85433)
			(xy 222.475815 138.86806) (xy 222.475815 138.8818) (xy 222.475815 138.89553) (xy 222.475815 138.90926)
			(xy 222.475815 138.92299) (xy 222.475815 138.93672) (xy 222.475815 138.95045) (xy 222.475815 138.96419)
			(xy 222.475815 138.97792) (xy 222.475815 138.99165) (xy 222.475815 139.00538) (xy 222.475815 139.01911)
			(xy 222.475815 139.03285) (xy 222.475815 139.04658) (xy 222.475815 139.06031) (xy 222.475815 139.07404)
			(xy 222.475815 139.08777) (xy 222.475815 139.10151) (xy 222.475815 139.11524) (xy 222.475815 139.12897)
			(xy 222.475815 139.1427) (xy 222.475815 139.15643) (xy 222.475815 139.17016) (xy 222.475815 139.1839)
			(xy 222.475815 139.19763) (xy 222.475815 139.21136) (xy 222.475815 139.22509) (xy 222.475815 139.23882)
			(xy 222.475815 139.25255) (xy 222.475815 139.26629) (xy 222.475815 139.28002) (xy 222.475815 139.29375)
			(xy 222.475815 139.30748) (xy 222.475815 139.32121) (xy 222.475815 139.33494) (xy 222.475815 139.34868)
			(xy 222.475815 139.36241) (xy 222.475815 139.37614) (xy 222.475815 139.38987) (xy 222.475815 139.4036)
			(xy 222.475815 139.41733) (xy 222.475815 139.43107) (xy 222.475815 139.4448) (xy 222.475815 139.45853)
			(xy 222.475815 139.47226) (xy 222.475815 139.48599) (xy 222.475815 139.49972) (xy 222.475815 139.51346)
			(xy 222.475815 139.52719) (xy 222.475815 139.54092) (xy 222.475815 139.55465) (xy 222.475815 139.56838)
			(xy 222.475815 139.58212) (xy 222.475815 139.59585) (xy 222.475815 139.60958) (xy 222.475815 139.62331)
			(xy 222.475815 139.63704) (xy 222.475815 139.65078) (xy 222.475815 139.66451) (xy 222.475815 139.67824)
			(xy 222.475815 139.69197) (xy 222.475815 139.7057) (xy 222.475815 139.71943) (xy 222.475815 139.73317)
			(xy 222.475815 139.7469) (xy 222.475815 139.76063) (xy 222.475815 139.77436) (xy 222.475815 139.78809)
			(xy 222.475815 139.80182) (xy 222.475815 139.81556) (xy 222.475815 139.82929) (xy 222.475815 139.84302)
			(xy 222.475815 139.85675) (xy 222.475815 139.87048) (xy 222.475815 139.88421) (xy 222.475815 139.89795)
			(xy 222.475815 139.91168) (xy 222.475815 139.92541) (xy 222.475815 139.93914) (xy 222.475815 139.95287)
			(xy 222.475815 139.9666) (xy 222.475815 139.98034) (xy 222.475815 139.99407) (xy 222.475815 140.0078)
			(xy 222.475815 140.02153) (xy 222.475815 140.03526) (xy 222.475815 140.04899) (xy 222.475815 140.06273)
			(xy 222.475815 140.07646) (xy 222.475815 140.09019) (xy 222.475815 140.10392) (xy 222.475815 140.11765)
			(xy 222.475815 140.13139) (xy 222.475815 140.14512) (xy 222.475815 140.15885) (xy 222.475815 140.17258)
			(xy 222.475815 140.18631) (xy 222.475815 140.20005) (xy 222.475815 140.21378) (xy 222.489555 140.21378)
			(xy 222.489555 140.22751) (xy 222.503285 140.22751) (xy 222.503285 140.24124) (xy 222.517015 140.24124)
			(xy 222.517015 140.25497) (xy 224.480655 140.25497) (xy 224.480655 140.24124) (xy 224.535585 140.24124)
			(xy 224.535585 140.22751) (xy 224.563045 140.22751) (xy 224.563045 140.21378) (xy 224.576775 140.21378)
			(xy 224.576775 140.20005) (xy 224.590505 140.20005) (xy 224.590505 140.18631) (xy 224.604245 140.18631)
			(xy 224.604245 140.17258) (xy 224.617975 140.17258) (xy 224.617975 140.15885) (xy 224.631705 140.15885)
			(xy 224.631705 140.14512) (xy 224.645435 140.14512) (xy 224.645435 140.13139) (xy 224.659165 140.13139)
			(xy 224.659165 140.11765) (xy 224.672895 140.11765) (xy 224.672895 140.10392) (xy 224.686635 140.10392)
			(xy 224.686635 140.09019) (xy 224.700365 140.09019) (xy 224.700365 140.07646) (xy 224.714095 140.07646)
			(xy 224.714095 140.06273) (xy 224.727825 140.06273) (xy 224.727825 140.04899) (xy 224.741555 140.04899)
			(xy 224.741555 140.03526) (xy 224.755285 140.03526) (xy 224.755285 140.02153) (xy 224.769025 140.02153)
			(xy 224.769025 140.0078) (xy 224.782755 140.0078) (xy 224.782755 139.99407) (xy 224.796485 139.99407)
			(xy 224.796485 139.98034) (xy 224.810215 139.98034) (xy 224.810215 139.9666) (xy 224.823945 139.9666)
			(xy 224.823945 139.95287) (xy 224.837675 139.95287) (xy 224.837675 139.93914) (xy 224.851415 139.93914)
			(xy 224.851415 139.92541) (xy 224.865145 139.92541) (xy 224.865145 139.91168) (xy 224.878875 139.91168)
			(xy 224.878875 139.89795) (xy 224.892605 139.89795) (xy 224.892605 139.88421) (xy 224.906335 139.88421)
			(xy 224.906335 139.87048) (xy 224.920065 139.87048) (xy 224.920065 139.85675) (xy 224.933805 139.85675)
			(xy 224.933805 139.84302) (xy 224.947535 139.84302) (xy 224.947535 139.82929) (xy 224.961265 139.82929)
			(xy 224.961265 139.81556) (xy 224.961265 139.80182) (xy 224.961265 139.78809) (xy 224.974995 139.78809)
			(xy 224.974995 139.77436) (xy 224.974995 139.76063) (xy 224.974995 139.7469) (xy 224.974995 139.73317)
			(xy 224.988725 139.73317) (xy 224.988725 139.71943) (xy 224.988725 139.7057) (xy 224.988725 139.69197)
			(xy 224.988725 139.67824) (xy 224.988725 139.66451) (xy 224.988725 139.65078) (xy 224.988725 139.63704)
			(xy 224.988725 139.62331) (xy 224.988725 139.60958) (xy 224.988725 139.59585) (xy 224.988725 139.58212)
			(xy 224.988725 139.56838) (xy 224.988725 139.55465) (xy 224.988725 139.54092) (xy 224.988725 139.52719)
			(xy 224.988725 139.51346) (xy 224.988725 139.49972) (xy 224.988725 139.48599) (xy 224.988725 139.47226)
			(xy 224.988725 139.45853) (xy 224.988725 139.4448) (xy 224.988725 139.43107) (xy 224.988725 139.41733)
			(xy 224.988725 139.4036) (xy 224.988725 139.38987) (xy 224.988725 139.37614) (xy 224.988725 139.36241)
			(xy 224.988725 139.34868) (xy 224.988725 139.33494) (xy 224.988725 139.32121) (xy 224.988725 139.30748)
			(xy 224.988725 139.29375) (xy 224.988725 139.28002) (xy 224.988725 139.26629) (xy 224.988725 139.25255)
			(xy 224.988725 139.23882) (xy 224.988725 139.22509) (xy 224.988725 139.21136) (xy 224.988725 139.19763)
			(xy 224.988725 139.1839) (xy 224.988725 139.17016) (xy 224.988725 139.15643) (xy 224.988725 139.1427)
			(xy 224.988725 139.12897) (xy 224.988725 139.11524) (xy 224.988725 139.10151) (xy 224.988725 139.08777)
			(xy 224.988725 139.07404) (xy 224.988725 139.06031) (xy 224.988725 139.04658) (xy 224.988725 139.03285)
			(xy 224.988725 139.01911) (xy 224.988725 139.00538) (xy 224.988725 138.99165) (xy 224.988725 138.97792)
			(xy 224.988725 138.96419) (xy 224.988725 138.95045) (xy 224.988725 138.93672) (xy 224.988725 138.92299)
			(xy 224.988725 138.90926) (xy 224.988725 138.89553) (xy 224.988725 138.8818) (xy 224.988725 138.86806)
			(xy 224.988725 138.85433) (xy 224.988725 138.8406) (xy 224.988725 138.82687) (xy 224.988725 138.81314)
			(xy 224.988725 138.79941) (xy 224.988725 138.78567) (xy 224.988725 138.77194) (xy 224.988725 138.75821)
			(xy 224.988725 138.74448) (xy 224.988725 138.73075) (xy 224.988725 138.71702) (xy 224.988725 138.70328)
			(xy 224.988725 138.68955) (xy 224.988725 138.67582) (xy 224.988725 138.66209) (xy 224.988725 138.64836)
			(xy 224.988725 138.63463) (xy 224.988725 138.62089) (xy 224.988725 138.60716) (xy 224.988725 138.59343)
			(xy 224.988725 138.5797) (xy 224.988725 138.56597) (xy 224.988725 138.55224) (xy 224.988725 138.5385)
			(xy 224.988725 138.52477) (xy 224.988725 138.51104) (xy 224.988725 138.49731) (xy 224.988725 138.48358)
			(xy 224.988725 138.46984) (xy 224.988725 138.45611) (xy 224.988725 138.44238) (xy 224.988725 138.42865)
			(xy 224.988725 138.41492) (xy 224.988725 138.40118) (xy 224.988725 138.38745) (xy 224.988725 138.37372)
			(xy 224.988725 138.35999) (xy 224.988725 138.34626) (xy 224.988725 138.33253) (xy 224.988725 138.31879)
			(xy 224.988725 138.30506) (xy 224.988725 138.29133) (xy 224.988725 138.2776) (xy 224.988725 138.26387)
			(xy 224.988725 138.25014) (xy 224.988725 138.2364) (xy 224.988725 138.22267) (xy 224.988725 138.20894)
			(xy 224.988725 138.19521) (xy 224.988725 138.18148) (xy 224.988725 138.16775) (xy 224.988725 138.15401)
			(xy 224.988725 138.14028) (xy 224.988725 138.12655) (xy 224.988725 138.11282) (xy 224.988725 138.09909)
			(xy 224.988725 138.08536) (xy 224.988725 138.07162) (xy 224.988725 138.05789) (xy 224.988725 138.04416)
			(xy 224.988725 138.03043) (xy 224.988725 138.0167) (xy 224.988725 138.00296) (xy 224.988725 137.98923)
			(xy 224.988725 137.9755) (xy 224.988725 137.96177) (xy 224.988725 137.94804) (xy 224.988725 137.9343)
			(xy 224.988725 137.92057) (xy 224.988725 137.90684) (xy 224.988725 137.89311) (xy 224.988725 137.87938)
			(xy 224.988725 137.86565) (xy 224.988725 137.85191) (xy 224.988725 137.83818) (xy 224.988725 137.82445)
			(xy 224.988725 137.81072) (xy 224.988725 137.79699) (xy 224.988725 137.78326) (xy 224.974995 137.78326)
			(xy 224.974995 137.76952) (xy 224.974995 137.75579) (xy 224.974995 137.74206) (xy 224.974995 137.72833)
			(xy 224.961265 137.72833) (xy 224.961265 137.7146) (xy 224.961265 137.70087) (xy 224.947535 137.70087)
			(xy 224.947535 137.68713) (xy 224.933805 137.68713) (xy 224.933805 137.6734) (xy 224.920065 137.6734)
			(xy 224.920065 137.65967) (xy 224.906335 137.65967) (xy 224.906335 137.64594) (xy 224.892605 137.64594)
			(xy 224.892605 137.63221) (xy 224.878875 137.63221) (xy 224.878875 137.61848) (xy 224.865145 137.61848)
			(xy 224.865145 137.60474) (xy 224.851415 137.60474) (xy 224.851415 137.59101) (xy 224.837675 137.59101)
			(xy 224.837675 137.57728) (xy 224.823945 137.57728) (xy 224.823945 137.56355) (xy 224.810215 137.56355)
			(xy 224.810215 137.54982) (xy 224.796485 137.54982) (xy 224.796485 137.53609) (xy 224.782755 137.53609)
			(xy 224.782755 137.52235) (xy 224.769025 137.52235) (xy 224.769025 137.50862) (xy 224.755285 137.50862)
			(xy 224.755285 137.49489) (xy 224.741555 137.49489) (xy 224.741555 137.48116) (xy 224.727825 137.48116)
			(xy 224.727825 137.46743) (xy 224.714095 137.46743) (xy 224.714095 137.45369) (xy 224.700365 137.45369)
			(xy 224.700365 137.43996) (xy 224.686635 137.43996) (xy 224.686635 137.42623) (xy 224.672895 137.42623)
			(xy 224.672895 137.4125) (xy 224.659165 137.4125) (xy 224.659165 137.39877) (xy 224.645435 137.39877)
			(xy 224.645435 137.38503) (xy 224.631705 137.38503) (xy 224.631705 137.3713) (xy 224.617975 137.3713)
			(xy 224.617975 137.35757) (xy 224.604245 137.35757) (xy 224.604245 137.34384) (xy 224.590505 137.34384)
			(xy 224.590505 137.33011) (xy 224.576775 137.33011) (xy 224.576775 137.31638) (xy 224.563045 137.31638)
			(xy 224.563045 137.30264) (xy 224.549315 137.30264) (xy 224.549315 137.28891) (xy 224.508115 137.28891)
			(xy 224.508115 137.27518) (xy 224.439455 137.27518) (xy 224.439455 137.26145) (xy 222.544475 137.26145)
			(xy 222.544475 137.27518) (xy 222.517015 137.27518) (xy 222.517015 137.28891) (xy 222.503285 137.28891)
			(xy 222.503285 137.30264) (xy 222.489555 137.30264) (xy 222.489555 137.31638) (xy 222.475815 137.31638)
			(xy 221.665645 137.31638) (xy 221.651915 137.31638) (xy 221.651915 137.30264) (xy 221.624445 137.30264)
			(xy 221.624445 137.28891) (xy 221.583255 137.28891) (xy 221.583255 137.27518) (xy 221.514595 137.27518)
			(xy 221.514595 137.26145) (xy 219.619615 137.26145) (xy 219.619615 137.27518) (xy 219.592145 137.27518)
			(xy 219.592145 137.28891) (xy 219.578415 137.28891) (xy 219.578415 137.30264) (xy 219.564685 137.30264)
			(xy 219.564685 137.31638) (xy 219.564685 137.33011) (xy 219.564685 137.34384) (xy 219.550955 137.34384)
			(xy 218.891835 137.34384) (xy 218.878095 137.34384) (xy 218.878095 137.33011) (xy 218.864365 137.33011)
			(xy 218.864365 137.31638) (xy 218.850635 137.31638) (xy 218.850635 137.30264) (xy 218.823175 137.30264)
			(xy 218.823175 137.28891) (xy 218.795705 137.28891) (xy 218.795705 137.27518) (xy 218.740785 137.27518)
			(xy 218.740785 137.26145) (xy 218.548535 137.26145) (xy 218.548535 137.27518) (xy 218.534805 137.27518)
			(xy 218.534805 137.28891) (xy 218.521075 137.28891) (xy 218.521075 137.30264) (xy 218.507345 137.30264)
			(xy 218.507345 137.31638) (xy 218.493615 137.31638) (xy 218.493615 137.33011) (xy 218.479875 137.33011)
			(xy 218.479875 137.34384) (xy 218.466145 137.34384) (xy 218.466145 137.35757) (xy 218.452415 137.35757)
			(xy 218.452415 137.3713) (xy 218.438685 137.3713) (xy 218.438685 137.38503) (xy 218.424955 137.38503)
			(xy 218.424955 137.39877) (xy 218.411225 137.39877) (xy 218.411225 137.4125) (xy 218.397485 137.4125)
			(xy 218.397485 137.42623) (xy 218.383755 137.42623) (xy 218.383755 137.43996) (xy 218.370025 137.43996)
			(xy 218.370025 137.45369) (xy 218.356295 137.45369) (xy 218.356295 137.46743) (xy 218.342565 137.46743)
			(xy 218.342565 137.48116) (xy 218.328835 137.48116) (xy 218.328835 137.49489) (xy 218.315095 137.49489)
			(xy 218.315095 137.50862) (xy 218.301365 137.50862) (xy 218.301365 137.52235) (xy 218.287635 137.52235)
			(xy 218.287635 137.53609) (xy 218.273905 137.53609) (xy 218.273905 137.54982) (xy 218.260175 137.54982)
			(xy 218.260175 137.56355) (xy 218.246445 137.56355) (xy 218.246445 137.57728) (xy 218.232705 137.57728)
			(xy 218.232705 137.59101) (xy 218.218975 137.59101) (xy 218.218975 137.60474) (xy 218.205245 137.60474)
			(xy 218.205245 137.61848) (xy 218.191515 137.61848) (xy 218.191515 137.63221) (xy 218.177785 137.63221)
			(xy 218.177785 137.64594) (xy 218.164045 137.64594) (xy 218.164045 137.65967) (xy 218.150315 137.65967)
			(xy 218.150315 137.6734) (xy 218.136585 137.6734) (xy 218.136585 137.68713) (xy 218.122855 137.68713)
			(xy 218.122855 137.70087) (xy 218.109125 137.70087) (xy 218.109125 137.7146) (xy 218.095385 137.7146)
			(xy 218.095385 137.72833) (xy 218.081655 137.72833) (xy 218.081655 137.74206) (xy 218.067925 137.74206)
			(xy 218.067925 137.75579) (xy 218.054195 137.75579) (xy 218.054195 137.76952) (xy 218.040465 137.76952)
			(xy 218.040465 137.78326) (xy 218.026735 137.78326) (xy 218.026735 137.79699) (xy 218.012995 137.79699)
			(xy 218.012995 137.81072) (xy 217.999265 137.81072) (xy 217.999265 137.82445) (xy 217.985535 137.82445)
			(xy 217.985535 137.83818) (xy 217.971805 137.83818) (xy 217.971805 137.85191) (xy 217.958075 137.85191)
			(xy 217.958075 137.86565) (xy 217.944345 137.86565) (xy 217.944345 137.87938) (xy 217.930605 137.87938)
			(xy 217.930605 137.89311) (xy 217.916875 137.89311) (xy 217.916875 137.90684) (xy 217.903145 137.90684)
			(xy 217.903145 137.92057) (xy 217.889415 137.92057) (xy 217.889415 137.9343) (xy 218.507345 137.9343)
			(xy 218.507345 137.94804) (xy 218.507345 137.96177) (xy 218.507345 137.9755) (xy 218.507345 137.98923)
			(xy 218.507345 138.00296) (xy 218.507345 138.0167) (xy 218.507345 138.03043) (xy 218.507345 138.04416)
			(xy 218.507345 138.05789) (xy 218.507345 138.07162) (xy 218.507345 138.08536) (xy 218.507345 138.09909)
			(xy 218.507345 138.11282) (xy 218.507345 138.12655) (xy 218.507345 138.14028) (xy 218.507345 138.15401)
			(xy 218.507345 138.16775) (xy 218.507345 138.18148) (xy 218.507345 138.19521) (xy 218.507345 138.20894)
			(xy 218.507345 138.22267) (xy 218.507345 138.2364) (xy 218.507345 138.25014) (xy 218.507345 138.26387)
			(xy 218.507345 138.2776) (xy 218.507345 138.29133) (xy 218.507345 138.30506) (xy 218.507345 138.31879)
			(xy 218.507345 138.33253) (xy 218.507345 138.34626) (xy 218.507345 138.35999) (xy 218.507345 138.37372)
			(xy 218.507345 138.38745) (xy 218.507345 138.40118) (xy 218.507345 138.41492) (xy 218.507345 138.42865)
			(xy 218.507345 138.44238) (xy 218.507345 138.45611) (xy 218.507345 138.46984) (xy 218.507345 138.48358)
			(xy 218.507345 138.49731) (xy 218.507345 138.51104) (xy 218.507345 138.52477) (xy 218.507345 138.5385)
			(xy 218.507345 138.55224) (xy 218.507345 138.56597) (xy 218.507345 138.5797) (xy 218.507345 138.59343)
			(xy 218.507345 138.60716) (xy 218.507345 138.62089) (xy 218.507345 138.63463) (xy 218.507345 138.64836)
			(xy 218.507345 138.66209) (xy 218.507345 138.67582) (xy 218.507345 138.68955) (xy 217.504925 138.68955)
			(xy 217.504925 138.67582) (xy 217.504925 138.66209) (xy 217.504925 138.64836) (xy 217.504925 138.63463)
			(xy 217.504925 138.62089) (xy 217.504925 138.60716) (xy 217.504925 138.59343) (xy 217.504925 138.5797)
			(xy 217.504925 138.56597) (xy 217.504925 138.55224) (xy 217.504925 138.5385) (xy 217.504925 138.52477)
			(xy 217.504925 138.51104) (xy 217.504925 138.49731) (xy 217.504925 138.48358) (xy 217.504925 138.46984)
			(xy 217.504925 138.45611) (xy 217.504925 138.44238) (xy 217.504925 138.42865) (xy 217.504925 138.41492)
			(xy 217.504925 138.40118) (xy 217.504925 138.38745) (xy 217.491195 138.38745) (xy 217.491195 138.40118)
			(xy 217.477465 138.40118) (xy 217.477465 138.41492) (xy 217.463725 138.41492) (xy 217.463725 138.42865)
			(xy 217.449995 138.42865) (xy 217.449995 138.44238) (xy 217.436265 138.44238) (xy 217.436265 138.45611)
			(xy 217.422535 138.45611) (xy 217.422535 138.46984) (xy 217.408805 138.46984) (xy 217.408805 138.48358)
			(xy 217.395075 138.48358) (xy 217.395075 138.49731) (xy 217.381335 138.49731) (xy 217.381335 138.51104)
			(xy 217.367605 138.51104) (xy 217.367605 138.52477) (xy 217.353875 138.52477) (xy 217.353875 138.5385)
			(xy 217.340145 138.5385) (xy 217.340145 138.55224) (xy 217.326415 138.55224) (xy 217.326415 138.56597)
			(xy 217.312685 138.56597) (xy 217.312685 138.5797) (xy 217.298945 138.5797) (xy 217.298945 138.59343)
			(xy 217.285215 138.59343) (xy 217.285215 138.60716) (xy 217.271485 138.60716) (xy 217.271485 138.62089)
			(xy 217.257755 138.62089) (xy 217.257755 138.63463) (xy 217.244025 138.63463) (xy 217.244025 138.64836)
			(xy 217.230295 138.64836) (xy 217.230295 138.66209) (xy 217.216555 138.66209) (xy 217.216555 138.67582)
			(xy 217.202825 138.67582) (xy 217.202825 138.68955) (xy 217.189095 138.68955) (xy 217.189095 138.70328)
			(xy 217.175365 138.70328) (xy 217.175365 138.71702) (xy 217.161635 138.71702) (xy 217.161635 138.73075)
			(xy 217.147905 138.73075) (xy 217.147905 138.74448) (xy 217.134165 138.74448) (xy 217.134165 138.75821)
			(xy 217.120435 138.75821) (xy 217.120435 138.77194) (xy 217.106705 138.77194) (xy 217.106705 138.78567)
			(xy 217.092975 138.78567) (xy 217.092975 138.79941) (xy 217.079245 138.79941) (xy 217.079245 138.81314)
			(xy 217.065505 138.81314) (xy 217.065505 138.82687) (xy 217.051775 138.82687) (xy 217.051775 138.8406)
			(xy 217.038045 138.8406) (xy 217.038045 138.85433) (xy 217.024315 138.85433) (xy 217.024315 138.86806)
			(xy 217.010585 138.86806) (xy 217.010585 138.8818) (xy 216.996845 138.8818) (xy 216.996845 138.89553)
			(xy 216.983115 138.89553) (xy 216.983115 138.90926) (xy 216.969385 138.90926) (xy 216.969385 138.92299)
			(xy 216.955655 138.92299) (xy 216.955655 138.93672) (xy 216.941925 138.93672) (xy 216.941925 138.95045)
			(xy 216.928195 138.95045) (xy 216.928195 138.96419) (xy 216.914455 138.96419) (xy 216.914455 138.97792)
			(xy 216.900725 138.97792) (xy 216.900725 138.99165) (xy 216.886995 138.99165) (xy 216.886995 139.00538)
			(xy 216.873265 139.00538) (xy 216.873265 139.01911) (xy 216.859535 139.01911) (xy 216.859535 139.03285)
			(xy 216.832065 139.03285) (xy 216.832065 139.04658) (xy 216.818335 139.04658) (xy 216.818335 139.06031)
			(xy 216.804605 139.06031) (xy 216.804605 139.07404) (xy 216.790875 139.07404) (xy 216.790875 139.08777)
			(xy 216.777145 139.08777) (xy 216.777145 139.10151) (xy 216.763415 139.10151) (xy 216.763415 139.11524)
			(xy 216.749675 139.11524) (xy 216.392655 139.11524) (xy 216.392655 139.10151) (xy 216.406385 139.10151)
			(xy 216.406385 139.08777) (xy 216.420115 139.08777) (xy 216.420115 139.07404) (xy 216.433845 139.07404)
			(xy 216.433845 139.06031) (xy 216.447575 139.06031) (xy 216.447575 139.04658) (xy 216.461315 139.04658)
			(xy 216.461315 139.03285) (xy 216.475045 139.03285) (xy 216.475045 139.01911) (xy 216.488775 139.01911)
			(xy 216.488775 139.00538) (xy 216.502505 139.00538) (xy 216.502505 138.99165) (xy 216.516235 138.99165)
			(xy 216.516235 138.97792) (xy 216.529965 138.97792) (xy 216.529965 138.96419) (xy 216.543705 138.96419)
			(xy 216.543705 138.95045) (xy 216.557435 138.95045) (xy 216.557435 138.93672) (xy 216.571165 138.93672)
			(xy 216.571165 138.92299) (xy 216.584895 138.92299) (xy 216.584895 138.90926) (xy 216.598625 138.90926)
			(xy 216.598625 138.89553) (xy 216.626095 138.89553) (xy 216.626095 138.8818) (xy 216.639825 138.8818)
			(xy 216.639825 138.86806) (xy 216.653555 138.86806) (xy 216.653555 138.85433) (xy 216.667285 138.85433)
			(xy 216.667285 138.8406) (xy 216.681025 138.8406) (xy 216.681025 138.82687) (xy 216.694755 138.82687)
			(xy 216.694755 138.81314) (xy 216.708485 138.81314) (xy 216.708485 138.79941) (xy 216.722215 138.79941)
			(xy 216.722215 138.78567) (xy 216.735945 138.78567) (xy 216.735945 138.77194) (xy 216.749675 138.77194)
			(xy 216.749675 138.75821) (xy 216.763415 138.75821) (xy 216.763415 138.74448) (xy 216.777145 138.74448)
			(xy 216.777145 138.73075) (xy 216.790875 138.73075) (xy 216.790875 138.71702) (xy 216.804605 138.71702)
			(xy 216.804605 138.70328) (xy 216.818335 138.70328) (xy 216.818335 138.68955) (xy 216.832065 138.68955)
			(xy 216.832065 138.67582) (xy 216.845805 138.67582) (xy 216.845805 138.66209) (xy 216.859535 138.66209)
			(xy 216.859535 138.64836) (xy 216.873265 138.64836) (xy 216.873265 138.63463) (xy 216.886995 138.63463)
			(xy 216.886995 138.62089) (xy 216.900725 138.62089) (xy 216.900725 138.60716) (xy 216.914455 138.60716)
			(xy 216.914455 138.59343) (xy 216.928195 138.59343) (xy 216.928195 138.5797) (xy 216.941925 138.5797)
			(xy 216.941925 138.56597) (xy 216.955655 138.56597) (xy 216.955655 138.55224) (xy 216.969385 138.55224)
			(xy 216.969385 138.5385) (xy 216.983115 138.5385) (xy 216.983115 138.52477) (xy 216.996845 138.52477)
			(xy 216.996845 138.51104) (xy 217.010585 138.51104) (xy 217.010585 138.49731) (xy 217.024315 138.49731)
			(xy 217.024315 138.48358) (xy 217.038045 138.48358) (xy 217.038045 138.46984) (xy 217.051775 138.46984)
			(xy 217.051775 138.45611) (xy 217.065505 138.45611) (xy 217.065505 138.44238) (xy 217.079245 138.44238)
			(xy 217.079245 138.42865) (xy 217.092975 138.42865) (xy 217.092975 138.41492) (xy 217.106705 138.41492)
			(xy 217.106705 138.40118) (xy 217.120435 138.40118) (xy 217.120435 138.38745) (xy 217.134165 138.38745)
			(xy 217.134165 138.37372) (xy 217.147905 138.37372) (xy 217.147905 138.35999) (xy 217.161635 138.35999)
			(xy 217.161635 138.34626) (xy 217.175365 138.34626) (xy 217.175365 138.33253) (xy 217.189095 138.33253)
			(xy 217.189095 138.31879) (xy 217.202825 138.31879) (xy 217.202825 138.30506) (xy 217.216555 138.30506)
			(xy 217.216555 138.29133) (xy 217.230295 138.29133) (xy 217.230295 138.2776) (xy 217.244025 138.2776)
			(xy 217.244025 138.26387) (xy 217.257755 138.26387) (xy 217.257755 138.25014) (xy 217.271485 138.25014)
			(xy 217.271485 138.2364) (xy 217.285215 138.2364) (xy 217.285215 138.22267) (xy 217.298945 138.22267)
			(xy 217.298945 138.20894) (xy 217.312685 138.20894) (xy 217.312685 138.19521) (xy 217.326415 138.19521)
			(xy 217.326415 138.18148) (xy 217.340145 138.18148) (xy 217.340145 138.16775) (xy 217.353875 138.16775)
			(xy 217.353875 138.15401) (xy 217.367605 138.15401) (xy 217.367605 138.14028) (xy 217.381335 138.14028)
			(xy 217.381335 138.12655) (xy 217.395075 138.12655) (xy 217.395075 138.11282) (xy 217.408805 138.11282)
			(xy 217.408805 138.09909) (xy 217.422535 138.09909) (xy 217.422535 138.08536) (xy 217.436265 138.08536)
			(xy 217.436265 138.07162) (xy 217.449995 138.07162) (xy 217.449995 138.05789) (xy 217.463725 138.05789)
			(xy 217.463725 138.04416) (xy 217.477465 138.04416) (xy 217.477465 138.03043) (xy 217.491195 138.03043)
			(xy 217.491195 138.0167) (xy 217.504925 138.0167) (xy 217.504925 138.00296) (xy 217.518655 138.00296)
			(xy 217.518655 137.98923) (xy 217.532385 137.98923) (xy 217.532385 137.9755) (xy 217.546115 137.9755)
			(xy 217.546115 137.96177) (xy 217.559855 137.96177) (xy 217.559855 137.94804) (xy 217.573585 137.94804)
			(xy 217.573585 137.9343) (xy 217.587315 137.9343) (xy 217.587315 137.92057) (xy 217.601045 137.92057)
			(xy 217.601045 137.90684) (xy 217.614775 137.90684) (xy 217.614775 137.89311) (xy 217.628515 137.89311)
			(xy 217.628515 137.87938) (xy 217.642245 137.87938) (xy 217.642245 137.86565) (xy 217.655975 137.86565)
			(xy 217.655975 137.85191) (xy 217.669705 137.85191) (xy 217.669705 137.83818) (xy 217.683435 137.83818)
			(xy 217.683435 137.82445) (xy 217.697175 137.82445) (xy 217.697175 137.81072) (xy 217.710905 137.81072)
			(xy 217.710905 137.79699) (xy 217.724635 137.79699) (xy 217.724635 137.78326) (xy 217.738365 137.78326)
			(xy 217.738365 137.76952) (xy 217.752095 137.76952) (xy 217.752095 137.75579) (xy 217.765825 137.75579)
			(xy 217.765825 137.74206) (xy 217.793295 137.74206) (xy 217.793295 137.72833) (xy 217.807025 137.72833)
			(xy 217.807025 137.7146) (xy 217.820755 137.7146) (xy 217.820755 137.70087) (xy 217.834485 137.70087)
			(xy 217.834485 137.68713) (xy 217.848215 137.68713) (xy 217.848215 137.6734) (xy 217.861955 137.6734)
			(xy 217.861955 137.65967) (xy 217.875685 137.65967) (xy 217.875685 137.64594) (xy 217.889415 137.64594)
			(xy 217.889415 137.63221) (xy 217.903145 137.63221) (xy 217.903145 137.61848) (xy 217.916875 137.61848)
			(xy 217.916875 137.60474) (xy 217.930605 137.60474) (xy 217.930605 137.59101) (xy 217.944345 137.59101)
			(xy 217.944345 137.57728) (xy 217.958075 137.57728) (xy 217.958075 137.56355) (xy 217.971805 137.56355)
			(xy 217.971805 137.54982) (xy 217.985535 137.54982) (xy 217.985535 137.53609) (xy 217.999265 137.53609)
			(xy 217.999265 137.52235) (xy 218.012995 137.52235) (xy 218.012995 137.50862) (xy 218.026735 137.50862)
			(xy 218.026735 137.49489) (xy 218.040465 137.49489) (xy 218.040465 137.48116) (xy 218.054195 137.48116)
			(xy 218.054195 137.46743) (xy 218.067925 137.46743) (xy 218.067925 137.45369) (xy 218.081655 137.45369)
			(xy 218.081655 137.43996) (xy 218.095385 137.43996) (xy 218.095385 137.42623) (xy 218.109125 137.42623)
			(xy 218.109125 137.4125) (xy 218.122855 137.4125) (xy 218.122855 137.39877) (xy 218.136585 137.39877)
			(xy 218.136585 137.38503) (xy 218.150315 137.38503) (xy 218.150315 137.3713) (xy 218.164045 137.3713)
			(xy 218.164045 137.35757) (xy 218.177785 137.35757) (xy 218.177785 137.34384) (xy 218.191515 137.34384)
			(xy 218.191515 137.33011) (xy 218.205245 137.33011) (xy 218.205245 137.31638) (xy 218.205245 137.30264)
			(xy 218.218975 137.30264) (xy 218.218975 137.28891) (xy 218.232705 137.28891) (xy 218.232705 137.27518)
			(xy 218.232705 137.26145) (xy 218.246445 137.26145) (xy 218.246445 137.24772) (xy 218.246445 137.23399)
			(xy 218.260175 137.23399) (xy 218.260175 137.22025) (xy 218.260175 137.20652) (xy 218.273905 137.20652)
			(xy 218.273905 137.19279) (xy 218.273905 137.17906) (xy 218.273905 137.16533) (xy 218.273905 137.1516)
			(xy 218.287635 137.1516) (xy 218.287635 137.13786) (xy 218.287635 137.12413) (xy 218.287635 137.1104)
			(xy 218.287635 137.09667) (xy 218.287635 137.08294) (xy 218.287635 137.06921) (xy 218.287635 137.05547)
			(xy 218.287635 137.04174) (xy 218.287635 137.02801) (xy 218.287635 137.01428) (xy 218.287635 137.00055)
			(xy 218.287635 136.98682) (xy 218.287635 136.97308) (xy 218.287635 136.95935) (xy 218.287635 136.94562)
			(xy 218.287635 136.93189) (xy 218.287635 136.91816) (xy 218.287635 136.90442) (xy 218.287635 136.89069)
			(xy 218.287635 136.87696) (xy 218.287635 136.86323) (xy 218.287635 136.8495) (xy 218.287635 136.83576)
			(xy 218.287635 136.82203) (xy 218.287635 136.8083) (xy 218.287635 136.79457) (xy 218.287635 136.78084)
			(xy 218.287635 136.76711) (xy 218.287635 136.75337) (xy 218.287635 136.73964) (xy 218.287635 136.72591)
			(xy 218.287635 136.71218) (xy 218.287635 136.69845) (xy 218.287635 136.68472) (xy 218.287635 136.67098)
			(xy 218.287635 136.65725) (xy 218.287635 136.64352) (xy 218.287635 136.62979) (xy 218.287635 136.61606)
			(xy 218.287635 136.60233) (xy 218.287635 136.58859) (xy 218.287635 136.57486) (xy 218.287635 136.56113)
			(xy 218.287635 136.5474) (xy 218.287635 136.53367) (xy 218.287635 136.51994) (xy 218.287635 136.5062)
			(xy 218.287635 136.49247) (xy 218.287635 136.47874) (xy 218.287635 136.46501) (xy 218.287635 136.45128)
			(xy 218.287635 136.43755) (xy 218.287635 136.42381) (xy 218.287635 136.41008) (xy 218.287635 136.39635)
			(xy 218.287635 136.38262) (xy 218.287635 136.36889) (xy 218.287635 136.35515) (xy 218.287635 136.34142)
			(xy 218.287635 136.32769) (xy 218.287635 136.31396) (xy 218.287635 136.30023) (xy 218.287635 136.28649)
			(xy 218.287635 136.27276) (xy 218.287635 136.25903) (xy 218.287635 136.2453) (xy 218.287635 136.23157)
			(xy 218.287635 136.21784) (xy 218.287635 136.2041) (xy 218.287635 136.19037) (xy 218.287635 136.17664)
			(xy 218.287635 136.16291) (xy 218.287635 136.14918) (xy 218.287635 136.13545) (xy 218.287635 136.12171)
			(xy 218.287635 136.10798) (xy 218.287635 136.09425) (xy 218.287635 136.08052) (xy 218.287635 136.06679)
			(xy 218.287635 136.05306) (xy 218.287635 136.03932) (xy 218.287635 136.02559) (xy 218.287635 136.01186)
			(xy 218.287635 135.99813) (xy 218.287635 135.9844) (xy 218.287635 135.97067) (xy 218.287635 135.95693)
			(xy 218.287635 135.9432) (xy 218.287635 135.92947) (xy 218.287635 135.91574) (xy 218.287635 135.90201)
			(xy 218.287635 135.88827) (xy 218.287635 135.87454) (xy 218.287635 135.86081) (xy 218.287635 135.84708)
			(xy 218.287635 135.83335) (xy 218.287635 135.81961) (xy 218.287635 135.80588) (xy 218.287635 135.79215)
			(xy 218.287635 135.77842) (xy 218.287635 135.76469) (xy 218.287635 135.75096) (xy 218.287635 135.73722)
			(xy 218.287635 135.72349) (xy 218.287635 135.70976) (xy 218.287635 135.69603) (xy 218.287635 135.6823)
			(xy 218.287635 135.66857) (xy 218.287635 135.65483) (xy 218.287635 135.6411) (xy 218.287635 135.62737)
			(xy 218.287635 135.61364) (xy 218.287635 135.59991) (xy 218.287635 135.58618) (xy 218.287635 135.57244)
			(xy 218.287635 135.55871) (xy 218.287635 135.54498) (xy 218.287635 135.53125) (xy 218.287635 135.51752)
			(xy 218.287635 135.50379) (xy 218.287635 135.49005) (xy 218.287635 135.47632) (xy 218.287635 135.46259)
			(xy 218.287635 135.44886) (xy 218.287635 135.43513) (xy 218.287635 135.4214) (xy 218.287635 135.40766)
			(xy 218.287635 135.39393) (xy 218.287635 135.3802) (xy 218.287635 135.36647) (xy 218.287635 135.35274)
			(xy 218.287635 135.339) (xy 218.287635 135.32527) (xy 218.287635 135.31154) (xy 218.287635 135.29781)
			(xy 218.287635 135.28408) (xy 218.287635 135.27034) (xy 218.287635 135.25661) (xy 218.287635 135.24288)
			(xy 218.287635 135.22915) (xy 218.287635 135.21542) (xy 218.287635 135.20169) (xy 218.287635 135.18795)
			(xy 218.287635 135.17422) (xy 218.287635 135.16049) (xy 218.287635 135.14676) (xy 218.287635 135.13303)
			(xy 218.287635 135.1193) (xy 218.287635 135.10556) (xy 218.287635 135.09183) (xy 218.287635 135.0781)
			(xy 218.287635 135.06437) (xy 218.287635 135.05064) (xy 218.287635 135.03691) (xy 218.287635 135.02317)
			(xy 218.287635 135.00944) (xy 218.287635 134.99571) (xy 218.287635 134.98198) (xy 218.287635 134.96825)
			(xy 218.287635 134.95452) (xy 218.287635 134.94078) (xy 218.287635 134.92705) (xy 218.287635 134.91332)
			(xy 218.287635 134.89959) (xy 218.287635 134.88586) (xy 218.287635 134.87213) (xy 218.287635 134.85839)
			(xy 218.287635 134.84466) (xy 218.287635 134.83093) (xy 218.287635 134.8172) (xy 218.287635 134.80347)
			(xy 218.287635 134.78973) (xy 218.287635 134.776) (xy 218.287635 134.76227) (xy 218.287635 134.74854)
			(xy 218.287635 134.73481) (xy 218.287635 134.72107) (xy 218.287635 134.70734) (xy 218.287635 134.69361)
			(xy 218.287635 134.67988) (xy 218.287635 134.66615) (xy 218.287635 134.65242) (xy 218.287635 134.63868)
			(xy 218.287635 134.62495) (xy 218.287635 134.61122) (xy 218.287635 134.59749) (xy 218.287635 134.58376)
			(xy 218.287635 134.57003) (xy 218.617195 134.57003) (xy 218.617195 134.58376) (xy 218.617195 134.59749)
			(xy 218.617195 134.61122) (xy 218.617195 134.62495) (xy 218.617195 134.63868) (xy 218.617195 134.65242)
			(xy 218.617195 134.66615) (xy 218.617195 134.67988) (xy 218.617195 134.69361) (xy 218.617195 134.70734)
			(xy 218.617195 134.72107) (xy 218.617195 134.73481) (xy 218.617195 134.74854) (xy 218.617195 134.76227)
			(xy 218.617195 134.776) (xy 218.617195 134.78973) (xy 218.617195 134.80347) (xy 218.617195 134.8172)
			(xy 218.617195 134.83093) (xy 218.617195 134.84466) (xy 218.617195 134.85839) (xy 218.617195 134.87213)
			(xy 218.617195 134.88586) (xy 218.617195 134.89959) (xy 218.617195 134.91332) (xy 218.617195 134.92705)
			(xy 218.617195 134.94078) (xy 218.617195 134.95452) (xy 218.617195 134.96825) (xy 218.617195 134.98198)
			(xy 218.617195 134.99571) (xy 218.617195 135.00944) (xy 218.617195 135.02317) (xy 218.617195 135.03691)
			(xy 218.617195 135.05064) (xy 218.617195 135.06437) (xy 218.617195 135.0781) (xy 218.617195 135.09183)
			(xy 218.617195 135.10556) (xy 218.617195 135.1193) (xy 218.617195 135.13303) (xy 218.617195 135.14676)
			(xy 218.617195 135.16049) (xy 218.617195 135.17422) (xy 218.617195 135.18795) (xy 218.617195 135.20169)
			(xy 218.617195 135.21542) (xy 218.617195 135.22915) (xy 218.617195 135.24288) (xy 218.617195 135.25661)
			(xy 218.617195 135.27034) (xy 218.617195 135.28408) (xy 218.617195 135.29781) (xy 218.617195 135.31154)
			(xy 218.617195 135.32527) (xy 218.617195 135.339) (xy 218.617195 135.35274) (xy 218.617195 135.36647)
			(xy 218.617195 135.3802) (xy 218.617195 135.39393) (xy 218.617195 135.40766) (xy 218.617195 135.4214)
			(xy 218.617195 135.43513) (xy 218.617195 135.44886) (xy 218.617195 135.46259) (xy 218.617195 135.47632)
			(xy 218.617195 135.49005) (xy 218.617195 135.50379) (xy 218.617195 135.51752) (xy 218.617195 135.53125)
			(xy 218.617195 135.54498) (xy 218.617195 135.55871) (xy 218.617195 135.57244) (xy 218.617195 135.58618)
			(xy 218.617195 135.59991) (xy 218.617195 135.61364) (xy 218.617195 135.62737) (xy 218.617195 135.6411)
			(xy 218.617195 135.65483) (xy 218.617195 135.66857) (xy 218.617195 135.6823) (xy 218.617195 135.69603)
			(xy 218.617195 135.70976) (xy 218.617195 135.72349) (xy 218.617195 135.73722) (xy 218.617195 135.75096)
			(xy 218.617195 135.76469) (xy 218.617195 135.77842) (xy 218.617195 135.79215) (xy 218.617195 135.80588)
			(xy 218.617195 135.81961) (xy 218.617195 135.83335) (xy 218.617195 135.84708) (xy 218.617195 135.86081)
			(xy 218.617195 135.87454) (xy 218.617195 135.88827) (xy 218.617195 135.90201) (xy 218.617195 135.91574)
			(xy 218.617195 135.92947) (xy 218.617195 135.9432) (xy 218.617195 135.95693) (xy 218.617195 135.97067)
			(xy 218.617195 135.9844) (xy 218.617195 135.99813) (xy 218.617195 136.01186) (xy 218.617195 136.02559)
			(xy 218.617195 136.03932) (xy 218.617195 136.05306) (xy 218.617195 136.06679) (xy 218.617195 136.08052)
			(xy 218.617195 136.09425) (xy 218.617195 136.10798) (xy 218.617195 136.12171) (xy 218.617195 136.13545)
			(xy 218.617195 136.14918) (xy 218.617195 136.16291) (xy 218.617195 136.17664) (xy 218.617195 136.19037)
			(xy 218.617195 136.2041) (xy 218.617195 136.21784) (xy 218.617195 136.23157) (xy 218.617195 136.2453)
			(xy 218.617195 136.25903) (xy 218.617195 136.27276) (xy 218.617195 136.28649) (xy 218.617195 136.30023)
			(xy 218.617195 136.31396) (xy 218.617195 136.32769) (xy 218.617195 136.34142) (xy 218.617195 136.35515)
			(xy 218.617195 136.36889) (xy 218.617195 136.38262) (xy 218.617195 136.39635) (xy 218.617195 136.41008)
			(xy 218.617195 136.42381) (xy 218.617195 136.43755) (xy 218.617195 136.45128) (xy 218.617195 136.46501)
			(xy 218.617195 136.47874) (xy 218.630925 136.47874) (xy 218.630925 136.49247) (xy 218.630925 136.5062)
			(xy 218.630925 136.51994) (xy 218.630925 136.53367) (xy 218.630925 136.5474) (xy 218.644655 136.5474)
			(xy 218.644655 136.56113) (xy 218.644655 136.57486) (xy 218.658395 136.57486) (xy 218.658395 136.58859)
			(xy 218.658395 136.60233) (xy 218.672125 136.60233) (xy 218.672125 136.61606) (xy 218.685855 136.61606)
			(xy 218.685855 136.62979) (xy 218.699585 136.62979) (xy 218.699585 136.64352) (xy 218.713315 136.64352)
			(xy 218.713315 136.65725) (xy 218.727055 136.65725) (xy 218.727055 136.67098) (xy 218.740785 136.67098)
			(xy 218.740785 136.68472) (xy 218.754515 136.68472) (xy 218.754515 136.69845) (xy 218.768245 136.69845)
			(xy 218.768245 136.71218) (xy 218.781975 136.71218) (xy 218.781975 136.72591) (xy 218.795705 136.72591)
			(xy 218.795705 136.73964) (xy 218.809445 136.73964) (xy 218.809445 136.75337) (xy 218.823175 136.75337)
			(xy 218.823175 136.76711) (xy 218.836905 136.76711) (xy 218.836905 136.78084) (xy 218.850635 136.78084)
			(xy 218.850635 136.79457) (xy 218.864365 136.79457) (xy 218.864365 136.8083) (xy 218.878095 136.8083)
			(xy 218.878095 136.82203) (xy 218.891835 136.82203) (xy 218.891835 136.83576) (xy 218.905565 136.83576)
			(xy 218.905565 136.8495) (xy 218.919295 136.8495) (xy 218.919295 136.86323) (xy 218.933025 136.86323)
			(xy 218.933025 136.87696) (xy 218.946755 136.87696) (xy 218.946755 136.89069) (xy 218.960485 136.89069)
			(xy 218.960485 136.90442) (xy 218.974225 136.90442) (xy 218.974225 136.91816) (xy 218.987955 136.91816)
			(xy 218.987955 136.93189) (xy 219.001685 136.93189) (xy 219.001685 136.94562) (xy 219.015415 136.94562)
			(xy 219.015415 136.95935) (xy 219.029145 136.95935) (xy 219.029145 136.97308) (xy 219.042875 136.97308)
			(xy 219.042875 136.98682) (xy 219.070345 136.98682) (xy 219.070345 137.00055) (xy 219.125265 137.00055)
			(xy 219.125265 137.01428) (xy 220.869205 137.01428) (xy 220.869205 137.00055) (xy 220.882935 137.00055)
			(xy 220.882935 136.98682) (xy 220.896665 136.98682) (xy 220.896665 136.97308) (xy 220.896665 136.95935)
			(xy 220.910395 136.95935) (xy 220.910395 136.94562) (xy 220.910395 136.93189) (xy 220.910395 136.91816)
			(xy 220.910395 136.90442) (xy 220.910395 136.89069) (xy 220.910395 136.87696) (xy 220.910395 136.86323)
			(xy 220.910395 136.8495) (xy 220.910395 136.83576) (xy 220.910395 136.82203) (xy 220.910395 136.8083)
			(xy 220.910395 136.79457) (xy 220.910395 136.78084) (xy 220.910395 136.76711) (xy 220.910395 136.75337)
			(xy 220.910395 136.73964) (xy 220.910395 136.72591) (xy 220.910395 136.71218) (xy 220.910395 136.69845)
			(xy 220.910395 136.68472) (xy 220.910395 136.67098) (xy 220.910395 136.65725) (xy 220.910395 136.64352)
			(xy 220.910395 136.62979) (xy 220.910395 136.61606) (xy 220.910395 136.60233) (xy 220.910395 136.58859)
			(xy 220.910395 136.57486) (xy 220.910395 136.56113) (xy 220.910395 136.5474) (xy 220.910395 136.53367)
			(xy 220.910395 136.51994) (xy 220.910395 136.5062) (xy 220.910395 136.49247) (xy 220.910395 136.47874)
			(xy 220.910395 136.46501) (xy 220.910395 136.45128) (xy 220.910395 136.43755) (xy 220.910395 136.42381)
			(xy 220.910395 136.41008) (xy 220.910395 136.39635) (xy 220.910395 136.38262) (xy 220.910395 136.36889)
			(xy 220.896665 136.36889) (xy 220.896665 136.35515) (xy 220.896665 136.34142) (xy 220.882935 136.34142)
			(xy 220.882935 136.32769) (xy 220.855475 136.32769) (xy 220.855475 136.31396) (xy 219.386175 136.31396)
			(xy 219.386175 136.30023) (xy 219.372445 136.30023) (xy 219.372445 136.28649) (xy 219.372445 136.27276)
			(xy 219.372445 136.25903) (xy 219.372445 136.2453) (xy 219.372445 136.23157) (xy 219.372445 136.21784)
			(xy 219.372445 136.2041) (xy 219.372445 136.19037) (xy 219.372445 136.17664) (xy 219.372445 136.16291)
			(xy 219.372445 136.14918) (xy 219.372445 136.13545) (xy 219.372445 136.12171) (xy 219.372445 136.10798)
			(xy 219.372445 136.09425) (xy 219.372445 136.08052) (xy 219.372445 136.06679) (xy 219.372445 136.05306)
			(xy 219.372445 136.03932) (xy 219.372445 136.02559) (xy 219.372445 136.01186) (xy 219.372445 135.99813)
			(xy 219.372445 135.9844) (xy 219.372445 135.97067) (xy 219.372445 135.95693) (xy 219.372445 135.9432)
			(xy 219.372445 135.92947) (xy 219.372445 135.91574) (xy 219.372445 135.90201) (xy 219.372445 135.88827)
			(xy 219.372445 135.87454) (xy 219.372445 135.86081) (xy 219.372445 135.84708) (xy 219.372445 135.83335)
			(xy 219.386175 135.83335) (xy 219.386175 135.81961) (xy 220.649495 135.81961) (xy 220.649495 135.80588)
			(xy 220.676955 135.80588) (xy 220.676955 135.79215) (xy 220.676955 135.77842) (xy 220.690685 135.77842)
			(xy 220.690685 135.76469) (xy 220.690685 135.75096) (xy 220.690685 135.73722) (xy 220.690685 135.72349)
			(xy 220.690685 135.70976) (xy 220.690685 135.69603) (xy 220.690685 135.6823) (xy 220.690685 135.66857)
			(xy 220.690685 135.65483) (xy 220.690685 135.6411) (xy 220.690685 135.62737) (xy 220.690685 135.61364)
			(xy 220.690685 135.59991) (xy 220.690685 135.58618) (xy 220.690685 135.57244) (xy 220.690685 135.55871)
			(xy 220.690685 135.54498) (xy 220.690685 135.53125) (xy 220.690685 135.51752) (xy 220.690685 135.50379)
			(xy 220.690685 135.49005) (xy 220.690685 135.47632) (xy 220.690685 135.46259) (xy 220.690685 135.44886)
			(xy 220.690685 135.43513) (xy 220.690685 135.4214) (xy 220.690685 135.40766) (xy 220.690685 135.39393)
			(xy 220.690685 135.3802) (xy 220.690685 135.36647) (xy 220.690685 135.35274) (xy 220.690685 135.339)
			(xy 220.690685 135.32527) (xy 220.690685 135.31154) (xy 220.690685 135.29781) (xy 220.690685 135.28408)
			(xy 220.690685 135.27034) (xy 220.676955 135.27034) (xy 220.676955 135.25661) (xy 220.676955 135.24288)
			(xy 220.649495 135.24288) (xy 220.649495 135.22915) (xy 219.386175 135.22915) (xy 219.386175 135.21542)
			(xy 219.372445 135.21542) (xy 219.372445 135.20169) (xy 219.372445 135.18795) (xy 219.372445 135.17422)
			(xy 219.372445 135.16049) (xy 219.372445 135.14676) (xy 219.372445 135.13303) (xy 219.372445 135.1193)
			(xy 219.372445 135.10556) (xy 219.372445 135.09183) (xy 219.372445 135.0781) (xy 219.372445 135.06437)
			(xy 219.372445 135.05064) (xy 219.372445 135.03691) (xy 219.372445 135.02317) (xy 219.372445 135.00944)
			(xy 219.372445 134.99571) (xy 219.372445 134.98198) (xy 219.372445 134.96825) (xy 219.372445 134.95452)
			(xy 219.372445 134.94078) (xy 219.372445 134.92705) (xy 219.372445 134.91332) (xy 219.372445 134.89959)
			(xy 219.372445 134.88586) (xy 219.372445 134.87213) (xy 219.372445 134.85839) (xy 219.372445 134.84466)
			(xy 219.372445 134.83093) (xy 219.372445 134.8172) (xy 219.372445 134.80347) (xy 219.372445 134.78973)
			(xy 219.372445 134.776) (xy 219.372445 134.76227) (xy 219.372445 134.74854) (xy 219.372445 134.73481)
			(xy 219.386175 134.73481) (xy 219.386175 134.72107) (xy 220.869205 134.72107) (xy 220.869205 134.70734)
			(xy 220.882935 134.70734) (xy 220.882935 134.69361) (xy 220.896665 134.69361) (xy 220.896665 134.67988)
			(xy 220.910395 134.67988) (xy 220.910395 134.66615) (xy 220.910395 134.65242) (xy 220.910395 134.63868)
			(xy 220.910395 134.62495) (xy 220.910395 134.61122) (xy 220.910395 134.59749) (xy 220.910395 134.58376)
			(xy 220.910395 134.57003) (xy 220.910395 134.55629) (xy 220.910395 134.54256) (xy 220.910395 134.52883)
			(xy 220.910395 134.5151) (xy 220.910395 134.50137) (xy 220.910395 134.48764) (xy 220.910395 134.4739)
			(xy 220.910395 134.46017) (xy 220.910395 134.44644) (xy 220.910395 134.43271) (xy 220.910395 134.41898)
			(xy 220.910395 134.40525) (xy 220.910395 134.39151) (xy 220.910395 134.37778) (xy 220.910395 134.36405)
			(xy 220.910395 134.35032) (xy 220.910395 134.33659) (xy 220.910395 134.32286) (xy 220.910395 134.30912)
			(xy 220.910395 134.29539) (xy 220.910395 134.28166) (xy 220.910395 134.26793) (xy 220.910395 134.2542)
			(xy 220.910395 134.24046) (xy 220.910395 134.22673) (xy 220.910395 134.213) (xy 220.910395 134.19927)
			(xy 220.910395 134.18554) (xy 220.910395 134.1718) (xy 220.910395 134.15807) (xy 220.910395 134.14434)
			(xy 220.910395 134.13061) (xy 220.910395 134.11688) (xy 220.910395 134.10315) (xy 220.910395 134.08941)
			(xy 220.896665 134.08941) (xy 220.896665 134.07568) (xy 220.896665 134.06195) (xy 220.882935 134.06195)
			(xy 220.882935 134.04822) (xy 220.869205 134.04822) (xy 220.869205 134.03449) (xy 220.841745 134.03449)
			(xy 220.841745 134.02076) (xy 220.800545 134.02076) (xy 220.800545 134.03449) (xy 220.786815 134.03449)
			(xy 220.786815 134.02076) (xy 219.180195 134.02076) (xy 219.180195 134.03449) (xy 219.111535 134.03449)
			(xy 219.111535 134.04822) (xy 219.070345 134.04822) (xy 219.070345 134.06195) (xy 219.042875 134.06195)
			(xy 219.042875 134.07568) (xy 219.029145 134.07568) (xy 219.029145 134.08941) (xy 219.015415 134.08941)
			(xy 219.015415 134.10315) (xy 219.001685 134.10315) (xy 219.001685 134.11688) (xy 218.987955 134.11688)
			(xy 218.987955 134.13061) (xy 218.974225 134.13061) (xy 218.974225 134.14434) (xy 218.960485 134.14434)
			(xy 218.960485 134.15807) (xy 218.946755 134.15807) (xy 218.946755 134.1718) (xy 218.933025 134.1718)
			(xy 218.933025 134.18554) (xy 218.919295 134.18554) (xy 218.919295 134.19927) (xy 218.905565 134.19927)
			(xy 218.905565 134.213) (xy 218.891835 134.213) (xy 218.891835 134.22673) (xy 218.878095 134.22673)
			(xy 218.878095 134.24046) (xy 218.864365 134.24046) (xy 218.864365 134.2542) (xy 218.850635 134.2542)
			(xy 218.850635 134.26793) (xy 218.836905 134.26793) (xy 218.836905 134.28166) (xy 218.823175 134.28166)
			(xy 218.823175 134.29539) (xy 218.809445 134.29539) (xy 218.809445 134.30912) (xy 218.795705 134.30912)
			(xy 218.795705 134.32286) (xy 218.781975 134.32286) (xy 218.781975 134.33659) (xy 218.768245 134.33659)
			(xy 218.768245 134.35032) (xy 218.754515 134.35032) (xy 218.754515 134.36405) (xy 218.740785 134.36405)
			(xy 218.740785 134.37778) (xy 218.727055 134.37778) (xy 218.727055 134.39151) (xy 218.713315 134.39151)
			(xy 218.713315 134.40525) (xy 218.699585 134.40525) (xy 218.699585 134.41898) (xy 218.685855 134.41898)
			(xy 218.685855 134.43271) (xy 218.672125 134.43271) (xy 218.672125 134.44644) (xy 218.658395 134.44644)
			(xy 218.658395 134.46017) (xy 218.644655 134.46017) (xy 218.644655 134.4739) (xy 218.644655 134.48764)
			(xy 218.644655 134.50137) (xy 218.630925 134.50137) (xy 218.630925 134.5151) (xy 218.630925 134.52883)
			(xy 218.630925 134.54256) (xy 218.630925 134.55629) (xy 218.630925 134.57003) (xy 218.617195 134.57003)
			(xy 218.287635 134.57003) (xy 218.287635 134.55629) (xy 218.287635 134.54256) (xy 218.287635 134.52883)
			(xy 218.287635 134.5151) (xy 218.287635 134.50137) (xy 218.287635 134.48764) (xy 218.287635 134.4739)
			(xy 218.287635 134.46017) (xy 218.287635 134.44644) (xy 218.287635 134.43271) (xy 218.287635 134.41898)
			(xy 218.287635 134.40525) (xy 218.287635 134.39151) (xy 218.287635 134.37778) (xy 218.287635 134.36405)
			(xy 218.287635 134.35032) (xy 218.287635 134.33659) (xy 218.287635 134.32286) (xy 218.287635 134.30912)
			(xy 218.287635 134.29539) (xy 218.287635 134.28166) (xy 218.287635 134.26793) (xy 218.287635 134.2542)
			(xy 218.287635 134.24046) (xy 218.287635 134.22673) (xy 218.287635 134.213) (xy 218.287635 134.19927)
			(xy 218.287635 134.18554) (xy 218.287635 134.1718) (xy 218.287635 134.15807) (xy 218.287635 134.14434)
			(xy 218.287635 134.13061) (xy 218.287635 134.11688) (xy 218.287635 134.10315) (xy 218.287635 134.08941)
			(xy 218.287635 134.07568) (xy 218.287635 134.06195) (xy 218.287635 134.04822) (xy 218.287635 134.03449)
			(xy 218.287635 134.02076) (xy 218.287635 134.00702) (xy 218.287635 133.99329) (xy 218.287635 133.97956)
			(xy 218.287635 133.96583) (xy 218.287635 133.9521) (xy 218.287635 133.93837) (xy 218.287635 133.92463)
			(xy 218.287635 133.9109) (xy 218.287635 133.89717) (xy 218.287635 133.88344) (xy 218.287635 133.86971)
			(xy 218.287635 133.85598) (xy 218.287635 133.84224) (xy 218.287635 133.82851) (xy 218.287635 133.81478)
			(xy 218.287635 133.80105) (xy 218.287635 133.78732) (xy 218.287635 133.77359) (xy 218.287635 133.75985)
			(xy 218.287635 133.74612) (xy 218.287635 133.73239) (xy 218.287635 133.71866) (xy 218.287635 133.70493)
			(xy 218.287635 133.69119) (xy 218.287635 133.67746) (xy 218.287635 133.66373) (xy 218.287635 133.65)
			(xy 218.287635 133.63627) (xy 218.287635 133.62253) (xy 218.287635 133.6088) (xy 218.287635 133.59507)
			(xy 218.287635 133.58134) (xy 218.287635 133.56761) (xy 218.287635 133.55388) (xy 218.287635 133.54014)
			(xy 218.287635 133.52641) (xy 218.287635 133.51268) (xy 218.287635 133.49895) (xy 218.287635 133.48522)
			(xy 218.287635 133.47149) (xy 218.287635 133.45775) (xy 218.287635 133.44402) (xy 218.287635 133.43029)
			(xy 218.287635 133.41656) (xy 218.287635 133.40283) (xy 218.287635 133.3891) (xy 218.287635 133.37536)
			(xy 218.287635 133.36163) (xy 218.287635 133.3479) (xy 218.287635 133.33417) (xy 218.287635 133.32044)
			(xy 218.287635 133.30671) (xy 218.287635 133.29297) (xy 218.287635 133.27924) (xy 218.287635 133.26551)
			(xy 218.287635 133.25178) (xy 218.287635 133.23805) (xy 218.287635 133.22431) (xy 218.287635 133.21058)
			(xy 218.287635 133.19685) (xy 218.287635 133.18312) (xy 218.287635 133.16939) (xy 218.287635 133.15565)
			(xy 218.287635 133.14192) (xy 218.287635 133.12819) (xy 218.287635 133.11446) (xy 218.287635 133.10073)
			(xy 218.287635 133.087) (xy 218.287635 133.07326) (xy 218.287635 133.05953) (xy 218.287635 133.0458)
			(xy 218.287635 133.03207) (xy 218.287635 133.01834) (xy 218.287635 133.00461) (xy 218.287635 132.99087)
			(xy 218.287635 132.97714) (xy 218.287635 132.96341) (xy 218.287635 132.94968) (xy 218.287635 132.93595)
			(xy 218.287635 132.92222) (xy 218.287635 132.90848) (xy 218.287635 132.89475) (xy 218.287635 132.88102)
			(xy 218.273905 132.88102) (xy 218.273905 132.86729) (xy 218.273905 132.85356) (xy 218.273905 132.83983)
			(xy 218.273905 132.82609) (xy 218.260175 132.82609) (xy 218.260175 132.81236) (xy 218.260175 132.79863)
			(xy 218.246445 132.79863) (xy 218.246445 132.7849) (xy 218.232705 132.7849) (xy 218.232705 132.77117)
			(xy 218.218975 132.77117) (xy 218.218975 132.75744) (xy 218.205245 132.75744) (xy 218.205245 132.7437)
			(xy 218.191515 132.7437) (xy 218.191515 132.72997) (xy 218.177785 132.72997) (xy 218.177785 132.71624)
			(xy 218.164045 132.71624) (xy 218.164045 132.70251) (xy 218.150315 132.70251) (xy 218.150315 132.68878)
			(xy 218.136585 132.68878) (xy 218.136585 132.67504) (xy 218.122855 132.67504) (xy 218.122855 132.66131)
			(xy 218.109125 132.66131) (xy 218.109125 132.64758) (xy 218.095385 132.64758) (xy 218.095385 132.63385)
			(xy 218.081655 132.63385) (xy 218.081655 132.62012) (xy 218.067925 132.62012) (xy 218.067925 132.60638)
			(xy 218.054195 132.60638) (xy 218.054195 132.59265) (xy 218.040465 132.59265) (xy 218.040465 132.57892)
			(xy 218.026735 132.57892) (xy 218.026735 132.56519) (xy 218.012995 132.56519) (xy 218.012995 132.55146)
			(xy 217.999265 132.55146) (xy 217.999265 132.53773) (xy 217.985535 132.53773) (xy 217.985535 132.52399)
			(xy 217.971805 132.52399) (xy 217.971805 132.51026) (xy 217.958075 132.51026) (xy 217.958075 132.49653)
			(xy 217.944345 132.49653) (xy 217.944345 132.4828) (xy 217.930605 132.4828) (xy 217.930605 132.46907)
			(xy 217.916875 132.46907) (xy 217.916875 132.45534) (xy 217.903145 132.45534) (xy 217.903145 132.4416)
			(xy 217.889415 132.4416) (xy 217.889415 132.42787) (xy 217.875685 132.42787) (xy 217.875685 132.41414)
			(xy 217.848215 132.41414) (xy 217.848215 132.40041) (xy 217.793295 132.40041) (xy 217.793295 132.38668)
			(xy 217.546115 132.38668) (xy 217.546115 132.40041) (xy 217.546115 132.41414) (xy 217.546115 132.42787)
			(xy 217.546115 132.4416) (xy 217.546115 132.45534) (xy 217.546115 132.46907) (xy 217.546115 132.4828)
			(xy 217.546115 132.49653) (xy 217.546115 132.51026) (xy 217.546115 132.52399) (xy 217.546115 132.53773)
			(xy 217.546115 132.55146) (xy 217.546115 132.56519) (xy 217.546115 132.57892) (xy 217.546115 132.59265)
			(xy 217.546115 132.60638) (xy 217.546115 132.62012) (xy 217.546115 132.63385) (xy 217.546115 132.64758)
			(xy 217.546115 132.66131) (xy 217.546115 132.67504) (xy 217.546115 132.68878) (xy 217.546115 132.70251)
			(xy 217.546115 132.71624) (xy 217.546115 132.72997) (xy 217.546115 132.7437) (xy 217.546115 132.75744)
			(xy 217.546115 132.77117) (xy 217.546115 132.7849) (xy 217.546115 132.79863) (xy 217.546115 132.81236)
			(xy 217.546115 132.82609) (xy 217.546115 132.83983) (xy 217.546115 132.85356) (xy 217.546115 132.86729)
			(xy 217.546115 132.88102) (xy 217.546115 132.89475) (xy 217.546115 132.90848) (xy 217.546115 132.92222)
			(xy 217.546115 132.93595) (xy 217.546115 132.94968) (xy 217.546115 132.96341) (xy 217.546115 132.97714)
			(xy 217.546115 132.99087) (xy 217.546115 133.00461) (xy 217.546115 133.01834) (xy 217.546115 133.03207)
			(xy 217.546115 133.0458) (xy 217.546115 133.05953) (xy 217.546115 133.07326) (xy 217.546115 133.087)
			(xy 217.546115 133.10073) (xy 217.546115 133.11446) (xy 217.546115 133.12819) (xy 217.546115 133.14192)
			(xy 217.546115 133.15565) (xy 217.546115 133.16939) (xy 217.546115 133.18312) (xy 217.546115 133.19685)
			(xy 217.546115 133.21058) (xy 217.546115 133.22431) (xy 217.546115 133.23805) (xy 217.546115 133.25178)
			(xy 217.546115 133.26551) (xy 217.546115 133.27924) (xy 217.546115 133.29297) (xy 217.546115 133.30671)
			(xy 217.546115 133.32044) (xy 217.546115 133.33417) (xy 217.546115 133.3479) (xy 217.546115 133.36163)
			(xy 217.546115 133.37536) (xy 217.546115 133.3891) (xy 217.546115 133.40283) (xy 217.546115 133.41656)
			(xy 217.546115 133.43029) (xy 217.546115 133.44402) (xy 217.546115 133.45775) (xy 217.546115 133.47149)
			(xy 217.546115 133.48522) (xy 217.546115 133.49895) (xy 217.546115 133.51268) (xy 217.546115 133.52641)
			(xy 217.546115 133.54014) (xy 217.546115 133.55388) (xy 217.546115 133.56761) (xy 217.546115 133.58134)
			(xy 217.546115 133.59507) (xy 217.546115 133.6088) (xy 217.546115 133.62253) (xy 217.546115 133.63627)
			(xy 217.546115 133.65) (xy 217.546115 133.66373) (xy 217.546115 133.67746) (xy 217.546115 133.69119)
			(xy 217.546115 133.70493) (xy 217.546115 133.71866) (xy 217.546115 133.73239) (xy 217.546115 133.74612)
			(xy 217.546115 133.75985) (xy 217.546115 133.77359) (xy 217.546115 133.78732) (xy 217.546115 133.80105)
			(xy 217.546115 133.81478) (xy 217.546115 133.82851) (xy 217.546115 133.84224) (xy 217.546115 133.85598)
			(xy 217.546115 133.86971) (xy 217.546115 133.88344) (xy 217.546115 133.89717) (xy 217.546115 133.9109)
			(xy 217.546115 133.92463) (xy 217.546115 133.93837) (xy 217.546115 133.9521) (xy 217.546115 133.96583)
			(xy 217.546115 133.97956) (xy 217.546115 133.99329) (xy 217.546115 134.00702) (xy 217.546115 134.02076)
			(xy 217.546115 134.03449) (xy 217.546115 134.04822) (xy 217.546115 134.06195) (xy 217.546115 134.07568)
			(xy 217.546115 134.08941) (xy 217.546115 134.10315) (xy 217.546115 134.11688) (xy 217.546115 134.13061)
			(xy 217.546115 134.14434) (xy 217.546115 134.15807) (xy 217.546115 134.1718) (xy 217.546115 134.18554)
			(xy 217.546115 134.19927) (xy 217.546115 134.213) (xy 217.546115 134.22673) (xy 217.546115 134.24046)
			(xy 217.546115 134.2542) (xy 217.546115 134.26793) (xy 217.546115 134.28166) (xy 217.546115 134.29539)
			(xy 217.546115 134.30912) (xy 217.546115 134.32286) (xy 217.546115 134.33659) (xy 217.546115 134.35032)
			(xy 217.546115 134.36405) (xy 217.546115 134.37778) (xy 217.546115 134.39151) (xy 217.546115 134.40525)
			(xy 217.546115 134.41898) (xy 217.546115 134.43271) (xy 217.546115 134.44644) (xy 217.546115 134.46017)
			(xy 217.546115 134.4739) (xy 217.546115 134.48764) (xy 217.546115 134.50137) (xy 217.546115 134.5151)
			(xy 217.546115 134.52883) (xy 217.546115 134.54256) (xy 217.546115 134.55629) (xy 217.546115 134.57003)
			(xy 217.546115 134.58376) (xy 217.546115 134.59749) (xy 217.546115 134.61122) (xy 217.546115 134.62495)
			(xy 217.546115 134.63868) (xy 217.546115 134.65242) (xy 217.546115 134.66615) (xy 217.546115 134.67988)
			(xy 217.546115 134.69361) (xy 217.546115 134.70734) (xy 217.546115 134.72107) (xy 217.546115 134.73481)
			(xy 217.546115 134.74854) (xy 217.546115 134.76227) (xy 217.546115 134.776) (xy 217.546115 134.78973)
			(xy 217.546115 134.80347) (xy 217.546115 134.8172) (xy 217.546115 134.83093) (xy 217.546115 134.84466)
			(xy 217.546115 134.85839) (xy 217.546115 134.87213) (xy 217.546115 134.88586) (xy 217.546115 134.89959)
			(xy 217.546115 134.91332) (xy 217.546115 134.92705) (xy 217.546115 134.94078) (xy 217.546115 134.95452)
			(xy 217.546115 134.96825) (xy 217.546115 134.98198) (xy 217.546115 134.99571) (xy 217.546115 135.00944)
			(xy 217.546115 135.02317) (xy 217.546115 135.03691) (xy 217.546115 135.05064) (xy 217.546115 135.06437)
			(xy 217.546115 135.0781) (xy 217.546115 135.09183) (xy 217.546115 135.10556) (xy 217.546115 135.1193)
			(xy 217.546115 135.13303) (xy 217.546115 135.14676) (xy 217.546115 135.16049) (xy 217.546115 135.17422)
			(xy 217.546115 135.18795) (xy 217.546115 135.20169) (xy 217.546115 135.21542) (xy 217.546115 135.22915)
			(xy 217.546115 135.24288) (xy 217.546115 135.25661) (xy 217.546115 135.27034) (xy 217.546115 135.28408)
			(xy 217.546115 135.29781) (xy 217.546115 135.31154) (xy 217.546115 135.32527) (xy 217.546115 135.339)
			(xy 217.546115 135.35274) (xy 217.546115 135.36647) (xy 217.546115 135.3802) (xy 217.546115 135.39393)
			(xy 217.546115 135.40766) (xy 217.546115 135.4214) (xy 217.546115 135.43513) (xy 217.546115 135.44886)
			(xy 217.546115 135.46259) (xy 217.546115 135.47632) (xy 217.546115 135.49005) (xy 217.546115 135.50379)
			(xy 217.546115 135.51752) (xy 217.546115 135.53125) (xy 217.546115 135.54498) (xy 217.546115 135.55871)
			(xy 217.546115 135.57244) (xy 217.546115 135.58618) (xy 217.546115 135.59991) (xy 217.546115 135.61364)
			(xy 217.546115 135.62737) (xy 217.546115 135.6411) (xy 217.546115 135.65483) (xy 217.546115 135.66857)
			(xy 217.546115 135.6823) (xy 217.546115 135.69603) (xy 217.546115 135.70976) (xy 217.546115 135.72349)
			(xy 217.546115 135.73722) (xy 217.546115 135.75096) (xy 217.546115 135.76469) (xy 217.546115 135.77842)
			(xy 217.546115 135.79215) (xy 217.546115 135.80588) (xy 217.546115 135.81961) (xy 217.546115 135.83335)
			(xy 217.546115 135.84708) (xy 217.546115 135.86081) (xy 217.546115 135.87454) (xy 217.546115 135.88827)
			(xy 217.546115 135.90201) (xy 217.546115 135.91574) (xy 217.546115 135.92947) (xy 217.546115 135.9432)
			(xy 217.546115 135.95693) (xy 217.546115 135.97067) (xy 217.546115 135.9844) (xy 217.546115 135.99813)
			(xy 217.546115 136.01186) (xy 217.546115 136.02559) (xy 217.546115 136.03932) (xy 217.546115 136.05306)
			(xy 217.546115 136.06679) (xy 217.546115 136.08052) (xy 217.546115 136.09425) (xy 217.546115 136.10798)
			(xy 217.546115 136.12171) (xy 217.546115 136.13545) (xy 217.546115 136.14918) (xy 217.546115 136.16291)
			(xy 217.546115 136.17664) (xy 217.546115 136.19037) (xy 217.546115 136.2041) (xy 217.546115 136.21784)
			(xy 217.546115 136.23157) (xy 217.546115 136.2453) (xy 217.546115 136.25903) (xy 217.546115 136.27276)
			(xy 217.546115 136.28649) (xy 217.546115 136.30023) (xy 217.546115 136.31396) (xy 217.546115 136.32769)
			(xy 217.546115 136.34142) (xy 217.546115 136.35515) (xy 217.546115 136.36889) (xy 217.546115 136.38262)
			(xy 217.546115 136.39635) (xy 217.546115 136.41008) (xy 217.546115 136.42381) (xy 217.546115 136.43755)
			(xy 217.546115 136.45128) (xy 217.546115 136.46501) (xy 217.546115 136.47874) (xy 217.546115 136.49247)
			(xy 217.546115 136.5062) (xy 217.546115 136.51994) (xy 217.546115 136.53367) (xy 217.546115 136.5474)
			(xy 217.546115 136.56113) (xy 217.546115 136.57486) (xy 217.546115 136.58859) (xy 217.546115 136.60233)
			(xy 217.546115 136.61606) (xy 217.546115 136.62979) (xy 217.546115 136.64352) (xy 217.546115 136.65725)
			(xy 217.546115 136.67098) (xy 217.546115 136.68472) (xy 217.546115 136.69845) (xy 217.546115 136.71218)
			(xy 217.546115 136.72591) (xy 217.546115 136.73964) (xy 217.546115 136.75337) (xy 217.546115 136.76711)
			(xy 217.546115 136.78084) (xy 217.546115 136.79457) (xy 217.546115 136.8083) (xy 217.546115 136.82203)
			(xy 217.546115 136.83576) (xy 217.546115 136.8495) (xy 217.546115 136.86323) (xy 217.546115 136.87696)
			(xy 217.546115 136.89069) (xy 217.546115 136.90442) (xy 217.546115 136.91816) (xy 217.546115 136.93189)
			(xy 217.532385 136.93189) (xy 217.532385 136.94562) (xy 217.518655 136.94562) (xy 217.518655 136.95935)
			(xy 217.504925 136.95935) (xy 217.504925 136.97308) (xy 217.491195 136.97308) (xy 217.491195 136.98682)
			(xy 217.477465 136.98682) (xy 217.477465 137.00055) (xy 217.463725 137.00055) (xy 217.463725 137.01428)
			(xy 217.449995 137.01428) (xy 217.449995 137.02801) (xy 217.436265 137.02801) (xy 217.436265 137.04174)
			(xy 217.422535 137.04174) (xy 217.422535 137.05547) (xy 217.408805 137.05547) (xy 217.408805 137.06921)
			(xy 217.395075 137.06921) (xy 217.395075 137.08294) (xy 217.381335 137.08294) (xy 217.381335 137.09667)
			(xy 217.367605 137.09667) (xy 217.367605 137.1104) (xy 217.353875 137.1104) (xy 217.353875 137.12413)
			(xy 217.340145 137.12413) (xy 217.340145 137.13786) (xy 217.326415 137.13786) (xy 217.326415 137.1516)
			(xy 217.312685 137.1516) (xy 217.312685 137.16533) (xy 217.285215 137.16533) (xy 217.285215 137.17906)
			(xy 217.271485 137.17906) (xy 217.271485 137.19279) (xy 217.257755 137.19279) (xy 217.257755 137.20652)
			(xy 217.244025 137.20652) (xy 217.244025 137.22025) (xy 217.230295 137.22025) (xy 217.230295 137.23399)
			(xy 217.216555 137.23399) (xy 217.216555 137.24772) (xy 217.202825 137.24772) (xy 217.202825 137.26145)
			(xy 217.189095 137.26145) (xy 217.189095 137.27518) (xy 217.175365 137.27518) (xy 217.175365 137.28891)
			(xy 217.161635 137.28891) (xy 217.161635 137.30264) (xy 217.147905 137.30264) (xy 217.147905 137.31638)
			(xy 217.134165 137.31638) (xy 217.134165 137.33011) (xy 217.120435 137.33011) (xy 217.120435 137.34384)
			(xy 217.106705 137.34384) (xy 217.106705 137.35757) (xy 217.092975 137.35757) (xy 217.092975 137.3713)
			(xy 217.079245 137.3713) (xy 217.079245 137.38503) (xy 217.065505 137.38503) (xy 217.065505 137.39877)
			(xy 217.051775 137.39877) (xy 217.051775 137.4125) (xy 217.038045 137.4125) (xy 217.038045 137.42623)
			(xy 217.024315 137.42623) (xy 217.024315 137.43996) (xy 217.010585 137.43996) (xy 217.010585 137.45369)
			(xy 216.996845 137.45369) (xy 216.996845 137.46743) (xy 216.983115 137.46743) (xy 216.983115 137.48116)
			(xy 216.969385 137.48116) (xy 216.969385 137.49489) (xy 216.955655 137.49489) (xy 216.955655 137.50862)
			(xy 216.941925 137.50862) (xy 216.941925 137.52235) (xy 216.928195 137.52235) (xy 216.928195 137.53609)
			(xy 216.914455 137.53609) (xy 216.914455 137.54982) (xy 216.900725 137.54982) (xy 216.900725 137.56355)
			(xy 216.886995 137.56355) (xy 216.886995 137.57728) (xy 216.873265 137.57728) (xy 216.873265 137.59101)
			(xy 216.859535 137.59101) (xy 216.859535 137.60474) (xy 216.845805 137.60474) (xy 216.845805 137.61848)
			(xy 216.832065 137.61848) (xy 216.832065 137.63221) (xy 216.818335 137.63221) (xy 216.818335 137.64594)
			(xy 216.804605 137.64594) (xy 216.804605 137.65967) (xy 216.790875 137.65967) (xy 216.790875 137.6734)
			(xy 216.777145 137.6734) (xy 216.777145 137.68713) (xy 216.763415 137.68713) (xy 216.763415 137.70087)
			(xy 216.749675 137.70087) (xy 216.749675 137.7146) (xy 216.735945 137.7146) (xy 216.735945 137.72833)
			(xy 216.722215 137.72833) (xy 216.722215 137.74206) (xy 216.708485 137.74206) (xy 216.708485 137.75579)
			(xy 216.694755 137.75579) (xy 216.694755 137.76952) (xy 216.681025 137.76952) (xy 216.681025 137.78326)
			(xy 216.667285 137.78326) (xy 216.667285 137.79699) (xy 216.653555 137.79699) (xy 216.653555 137.81072)
			(xy 216.639825 137.81072) (xy 216.639825 137.82445) (xy 216.626095 137.82445) (xy 216.626095 137.83818)
			(xy 216.612365 137.83818) (xy 216.612365 137.85191) (xy 216.598625 137.85191) (xy 216.598625 137.86565)
			(xy 216.584895 137.86565) (xy 216.584895 137.87938) (xy 216.571165 137.87938) (xy 216.571165 137.89311)
			(xy 216.557435 137.89311) (xy 216.557435 137.90684) (xy 216.543705 137.90684) (xy 216.543705 137.92057)
			(xy 216.529965 137.92057) (xy 216.529965 137.9343) (xy 216.516235 137.9343) (xy 216.516235 137.94804)
			(xy 216.502505 137.94804) (xy 216.502505 137.96177) (xy 216.488775 137.96177) (xy 216.488775 137.9755)
			(xy 216.475045 137.9755) (xy 216.475045 137.98923) (xy 216.461315 137.98923) (xy 216.461315 138.00296)
			(xy 216.447575 138.00296) (xy 216.447575 138.0167) (xy 216.433845 138.0167) (xy 216.433845 138.03043)
			(xy 216.420115 138.03043) (xy 216.420115 138.04416) (xy 216.406385 138.04416) (xy 216.406385 138.05789)
			(xy 216.392655 138.05789) (xy 216.392655 138.07162) (xy 216.378925 138.07162) (xy 216.378925 138.08536)
			(xy 216.351455 138.08536) (xy 216.351455 138.09909) (xy 216.337725 138.09909) (xy 216.337725 138.11282)
			(xy 216.323995 138.11282) (xy 216.323995 138.12655) (xy 216.310265 138.12655) (xy 216.310265 138.14028)
			(xy 216.296535 138.14028) (xy 216.296535 138.15401) (xy 216.282795 138.15401) (xy 216.282795 138.16775)
			(xy 216.269065 138.16775) (xy 216.269065 138.18148) (xy 216.255335 138.18148) (xy 216.255335 138.19521)
			(xy 216.241605 138.19521) (xy 216.241605 138.20894) (xy 216.227875 138.20894) (xy 216.227875 138.22267)
			(xy 216.214145 138.22267) (xy 216.214145 138.2364) (xy 216.200405 138.2364) (xy 216.200405 138.25014)
			(xy 216.186675 138.25014) (xy 216.186675 138.26387) (xy 216.172945 138.26387) (xy 216.172945 138.2776)
			(xy 216.159215 138.2776) (xy 216.159215 138.29133) (xy 216.145485 138.29133) (xy 216.145485 138.30506)
			(xy 216.131755 138.30506) (xy 216.131755 138.31879) (xy 216.131755 138.33253) (xy 216.118015 138.33253)
			(xy 216.118015 138.34626) (xy 216.104285 138.34626) (xy 216.104285 138.35999) (xy 216.104285 138.37372)
			(xy 216.090555 138.37372) (xy 216.090555 138.38745) (xy 216.090555 138.40118) (xy 216.076825 138.40118)
			(xy 214.882155 138.40118) (xy 214.882155 138.38745) (xy 214.882155 138.37372) (xy 214.882155 138.35999)
			(xy 214.882155 138.34626) (xy 214.882155 138.33253) (xy 214.882155 138.31879) (xy 214.882155 138.30506)
			(xy 214.882155 138.29133) (xy 214.882155 138.2776) (xy 214.882155 138.26387) (xy 214.882155 138.25014)
			(xy 214.882155 138.2364) (xy 214.882155 138.22267) (xy 214.882155 138.20894) (xy 214.882155 138.19521)
			(xy 214.882155 138.18148) (xy 214.882155 138.16775) (xy 214.882155 138.15401) (xy 214.882155 138.14028)
			(xy 214.882155 138.12655) (xy 214.882155 138.11282) (xy 214.882155 138.09909) (xy 214.882155 138.08536)
			(xy 214.882155 138.07162) (xy 214.882155 138.05789) (xy 214.882155 138.04416) (xy 214.882155 138.03043)
			(xy 214.895895 138.03043) (xy 214.895895 138.0167) (xy 214.909625 138.0167) (xy 214.909625 138.00296)
			(xy 216.269065 138.00296) (xy 216.269065 137.98923) (xy 216.282795 137.98923) (xy 216.282795 138.00296)
			(xy 216.337725 138.00296) (xy 216.337725 137.98923) (xy 216.378925 137.98923) (xy 216.378925 137.9755)
			(xy 216.392655 137.9755) (xy 216.392655 137.96177) (xy 216.406385 137.96177) (xy 216.406385 137.94804)
			(xy 216.406385 137.9343) (xy 216.406385 137.92057) (xy 216.406385 137.90684) (xy 216.406385 137.89311)
			(xy 216.406385 137.87938) (xy 216.406385 137.86565) (xy 216.406385 137.85191) (xy 216.406385 137.83818)
			(xy 216.406385 137.82445) (xy 216.406385 137.81072) (xy 216.406385 137.79699) (xy 216.406385 137.78326)
			(xy 216.406385 137.76952) (xy 216.406385 137.75579) (xy 216.406385 137.74206) (xy 216.406385 137.72833)
			(xy 216.406385 137.7146) (xy 216.406385 137.70087) (xy 216.406385 137.68713) (xy 216.406385 137.6734)
			(xy 216.406385 137.65967) (xy 216.406385 137.64594) (xy 216.406385 137.63221) (xy 216.406385 137.61848)
			(xy 216.406385 137.60474) (xy 216.406385 137.59101) (xy 216.406385 137.57728) (xy 216.406385 137.56355)
			(xy 216.406385 137.54982) (xy 216.406385 137.53609) (xy 216.406385 137.52235) (xy 216.406385 137.50862)
			(xy 216.406385 137.49489) (xy 216.406385 137.48116) (xy 216.406385 137.46743) (xy 216.406385 137.45369)
			(xy 216.406385 137.43996) (xy 216.406385 137.42623) (xy 216.406385 137.4125) (xy 216.406385 137.39877)
			(xy 216.406385 137.38503) (xy 216.406385 137.3713) (xy 216.406385 137.35757) (xy 216.406385 137.34384)
			(xy 216.406385 137.33011) (xy 216.406385 137.31638) (xy 216.406385 137.30264) (xy 216.392655 137.30264)
			(xy 216.392655 137.28891) (xy 216.378925 137.28891) (xy 216.378925 137.27518) (xy 216.337725 137.27518)
			(xy 216.337725 137.26145) (xy 216.310265 137.26145) (xy 216.310265 137.27518) (xy 216.296535 137.27518)
			(xy 216.296535 137.26145) (xy 214.648725 137.26145) (xy 214.648725 137.27518) (xy 214.607525 137.27518)
			(xy 214.607525 137.28891) (xy 214.566335 137.28891) (xy 214.566335 137.30264) (xy 214.538865 137.30264)
			(xy 214.538865 137.31638) (xy 214.525135 137.31638) (xy 214.525135 137.33011) (xy 214.511405 137.33011)
			(xy 214.511405 137.34384) (xy 214.497675 137.34384) (xy 214.497675 137.35757) (xy 214.483935 137.35757)
			(xy 214.483935 137.3713) (xy 214.470205 137.3713) (xy 214.470205 137.38503) (xy 214.456475 137.38503)
			(xy 214.456475 137.39877) (xy 214.442745 137.39877) (xy 214.442745 137.4125) (xy 214.429015 137.4125)
			(xy 214.429015 137.42623) (xy 214.415275 137.42623) (xy 214.415275 137.43996) (xy 214.401545 137.43996)
			(xy 214.401545 137.45369) (xy 214.387815 137.45369) (xy 214.387815 137.46743) (xy 214.374085 137.46743)
			(xy 214.374085 137.48116) (xy 214.360355 137.48116) (xy 214.360355 137.49489) (xy 214.346625 137.49489)
			(xy 214.346625 137.50862) (xy 214.332885 137.50862) (xy 214.332885 137.52235) (xy 214.319155 137.52235)
			(xy 214.319155 137.53609) (xy 214.305425 137.53609) (xy 214.305425 137.54982) (xy 214.291695 137.54982)
			(xy 214.291695 137.56355) (xy 214.277965 137.56355) (xy 214.277965 137.57728) (xy 214.264235 137.57728)
			(xy 214.264235 137.59101) (xy 214.250495 137.59101) (xy 214.250495 137.60474) (xy 214.236765 137.60474)
			(xy 214.236765 137.61848) (xy 214.223035 137.61848) (xy 214.223035 137.63221) (xy 214.209305 137.63221)
			(xy 214.209305 137.64594) (xy 214.195575 137.64594) (xy 214.195575 137.65967) (xy 214.181845 137.65967)
			(xy 214.181845 137.6734) (xy 214.168105 137.6734) (xy 214.168105 137.68713) (xy 214.154375 137.68713)
			(xy 214.154375 137.70087) (xy 214.154375 137.7146) (xy 214.140645 137.7146) (xy 214.140645 137.72833)
			(xy 214.140645 137.74206) (xy 214.140645 137.75579) (xy 214.140645 137.76952) (xy 214.126915 137.76952)
			(xy 212.904785 137.76952) (xy 212.904785 137.75579) (xy 212.904785 137.74206) (xy 212.904785 137.72833)
			(xy 212.904785 137.7146) (xy 212.891055 137.7146) (xy 212.891055 137.70087) (xy 212.891055 137.68713)
			(xy 212.891055 137.6734) (xy 212.891055 137.65967) (xy 212.891055 137.64594) (xy 212.891055 137.63221)
			(xy 212.891055 137.61848) (xy 212.891055 137.60474) (xy 212.891055 137.59101) (xy 212.891055 137.57728)
			(xy 212.877325 137.57728) (xy 212.877325 137.56355) (xy 212.877325 137.54982) (xy 212.877325 137.53609)
			(xy 212.877325 137.52235) (xy 212.877325 137.50862) (xy 212.877325 137.49489) (xy 212.877325 137.48116)
			(xy 212.877325 137.46743) (xy 212.877325 137.45369) (xy 212.877325 137.43996) (xy 212.877325 137.42623)
			(xy 212.877325 137.4125) (xy 212.877325 137.39877) (xy 212.877325 137.38503) (xy 212.877325 137.3713)
			(xy 212.877325 137.35757) (xy 212.863595 137.35757) (xy 212.863595 137.34384) (xy 212.863595 137.33011)
			(xy 212.863595 137.31638) (xy 212.863595 137.30264) (xy 212.863595 137.28891) (xy 212.863595 137.27518)
			(xy 212.698815 137.27518) (xy 212.698815 137.28891) (xy 210.858755 137.28891) (xy 210.858755 137.27518)
			(xy 210.858755 137.26145) (xy 210.858755 137.24772) (xy 210.858755 137.23399) (xy 210.858755 137.22025)
			(xy 210.858755 137.20652) (xy 210.858755 137.19279) (xy 210.858755 137.17906) (xy 210.858755 137.16533)
			(xy 210.858755 137.1516) (xy 210.858755 137.13786) (xy 210.858755 137.12413) (xy 210.858755 137.1104)
			(xy 210.858755 137.09667) (xy 210.858755 137.08294) (xy 210.858755 137.06921) (xy 210.858755 137.05547)
			(xy 210.858755 137.04174) (xy 210.858755 137.02801) (xy 210.858755 137.01428) (xy 210.858755 137.00055)
			(xy 210.858755 136.98682) (xy 210.858755 136.97308) (xy 210.858755 136.95935) (xy 210.858755 136.94562)
			(xy 210.858755 136.93189) (xy 210.858755 136.91816) (xy 210.858755 136.90442) (xy 210.858755 136.89069)
			(xy 210.858755 136.87696) (xy 210.858755 136.86323) (xy 210.858755 136.8495) (xy 210.858755 136.83576)
			(xy 210.858755 136.82203) (xy 210.858755 136.8083) (xy 210.858755 136.79457) (xy 210.858755 136.78084)
			(xy 210.858755 136.76711) (xy 210.858755 136.75337) (xy 210.858755 136.73964) (xy 210.858755 136.72591)
			(xy 210.858755 136.71218) (xy 210.858755 136.69845) (xy 210.858755 136.68472) (xy 210.858755 136.67098)
			(xy 210.858755 136.65725) (xy 210.858755 136.64352) (xy 210.858755 136.62979) (xy 210.858755 136.61606)
			(xy 210.858755 136.60233) (xy 210.858755 136.58859) (xy 210.858755 136.57486) (xy 210.858755 136.56113)
			(xy 210.858755 136.5474) (xy 210.858755 136.53367) (xy 210.858755 136.51994) (xy 210.858755 136.5062)
			(xy 210.858755 136.49247) (xy 210.858755 136.47874) (xy 210.858755 136.46501) (xy 210.858755 136.45128)
			(xy 210.858755 136.43755) (xy 210.858755 136.42381) (xy 210.858755 136.41008) (xy 210.858755 136.39635)
			(xy 210.858755 136.38262) (xy 210.858755 136.36889) (xy 210.858755 136.35515) (xy 210.858755 136.34142)
			(xy 210.858755 136.32769) (xy 210.858755 136.31396) (xy 210.858755 136.30023) (xy 210.858755 136.28649)
			(xy 210.858755 136.27276) (xy 210.858755 136.25903) (xy 210.858755 136.2453) (xy 210.858755 136.23157)
			(xy 210.858755 136.21784) (xy 210.858755 136.2041) (xy 210.858755 136.19037) (xy 210.858755 136.17664)
			(xy 210.858755 136.16291) (xy 209.526775 136.16291) (xy 209.526775 136.14918) (xy 209.526775 136.13545)
			(xy 209.526775 136.12171) (xy 209.526775 136.10798) (xy 209.526775 136.09425) (xy 209.526775 136.08052)
			(xy 209.526775 136.06679) (xy 209.526775 136.05306) (xy 209.526775 136.03932) (xy 209.526775 136.02559)
			(xy 209.526775 136.01186) (xy 209.526775 135.99813) (xy 209.526775 135.9844) (xy 209.526775 135.97067)
			(xy 209.526775 135.95693) (xy 209.526775 135.9432) (xy 209.526775 135.92947) (xy 209.526775 135.91574)
			(xy 209.526775 135.90201) (xy 209.526775 135.88827) (xy 209.526775 135.87454) (xy 209.526775 135.86081)
			(xy 209.526775 135.84708) (xy 209.526775 135.83335) (xy 209.526775 135.81961) (xy 209.526775 135.80588)
			(xy 209.526775 135.79215) (xy 209.526775 135.77842) (xy 209.526775 135.76469) (xy 209.526775 135.75096)
			(xy 209.526775 135.73722) (xy 209.526775 135.72349) (xy 209.526775 135.70976) (xy 209.526775 135.69603)
			(xy 209.526775 135.6823) (xy 209.526775 135.66857) (xy 209.526775 135.65483) (xy 209.526775 135.6411)
			(xy 209.526775 135.62737) (xy 209.526775 135.61364) (xy 209.526775 135.59991) (xy 209.526775 135.58618)
			(xy 209.526775 135.57244) (xy 209.526775 135.55871) (xy 209.526775 135.54498) (xy 209.526775 135.53125)
			(xy 209.526775 135.51752) (xy 209.526775 135.50379) (xy 209.526775 135.49005) (xy 209.526775 135.47632)
			(xy 209.526775 135.46259) (xy 209.526775 135.44886) (xy 209.526775 135.43513) (xy 209.526775 135.4214)
			(xy 209.526775 135.40766) (xy 209.526775 135.39393) (xy 209.526775 135.3802) (xy 209.526775 135.36647)
			(xy 209.526775 135.35274) (xy 209.526775 135.339) (xy 209.526775 135.32527) (xy 209.526775 135.31154)
			(xy 209.526775 135.29781) (xy 209.526775 135.28408) (xy 209.526775 135.27034) (xy 209.526775 135.25661)
			(xy 209.526775 135.24288) (xy 209.526775 135.22915) (xy 209.526775 135.21542) (xy 209.526775 135.20169)
			(xy 209.526775 135.18795) (xy 209.526775 135.17422) (xy 209.526775 135.16049) (xy 209.526775 135.14676)
			(xy 209.526775 135.13303) (xy 209.526775 135.1193) (xy 209.526775 135.10556) (xy 209.526775 135.09183)
			(xy 209.526775 135.0781) (xy 209.526775 135.06437) (xy 209.526775 135.05064) (xy 209.526775 135.03691)
			(xy 209.526775 135.02317) (xy 209.526775 135.00944) (xy 209.526775 134.99571) (xy 209.526775 134.98198)
			(xy 209.526775 134.96825) (xy 209.526775 134.95452) (xy 209.526775 134.94078) (xy 209.526775 134.92705)
			(xy 209.526775 134.91332) (xy 209.526775 134.89959) (xy 209.526775 134.88586) (xy 209.526775 134.87213)
			(xy 209.526775 134.85839) (xy 209.526775 134.84466) (xy 209.526775 134.83093) (xy 209.526775 134.8172)
			(xy 209.526775 134.80347) (xy 209.526775 134.78973) (xy 209.526775 134.776) (xy 209.526775 134.76227)
			(xy 209.526775 134.74854) (xy 209.526775 134.73481) (xy 209.526775 134.72107) (xy 209.526775 134.70734)
			(xy 209.526775 134.69361) (xy 209.526775 134.67988) (xy 209.526775 134.66615) (xy 209.526775 134.65242)
			(xy 209.526775 134.63868) (xy 209.526775 134.62495) (xy 209.526775 134.61122) (xy 209.526775 134.59749)
			(xy 209.526775 134.58376) (xy 209.526775 134.57003) (xy 209.526775 134.55629) (xy 209.526775 134.54256)
			(xy 209.526775 134.52883) (xy 209.526775 134.5151) (xy 209.526775 134.50137) (xy 209.526775 134.48764)
			(xy 209.526775 134.4739) (xy 209.526775 134.46017) (xy 209.526775 134.44644) (xy 209.526775 134.43271)
			(xy 209.526775 134.41898) (xy 209.526775 134.40525) (xy 209.526775 134.39151) (xy 209.526775 134.37778)
			(xy 209.526775 134.36405) (xy 209.526775 134.35032) (xy 209.526775 134.33659) (xy 209.526775 134.32286)
			(xy 209.526775 134.30912) (xy 209.526775 134.29539) (xy 209.526775 134.28166) (xy 209.526775 134.26793)
			(xy 209.526775 134.2542) (xy 209.526775 134.24046) (xy 209.526775 134.22673) (xy 209.526775 134.213)
			(xy 209.526775 134.19927) (xy 209.526775 134.18554) (xy 209.526775 134.1718) (xy 209.526775 134.15807)
			(xy 209.526775 134.14434) (xy 209.526775 134.13061) (xy 209.526775 134.11688) (xy 209.526775 134.10315)
			(xy 209.526775 134.08941) (xy 209.526775 134.07568) (xy 211.586535 134.07568) (xy 211.586535 134.08941)
			(xy 211.586535 134.10315) (xy 211.586535 134.11688) (xy 211.586535 134.13061) (xy 211.586535 134.14434)
			(xy 211.586535 134.15807) (xy 211.586535 134.1718) (xy 211.586535 134.18554) (xy 211.586535 134.19927)
			(xy 211.586535 134.213) (xy 211.586535 134.22673) (xy 211.586535 134.24046) (xy 211.586535 134.2542)
			(xy 211.586535 134.26793) (xy 211.586535 134.28166) (xy 211.586535 134.29539) (xy 211.586535 134.30912)
			(xy 211.586535 134.32286) (xy 211.586535 134.33659) (xy 211.586535 134.35032) (xy 211.586535 134.36405)
			(xy 211.586535 134.37778) (xy 211.586535 134.39151) (xy 211.586535 134.40525) (xy 211.586535 134.41898)
			(xy 211.586535 134.43271) (xy 211.586535 134.44644) (xy 211.586535 134.46017) (xy 211.586535 134.4739)
			(xy 211.586535 134.48764) (xy 211.586535 134.50137) (xy 211.586535 134.5151) (xy 211.586535 134.52883)
			(xy 211.586535 134.54256) (xy 211.586535 134.55629) (xy 211.586535 134.57003) (xy 211.586535 134.58376)
			(xy 211.586535 134.59749) (xy 211.586535 134.61122) (xy 211.586535 134.62495) (xy 211.586535 134.63868)
			(xy 211.586535 134.65242) (xy 211.586535 134.66615) (xy 211.586535 134.67988) (xy 211.586535 134.69361)
			(xy 211.586535 134.70734) (xy 211.600275 134.70734) (xy 211.600275 134.72107) (xy 211.614005 134.72107)
			(xy 211.614005 134.73481) (xy 211.627735 134.73481) (xy 211.627735 134.74854) (xy 211.655195 134.74854)
			(xy 211.655195 134.76227) (xy 212.314325 134.76227) (xy 212.314325 134.776) (xy 212.328055 134.776)
			(xy 212.328055 134.78973) (xy 212.341785 134.78973) (xy 212.341785 134.80347) (xy 212.341785 134.8172)
			(xy 212.355515 134.8172) (xy 212.355515 134.83093) (xy 212.355515 134.84466) (xy 212.355515 134.85839)
			(xy 212.355515 134.87213) (xy 212.355515 134.88586) (xy 212.355515 134.89959) (xy 212.355515 134.91332)
			(xy 212.355515 134.92705) (xy 212.355515 134.94078) (xy 212.355515 134.95452) (xy 212.355515 134.96825)
			(xy 212.355515 134.98198) (xy 212.355515 134.99571) (xy 212.355515 135.00944) (xy 212.355515 135.02317)
			(xy 212.355515 135.03691) (xy 212.355515 135.05064) (xy 212.355515 135.06437) (xy 212.355515 135.0781)
			(xy 212.355515 135.09183) (xy 212.355515 135.10556) (xy 212.355515 135.1193) (xy 212.355515 135.13303)
			(xy 212.355515 135.14676) (xy 212.355515 135.16049) (xy 212.355515 135.17422) (xy 212.355515 135.18795)
			(xy 212.355515 135.20169) (xy 212.355515 135.21542) (xy 212.355515 135.22915) (xy 212.355515 135.24288)
			(xy 212.355515 135.25661) (xy 212.355515 135.27034) (xy 212.355515 135.28408) (xy 212.355515 135.29781)
			(xy 212.355515 135.31154) (xy 212.355515 135.32527) (xy 212.355515 135.339) (xy 212.355515 135.35274)
			(xy 212.355515 135.36647) (xy 212.355515 135.3802) (xy 212.355515 135.39393) (xy 212.355515 135.40766)
			(xy 212.355515 135.4214) (xy 212.355515 135.43513) (xy 212.355515 135.44886) (xy 212.355515 135.46259)
			(xy 212.355515 135.47632) (xy 212.355515 135.49005) (xy 212.355515 135.50379) (xy 212.355515 135.51752)
			(xy 212.355515 135.53125) (xy 212.355515 135.54498) (xy 212.355515 135.55871) (xy 212.355515 135.57244)
			(xy 212.355515 135.58618) (xy 212.355515 135.59991) (xy 212.355515 135.61364) (xy 212.355515 135.62737)
			(xy 212.355515 135.6411) (xy 212.355515 135.65483) (xy 212.355515 135.66857) (xy 212.355515 135.6823)
			(xy 212.355515 135.69603) (xy 212.355515 135.70976) (xy 212.355515 135.72349) (xy 212.355515 135.73722)
			(xy 212.355515 135.75096) (xy 212.355515 135.76469) (xy 212.355515 135.77842) (xy 212.355515 135.79215)
			(xy 212.355515 135.80588) (xy 212.355515 135.81961) (xy 212.355515 135.83335) (xy 212.355515 135.84708)
			(xy 212.355515 135.86081) (xy 212.355515 135.87454) (xy 212.355515 135.88827) (xy 212.355515 135.90201)
			(xy 212.355515 135.91574) (xy 212.355515 135.92947) (xy 212.355515 135.9432) (xy 212.355515 135.95693)
			(xy 212.355515 135.97067) (xy 212.355515 135.9844) (xy 212.355515 135.99813) (xy 212.355515 136.01186)
			(xy 212.355515 136.02559) (xy 212.355515 136.03932) (xy 212.355515 136.05306) (xy 212.355515 136.06679)
			(xy 212.355515 136.08052) (xy 212.355515 136.09425) (xy 212.355515 136.10798) (xy 212.355515 136.12171)
			(xy 212.355515 136.13545) (xy 212.355515 136.14918) (xy 212.355515 136.16291) (xy 212.355515 136.17664)
			(xy 212.355515 136.19037) (xy 212.355515 136.2041) (xy 212.355515 136.21784) (xy 212.355515 136.23157)
			(xy 212.355515 136.2453) (xy 212.355515 136.25903) (xy 212.355515 136.27276) (xy 212.355515 136.28649)
			(xy 212.355515 136.30023) (xy 212.355515 136.31396) (xy 212.355515 136.32769) (xy 212.355515 136.34142)
			(xy 212.355515 136.35515) (xy 212.355515 136.36889) (xy 212.355515 136.38262) (xy 212.355515 136.39635)
			(xy 212.355515 136.41008) (xy 212.355515 136.42381) (xy 212.355515 136.43755) (xy 212.355515 136.45128)
			(xy 212.355515 136.46501) (xy 212.355515 136.47874) (xy 212.355515 136.49247) (xy 212.355515 136.5062)
			(xy 212.355515 136.51994) (xy 212.355515 136.53367) (xy 212.355515 136.5474) (xy 212.355515 136.56113)
			(xy 212.355515 136.57486) (xy 212.355515 136.58859) (xy 212.355515 136.60233) (xy 212.355515 136.61606)
			(xy 212.355515 136.62979) (xy 212.355515 136.64352) (xy 212.355515 136.65725) (xy 212.355515 136.67098)
			(xy 212.355515 136.68472) (xy 212.355515 136.69845) (xy 212.355515 136.71218) (xy 212.355515 136.72591)
			(xy 212.355515 136.73964) (xy 212.355515 136.75337) (xy 212.355515 136.76711) (xy 212.355515 136.78084)
			(xy 212.355515 136.79457) (xy 212.355515 136.8083) (xy 212.355515 136.82203) (xy 212.355515 136.83576)
			(xy 212.355515 136.8495) (xy 212.355515 136.86323) (xy 212.355515 136.87696) (xy 212.355515 136.89069)
			(xy 212.355515 136.90442) (xy 212.355515 136.91816) (xy 212.355515 136.93189) (xy 212.355515 136.94562)
			(xy 212.355515 136.95935) (xy 212.355515 136.97308) (xy 212.369255 136.97308) (xy 212.369255 136.98682)
			(xy 212.382985 136.98682) (xy 212.382985 137.00055) (xy 212.396715 137.00055) (xy 212.396715 137.01428)
			(xy 213.069565 137.01428) (xy 213.069565 137.00055) (xy 213.083305 137.00055) (xy 213.083305 136.98682)
			(xy 213.097035 136.98682) (xy 213.097035 136.97308) (xy 213.097035 136.95935) (xy 213.097035 136.94562)
			(xy 213.110765 136.94562) (xy 213.110765 136.93189) (xy 213.110765 136.91816) (xy 213.110765 136.90442)
			(xy 213.110765 136.89069) (xy 213.110765 136.87696) (xy 213.110765 136.86323) (xy 213.110765 136.8495)
			(xy 213.110765 136.83576) (xy 213.110765 136.82203) (xy 213.110765 136.8083) (xy 213.110765 136.79457)
			(xy 213.110765 136.78084) (xy 213.110765 136.76711) (xy 213.110765 136.75337) (xy 213.110765 136.73964)
			(xy 213.110765 136.72591) (xy 213.110765 136.71218) (xy 213.110765 136.69845) (xy 213.110765 136.68472)
			(xy 213.110765 136.67098) (xy 213.110765 136.65725) (xy 213.110765 136.64352) (xy 213.110765 136.62979)
			(xy 213.110765 136.61606) (xy 213.110765 136.60233) (xy 213.110765 136.58859) (xy 213.110765 136.57486)
			(xy 213.110765 136.56113) (xy 213.110765 136.5474) (xy 213.110765 136.53367) (xy 213.110765 136.51994)
			(xy 213.110765 136.5062) (xy 213.110765 136.49247) (xy 213.110765 136.47874) (xy 213.110765 136.46501)
			(xy 213.110765 136.45128) (xy 213.110765 136.43755) (xy 213.110765 136.42381) (xy 213.110765 136.41008)
			(xy 213.110765 136.39635) (xy 213.110765 136.38262) (xy 213.110765 136.36889) (xy 213.110765 136.35515)
			(xy 213.110765 136.34142) (xy 213.110765 136.32769) (xy 213.110765 136.31396) (xy 213.110765 136.30023)
			(xy 213.110765 136.28649) (xy 213.110765 136.27276) (xy 213.110765 136.25903) (xy 213.110765 136.2453)
			(xy 213.110765 136.23157) (xy 213.110765 136.21784) (xy 213.110765 136.2041) (xy 213.110765 136.19037)
			(xy 213.110765 136.17664) (xy 213.110765 136.16291) (xy 213.110765 136.14918) (xy 213.110765 136.13545)
			(xy 213.110765 136.12171) (xy 213.110765 136.10798) (xy 213.110765 136.09425) (xy 213.110765 136.08052)
			(xy 213.110765 136.06679) (xy 213.110765 136.05306) (xy 213.110765 136.03932) (xy 213.110765 136.02559)
			(xy 213.110765 136.01186) (xy 213.110765 135.99813) (xy 213.110765 135.9844) (xy 213.110765 135.97067)
			(xy 213.110765 135.95693) (xy 213.110765 135.9432) (xy 213.110765 135.92947) (xy 213.110765 135.91574)
			(xy 213.110765 135.90201) (xy 213.110765 135.88827) (xy 213.110765 135.87454) (xy 213.110765 135.86081)
			(xy 213.110765 135.84708) (xy 213.110765 135.83335) (xy 213.110765 135.81961) (xy 213.110765 135.80588)
			(xy 213.110765 135.79215) (xy 213.110765 135.77842) (xy 213.110765 135.76469) (xy 213.110765 135.75096)
			(xy 213.110765 135.73722) (xy 213.110765 135.72349) (xy 213.110765 135.70976) (xy 213.110765 135.69603)
			(xy 213.110765 135.6823) (xy 213.110765 135.66857) (xy 213.110765 135.65483) (xy 213.110765 135.6411)
			(xy 213.110765 135.62737) (xy 213.110765 135.61364) (xy 213.110765 135.59991) (xy 213.110765 135.58618)
			(xy 213.110765 135.57244) (xy 213.110765 135.55871) (xy 213.110765 135.54498) (xy 213.110765 135.53125)
			(xy 213.110765 135.51752) (xy 213.110765 135.50379) (xy 213.110765 135.49005) (xy 213.110765 135.47632)
			(xy 213.110765 135.46259) (xy 213.110765 135.44886) (xy 213.110765 135.43513) (xy 213.110765 135.4214)
			(xy 213.110765 135.40766) (xy 213.110765 135.39393) (xy 213.110765 135.3802) (xy 213.110765 135.36647)
			(xy 213.110765 135.35274) (xy 213.110765 135.339) (xy 213.110765 135.32527) (xy 213.110765 135.31154)
			(xy 213.110765 135.29781) (xy 213.110765 135.28408) (xy 213.110765 135.27034) (xy 213.110765 135.25661)
			(xy 213.110765 135.24288) (xy 213.110765 135.22915) (xy 213.110765 135.21542) (xy 213.110765 135.20169)
			(xy 213.110765 135.18795) (xy 213.110765 135.17422) (xy 213.110765 135.16049) (xy 213.110765 135.14676)
			(xy 213.110765 135.13303) (xy 213.110765 135.1193) (xy 213.110765 135.10556) (xy 213.110765 135.09183)
			(xy 213.110765 135.0781) (xy 213.110765 135.06437) (xy 213.110765 135.05064) (xy 213.110765 135.03691)
			(xy 213.110765 135.02317) (xy 213.110765 135.00944) (xy 213.110765 134.99571) (xy 213.110765 134.98198)
			(xy 213.110765 134.96825) (xy 213.110765 134.95452) (xy 213.110765 134.94078) (xy 213.110765 134.92705)
			(xy 213.110765 134.91332) (xy 213.110765 134.89959) (xy 213.110765 134.88586) (xy 213.110765 134.87213)
			(xy 213.110765 134.85839) (xy 213.110765 134.84466) (xy 213.110765 134.83093) (xy 213.110765 134.8172)
			(xy 213.110765 134.80347) (xy 213.110765 134.78973) (xy 213.124495 134.78973) (xy 213.124495 134.776)
			(xy 213.138225 134.776) (xy 213.138225 134.76227) (xy 213.797355 134.76227) (xy 213.797355 134.74854)
			(xy 213.838545 134.74854) (xy 213.838545 134.73481) (xy 213.852275 134.73481) (xy 213.852275 134.72107)
			(xy 213.866005 134.72107) (xy 213.866005 134.70734) (xy 213.866005 134.69361) (xy 213.866005 134.67988)
			(xy 213.879745 134.67988) (xy 213.879745 134.66615) (xy 213.879745 134.65242) (xy 213.879745 134.63868)
			(xy 213.879745 134.62495) (xy 213.879745 134.61122) (xy 213.879745 134.59749) (xy 213.879745 134.58376)
			(xy 213.879745 134.57003) (xy 213.879745 134.55629) (xy 213.879745 134.54256) (xy 213.879745 134.52883)
			(xy 213.879745 134.5151) (xy 213.879745 134.50137) (xy 213.879745 134.48764) (xy 213.879745 134.4739)
			(xy 213.879745 134.46017) (xy 213.879745 134.44644) (xy 213.879745 134.43271) (xy 213.879745 134.41898)
			(xy 213.879745 134.40525) (xy 213.879745 134.39151) (xy 213.879745 134.37778) (xy 213.879745 134.36405)
			(xy 213.879745 134.35032) (xy 213.879745 134.33659) (xy 213.879745 134.32286) (xy 213.879745 134.30912)
			(xy 213.879745 134.29539) (xy 213.879745 134.28166) (xy 213.879745 134.26793) (xy 213.879745 134.2542)
			(xy 213.879745 134.24046) (xy 213.879745 134.22673) (xy 213.879745 134.213) (xy 213.879745 134.19927)
			(xy 213.879745 134.18554) (xy 213.879745 134.1718) (xy 213.879745 134.15807) (xy 213.879745 134.14434)
			(xy 213.879745 134.13061) (xy 213.879745 134.11688) (xy 213.879745 134.10315) (xy 213.866005 134.10315)
			(xy 213.866005 134.08941) (xy 214.044525 134.08941) (xy 214.044525 134.10315) (xy 214.044525 134.11688)
			(xy 214.044525 134.13061) (xy 214.044525 134.14434) (xy 214.044525 134.15807) (xy 214.044525 134.1718)
			(xy 214.044525 134.18554) (xy 214.044525 134.19927) (xy 214.044525 134.213) (xy 214.044525 134.22673)
			(xy 214.044525 134.24046) (xy 214.044525 134.2542) (xy 214.044525 134.26793) (xy 214.044525 134.28166)
			(xy 214.044525 134.29539) (xy 214.044525 134.30912) (xy 214.044525 134.32286) (xy 214.044525 134.33659)
			(xy 214.044525 134.35032) (xy 214.044525 134.36405) (xy 214.044525 134.37778) (xy 214.044525 134.39151)
			(xy 214.044525 134.40525) (xy 214.044525 134.41898) (xy 214.044525 134.43271) (xy 214.044525 134.44644)
			(xy 214.044525 134.46017) (xy 214.044525 134.4739) (xy 214.044525 134.48764) (xy 214.044525 134.50137)
			(xy 214.044525 134.5151) (xy 214.044525 134.52883) (xy 214.044525 134.54256) (xy 214.044525 134.55629)
			(xy 214.044525 134.57003) (xy 214.044525 134.58376) (xy 214.044525 134.59749) (xy 214.044525 134.61122)
			(xy 214.044525 134.62495) (xy 214.044525 134.63868) (xy 214.044525 134.65242) (xy 214.044525 134.66615)
			(xy 214.044525 134.67988) (xy 214.044525 134.69361) (xy 214.044525 134.70734) (xy 214.044525 134.72107)
			(xy 214.044525 134.73481) (xy 214.044525 134.74854) (xy 214.044525 134.76227) (xy 214.044525 134.776)
			(xy 214.044525 134.78973) (xy 214.044525 134.80347) (xy 214.044525 134.8172) (xy 214.044525 134.83093)
			(xy 214.044525 134.84466) (xy 214.044525 134.85839) (xy 214.044525 134.87213) (xy 214.044525 134.88586)
			(xy 214.044525 134.89959) (xy 214.044525 134.91332) (xy 214.044525 134.92705) (xy 214.044525 134.94078)
			(xy 214.044525 134.95452) (xy 214.044525 134.96825) (xy 214.044525 134.98198) (xy 214.044525 134.99571)
			(xy 214.044525 135.00944) (xy 214.044525 135.02317) (xy 214.044525 135.03691) (xy 214.044525 135.05064)
			(xy 214.044525 135.06437) (xy 214.044525 135.0781) (xy 214.044525 135.09183) (xy 214.044525 135.10556)
			(xy 214.044525 135.1193) (xy 214.044525 135.13303) (xy 214.044525 135.14676) (xy 214.044525 135.16049)
			(xy 214.044525 135.17422) (xy 214.044525 135.18795) (xy 214.044525 135.20169) (xy 214.044525 135.21542)
			(xy 214.044525 135.22915) (xy 214.044525 135.24288) (xy 214.044525 135.25661) (xy 214.044525 135.27034)
			(xy 214.044525 135.28408) (xy 214.044525 135.29781) (xy 214.044525 135.31154) (xy 214.044525 135.32527)
			(xy 214.044525 135.339) (xy 214.044525 135.35274) (xy 214.044525 135.36647) (xy 214.044525 135.3802)
			(xy 214.044525 135.39393) (xy 214.044525 135.40766) (xy 214.044525 135.4214) (xy 214.044525 135.43513)
			(xy 214.044525 135.44886) (xy 214.044525 135.46259) (xy 214.044525 135.47632) (xy 214.044525 135.49005)
			(xy 214.044525 135.50379) (xy 214.044525 135.51752) (xy 214.044525 135.53125) (xy 214.044525 135.54498)
			(xy 214.044525 135.55871) (xy 214.044525 135.57244) (xy 214.044525 135.58618) (xy 214.044525 135.59991)
			(xy 214.044525 135.61364) (xy 214.044525 135.62737) (xy 214.044525 135.6411) (xy 214.044525 135.65483)
			(xy 214.044525 135.66857) (xy 214.044525 135.6823) (xy 214.044525 135.69603) (xy 214.044525 135.70976)
			(xy 214.044525 135.72349) (xy 214.044525 135.73722) (xy 214.044525 135.75096) (xy 214.044525 135.76469)
			(xy 214.044525 135.77842) (xy 214.044525 135.79215) (xy 214.044525 135.80588) (xy 214.044525 135.81961)
			(xy 214.044525 135.83335) (xy 214.044525 135.84708) (xy 214.044525 135.86081) (xy 214.044525 135.87454)
			(xy 214.044525 135.88827) (xy 214.044525 135.90201) (xy 214.044525 135.91574) (xy 214.044525 135.92947)
			(xy 214.044525 135.9432) (xy 214.044525 135.95693) (xy 214.044525 135.97067) (xy 214.044525 135.9844)
			(xy 214.044525 135.99813) (xy 214.044525 136.01186) (xy 214.044525 136.02559) (xy 214.044525 136.03932)
			(xy 214.044525 136.05306) (xy 214.044525 136.06679) (xy 214.044525 136.08052) (xy 214.044525 136.09425)
			(xy 214.044525 136.10798) (xy 214.044525 136.12171) (xy 214.044525 136.13545) (xy 214.044525 136.14918)
			(xy 214.044525 136.16291) (xy 214.044525 136.17664) (xy 214.044525 136.19037) (xy 214.044525 136.2041)
			(xy 214.044525 136.21784) (xy 214.044525 136.23157) (xy 214.044525 136.2453) (xy 214.044525 136.25903)
			(xy 214.044525 136.27276) (xy 214.044525 136.28649) (xy 214.044525 136.30023) (xy 214.044525 136.31396)
			(xy 214.044525 136.32769) (xy 214.044525 136.34142) (xy 214.044525 136.35515) (xy 214.044525 136.36889)
			(xy 214.044525 136.38262) (xy 214.044525 136.39635) (xy 214.044525 136.41008) (xy 214.044525 136.42381)
			(xy 214.044525 136.43755) (xy 214.044525 136.45128) (xy 214.044525 136.46501) (xy 214.044525 136.47874)
			(xy 214.044525 136.49247) (xy 214.044525 136.5062) (xy 214.044525 136.51994) (xy 214.044525 136.53367)
			(xy 214.044525 136.5474) (xy 214.044525 136.56113) (xy 214.044525 136.57486) (xy 214.044525 136.58859)
			(xy 214.044525 136.60233) (xy 214.044525 136.61606) (xy 214.044525 136.62979) (xy 214.044525 136.64352)
			(xy 214.044525 136.65725) (xy 214.044525 136.67098) (xy 214.044525 136.68472) (xy 214.044525 136.69845)
			(xy 214.044525 136.71218) (xy 214.044525 136.72591) (xy 214.044525 136.73964) (xy 214.044525 136.75337)
			(xy 214.044525 136.76711) (xy 214.044525 136.78084) (xy 214.044525 136.79457) (xy 214.044525 136.8083)
			(xy 214.044525 136.82203) (xy 214.044525 136.83576) (xy 214.044525 136.8495) (xy 214.044525 136.86323)
			(xy 214.044525 136.87696) (xy 214.044525 136.89069) (xy 214.044525 136.90442) (xy 214.044525 136.91816)
			(xy 214.044525 136.93189) (xy 214.044525 136.94562) (xy 214.044525 136.95935) (xy 214.058255 136.95935)
			(xy 214.058255 136.97308) (xy 214.058255 136.98682) (xy 214.071985 136.98682) (xy 214.071985 137.00055)
			(xy 214.085715 137.00055) (xy 214.085715 137.01428) (xy 214.772305 137.01428) (xy 214.772305 137.00055)
			(xy 214.786035 137.00055) (xy 214.786035 136.98682) (xy 214.799765 136.98682) (xy 214.799765 136.97308)
			(xy 214.799765 136.95935) (xy 214.799765 136.94562) (xy 214.799765 136.93189) (xy 214.799765 136.91816)
			(xy 214.799765 136.90442) (xy 214.799765 136.89069) (xy 214.799765 136.87696) (xy 214.799765 136.86323)
			(xy 214.799765 136.8495) (xy 214.799765 136.83576) (xy 214.799765 136.82203) (xy 214.799765 136.8083)
			(xy 214.799765 136.79457) (xy 214.799765 136.78084) (xy 214.799765 136.76711) (xy 214.799765 136.75337)
			(xy 214.799765 136.73964) (xy 214.799765 136.72591) (xy 214.799765 136.71218) (xy 214.799765 136.69845)
			(xy 214.799765 136.68472) (xy 214.799765 136.67098) (xy 214.799765 136.65725) (xy 214.799765 136.64352)
			(xy 214.799765 136.62979) (xy 214.799765 136.61606) (xy 214.799765 136.60233) (xy 214.799765 136.58859)
			(xy 214.799765 136.57486) (xy 214.799765 136.56113) (xy 214.799765 136.5474) (xy 214.799765 136.53367)
			(xy 214.799765 136.51994) (xy 214.799765 136.5062) (xy 214.799765 136.49247) (xy 214.799765 136.47874)
			(xy 214.799765 136.46501) (xy 214.799765 136.45128) (xy 214.799765 136.43755) (xy 214.799765 136.42381)
			(xy 214.799765 136.41008) (xy 214.799765 136.39635) (xy 214.799765 136.38262) (xy 214.799765 136.36889)
			(xy 214.799765 136.35515) (xy 214.799765 136.34142) (xy 214.799765 136.32769) (xy 214.799765 136.31396)
			(xy 214.799765 136.30023) (xy 214.799765 136.28649) (xy 214.799765 136.27276) (xy 214.799765 136.25903)
			(xy 214.799765 136.2453) (xy 214.799765 136.23157) (xy 214.799765 136.21784) (xy 214.799765 136.2041)
			(xy 214.799765 136.19037) (xy 214.799765 136.17664) (xy 214.799765 136.16291) (xy 214.799765 136.14918)
			(xy 214.799765 136.13545) (xy 214.799765 136.12171) (xy 214.799765 136.10798) (xy 214.799765 136.09425)
			(xy 214.799765 136.08052) (xy 214.799765 136.06679) (xy 214.799765 136.05306) (xy 214.799765 136.03932)
			(xy 214.799765 136.02559) (xy 214.799765 136.01186) (xy 214.799765 135.99813) (xy 214.799765 135.9844)
			(xy 214.799765 135.97067) (xy 214.799765 135.95693) (xy 214.799765 135.9432) (xy 214.799765 135.92947)
			(xy 214.799765 135.91574) (xy 214.799765 135.90201) (xy 214.799765 135.88827) (xy 214.799765 135.87454)
			(xy 214.799765 135.86081) (xy 214.799765 135.84708) (xy 214.799765 135.83335) (xy 214.799765 135.81961)
			(xy 214.799765 135.80588) (xy 214.799765 135.79215) (xy 214.799765 135.77842) (xy 214.799765 135.76469)
			(xy 214.799765 135.75096) (xy 214.799765 135.73722) (xy 214.799765 135.72349) (xy 214.799765 135.70976)
			(xy 214.799765 135.69603) (xy 214.799765 135.6823) (xy 214.799765 135.66857) (xy 214.799765 135.65483)
			(xy 214.799765 135.6411) (xy 214.799765 135.62737) (xy 214.799765 135.61364) (xy 214.799765 135.59991)
			(xy 214.799765 135.58618) (xy 214.799765 135.57244) (xy 214.799765 135.55871) (xy 214.799765 135.54498)
			(xy 214.799765 135.53125) (xy 214.799765 135.51752) (xy 214.799765 135.50379) (xy 214.799765 135.49005)
			(xy 214.799765 135.47632) (xy 214.799765 135.46259) (xy 214.799765 135.44886) (xy 214.799765 135.43513)
			(xy 214.799765 135.4214) (xy 214.799765 135.40766) (xy 214.799765 135.39393) (xy 214.799765 135.3802)
			(xy 214.799765 135.36647) (xy 214.799765 135.35274) (xy 214.799765 135.339) (xy 214.799765 135.32527)
			(xy 214.799765 135.31154) (xy 214.799765 135.29781) (xy 214.799765 135.28408) (xy 214.799765 135.27034)
			(xy 214.799765 135.25661) (xy 214.799765 135.24288) (xy 214.799765 135.22915) (xy 214.799765 135.21542)
			(xy 214.799765 135.20169) (xy 214.799765 135.18795) (xy 214.799765 135.17422) (xy 214.799765 135.16049)
			(xy 214.799765 135.14676) (xy 214.799765 135.13303) (xy 214.799765 135.1193) (xy 214.799765 135.10556)
			(xy 214.799765 135.09183) (xy 214.799765 135.0781) (xy 214.799765 135.06437) (xy 214.799765 135.05064)
			(xy 214.799765 135.03691) (xy 214.799765 135.02317) (xy 214.799765 135.00944) (xy 214.799765 134.99571)
			(xy 214.799765 134.98198) (xy 214.799765 134.96825) (xy 214.799765 134.95452) (xy 214.799765 134.94078)
			(xy 214.799765 134.92705) (xy 214.799765 134.91332) (xy 214.799765 134.89959) (xy 214.799765 134.88586)
			(xy 214.799765 134.87213) (xy 214.799765 134.85839) (xy 214.799765 134.84466) (xy 214.799765 134.83093)
			(xy 214.799765 134.8172) (xy 214.799765 134.80347) (xy 214.799765 134.78973) (xy 214.799765 134.776)
			(xy 214.799765 134.76227) (xy 214.799765 134.74854) (xy 214.799765 134.73481) (xy 214.799765 134.72107)
			(xy 214.799765 134.70734) (xy 214.799765 134.69361) (xy 214.799765 134.67988) (xy 214.799765 134.66615)
			(xy 214.799765 134.65242) (xy 214.799765 134.63868) (xy 214.799765 134.62495) (xy 214.799765 134.61122)
			(xy 214.799765 134.59749) (xy 214.799765 134.58376) (xy 214.799765 134.57003) (xy 214.799765 134.55629)
			(xy 214.799765 134.54256) (xy 214.799765 134.52883) (xy 214.799765 134.5151) (xy 214.799765 134.50137)
			(xy 214.799765 134.48764) (xy 214.799765 134.4739) (xy 214.799765 134.46017) (xy 214.799765 134.44644)
			(xy 214.799765 134.43271) (xy 214.799765 134.41898) (xy 214.799765 134.40525) (xy 214.799765 134.39151)
			(xy 214.799765 134.37778) (xy 214.799765 134.36405) (xy 214.799765 134.35032) (xy 214.799765 134.33659)
			(xy 214.799765 134.32286) (xy 214.799765 134.30912) (xy 214.799765 134.29539) (xy 214.799765 134.28166)
			(xy 214.799765 134.26793) (xy 214.799765 134.2542) (xy 214.799765 134.24046) (xy 214.799765 134.22673)
			(xy 214.799765 134.213) (xy 214.799765 134.19927) (xy 214.799765 134.18554) (xy 214.799765 134.1718)
			(xy 214.799765 134.15807) (xy 214.799765 134.14434) (xy 214.799765 134.13061) (xy 214.799765 134.11688)
			(xy 214.799765 134.10315) (xy 214.799765 134.08941) (xy 214.799765 134.07568) (xy 215.143065 134.07568)
			(xy 215.143065 134.08941) (xy 215.143065 134.10315) (xy 215.143065 134.11688) (xy 215.143065 134.13061)
			(xy 215.143065 134.14434) (xy 215.143065 134.15807) (xy 215.143065 134.1718) (xy 215.143065 134.18554)
			(xy 215.143065 134.19927) (xy 215.143065 134.213) (xy 215.143065 134.22673) (xy 215.143065 134.24046)
			(xy 215.143065 134.2542) (xy 215.143065 134.26793) (xy 215.143065 134.28166) (xy 215.143065 134.29539)
			(xy 215.143065 134.30912) (xy 215.143065 134.32286) (xy 215.143065 134.33659) (xy 215.143065 134.35032)
			(xy 215.143065 134.36405) (xy 215.143065 134.37778) (xy 215.143065 134.39151) (xy 215.143065 134.40525)
			(xy 215.143065 134.41898) (xy 215.143065 134.43271) (xy 215.143065 134.44644) (xy 215.143065 134.46017)
			(xy 215.143065 134.4739) (xy 215.143065 134.48764) (xy 215.143065 134.50137) (xy 215.143065 134.5151)
			(xy 215.143065 134.52883) (xy 215.143065 134.54256) (xy 215.143065 134.55629) (xy 215.143065 134.57003)
			(xy 215.143065 134.58376) (xy 215.143065 134.59749) (xy 215.143065 134.61122) (xy 215.143065 134.62495)
			(xy 215.143065 134.63868) (xy 215.143065 134.65242) (xy 215.143065 134.66615) (xy 215.143065 134.67988)
			(xy 215.143065 134.69361) (xy 215.143065 134.70734) (xy 215.143065 134.72107) (xy 215.143065 134.73481)
			(xy 215.143065 134.74854) (xy 215.143065 134.76227) (xy 215.143065 134.776) (xy 215.143065 134.78973)
			(xy 215.143065 134.80347) (xy 215.143065 134.8172) (xy 215.143065 134.83093) (xy 215.143065 134.84466)
			(xy 215.143065 134.85839) (xy 215.143065 134.87213) (xy 215.143065 134.88586) (xy 215.143065 134.89959)
			(xy 215.143065 134.91332) (xy 215.143065 134.92705) (xy 215.143065 134.94078) (xy 215.143065 134.95452)
			(xy 215.143065 134.96825) (xy 215.143065 134.98198) (xy 215.143065 134.99571) (xy 215.143065 135.00944)
			(xy 215.143065 135.02317) (xy 215.143065 135.03691) (xy 215.143065 135.05064) (xy 215.143065 135.06437)
			(xy 215.143065 135.0781) (xy 215.143065 135.09183) (xy 215.143065 135.10556) (xy 215.143065 135.1193)
			(xy 215.143065 135.13303) (xy 215.143065 135.14676) (xy 215.143065 135.16049) (xy 215.143065 135.17422)
			(xy 215.143065 135.18795) (xy 215.143065 135.20169) (xy 215.143065 135.21542) (xy 215.143065 135.22915)
			(xy 215.143065 135.24288) (xy 215.143065 135.25661) (xy 215.143065 135.27034) (xy 215.143065 135.28408)
			(xy 215.143065 135.29781) (xy 215.143065 135.31154) (xy 215.143065 135.32527) (xy 215.143065 135.339)
			(xy 215.143065 135.35274) (xy 215.143065 135.36647) (xy 215.143065 135.3802) (xy 215.143065 135.39393)
			(xy 215.143065 135.40766) (xy 215.143065 135.4214) (xy 215.143065 135.43513) (xy 215.143065 135.44886)
			(xy 215.143065 135.46259) (xy 215.143065 135.47632) (xy 215.143065 135.49005) (xy 215.143065 135.50379)
			(xy 215.143065 135.51752) (xy 215.143065 135.53125) (xy 215.143065 135.54498) (xy 215.143065 135.55871)
			(xy 215.143065 135.57244) (xy 215.143065 135.58618) (xy 215.143065 135.59991) (xy 215.143065 135.61364)
			(xy 215.143065 135.62737) (xy 215.143065 135.6411) (xy 215.143065 135.65483) (xy 215.143065 135.66857)
			(xy 215.143065 135.6823) (xy 215.143065 135.69603) (xy 215.143065 135.70976) (xy 215.143065 135.72349)
			(xy 215.143065 135.73722) (xy 215.143065 135.75096) (xy 215.143065 135.76469) (xy 215.143065 135.77842)
			(xy 215.143065 135.79215) (xy 215.143065 135.80588) (xy 215.143065 135.81961) (xy 215.143065 135.83335)
			(xy 215.143065 135.84708) (xy 215.143065 135.86081) (xy 215.143065 135.87454) (xy 215.143065 135.88827)
			(xy 215.143065 135.90201) (xy 215.143065 135.91574) (xy 215.143065 135.92947) (xy 215.143065 135.9432)
			(xy 215.143065 135.95693) (xy 215.143065 135.97067) (xy 215.143065 135.9844) (xy 215.143065 135.99813)
			(xy 215.143065 136.01186) (xy 215.143065 136.02559) (xy 215.143065 136.03932) (xy 215.143065 136.05306)
			(xy 215.143065 136.06679) (xy 215.143065 136.08052) (xy 215.143065 136.09425) (xy 215.143065 136.10798)
			(xy 215.143065 136.12171) (xy 215.143065 136.13545) (xy 215.143065 136.14918) (xy 215.143065 136.16291)
			(xy 215.143065 136.17664) (xy 215.143065 136.19037) (xy 215.143065 136.2041) (xy 215.143065 136.21784)
			(xy 215.143065 136.23157) (xy 215.143065 136.2453) (xy 215.143065 136.25903) (xy 215.143065 136.27276)
			(xy 215.143065 136.28649) (xy 215.143065 136.30023) (xy 215.143065 136.31396) (xy 215.143065 136.32769)
			(xy 215.143065 136.34142) (xy 215.143065 136.35515) (xy 215.143065 136.36889) (xy 215.143065 136.38262)
			(xy 215.143065 136.39635) (xy 215.143065 136.41008) (xy 215.143065 136.42381) (xy 215.143065 136.43755)
			(xy 215.143065 136.45128) (xy 215.143065 136.46501) (xy 215.143065 136.47874) (xy 215.143065 136.49247)
			(xy 215.143065 136.5062) (xy 215.143065 136.51994) (xy 215.143065 136.53367) (xy 215.143065 136.5474)
			(xy 215.143065 136.56113) (xy 215.143065 136.57486) (xy 215.143065 136.58859) (xy 215.143065 136.60233)
			(xy 215.143065 136.61606) (xy 215.143065 136.62979) (xy 215.143065 136.64352) (xy 215.143065 136.65725)
			(xy 215.143065 136.67098) (xy 215.143065 136.68472) (xy 215.143065 136.69845) (xy 215.143065 136.71218)
			(xy 215.143065 136.72591) (xy 215.143065 136.73964) (xy 215.143065 136.75337) (xy 215.143065 136.76711)
			(xy 215.143065 136.78084) (xy 215.143065 136.79457) (xy 215.143065 136.8083) (xy 215.143065 136.82203)
			(xy 215.143065 136.83576) (xy 215.143065 136.8495) (xy 215.143065 136.86323) (xy 215.143065 136.87696)
			(xy 215.143065 136.89069) (xy 215.143065 136.90442) (xy 215.143065 136.91816) (xy 215.143065 136.93189)
			(xy 215.143065 136.94562) (xy 215.143065 136.95935) (xy 215.143065 136.97308) (xy 215.156795 136.97308)
			(xy 215.156795 136.98682) (xy 215.156795 137.00055) (xy 215.184255 137.00055) (xy 215.184255 137.01428)
			(xy 215.857115 137.01428) (xy 215.857115 137.00055) (xy 215.870845 137.00055) (xy 215.870845 136.98682)
			(xy 215.884575 136.98682) (xy 215.884575 136.97308) (xy 215.884575 136.95935) (xy 215.898305 136.95935)
			(xy 215.898305 136.94562) (xy 215.898305 136.93189) (xy 215.898305 136.91816) (xy 215.898305 136.90442)
			(xy 215.898305 136.89069) (xy 215.898305 136.87696) (xy 215.898305 136.86323) (xy 215.898305 136.8495)
			(xy 215.898305 136.83576) (xy 215.898305 136.82203) (xy 215.898305 136.8083) (xy 215.898305 136.79457)
			(xy 215.898305 136.78084) (xy 215.898305 136.76711) (xy 215.898305 136.75337) (xy 215.898305 136.73964)
			(xy 215.898305 136.72591) (xy 215.898305 136.71218) (xy 215.898305 136.69845) (xy 215.898305 136.68472)
			(xy 215.898305 136.67098) (xy 215.898305 136.65725) (xy 215.898305 136.64352) (xy 215.898305 136.62979)
			(xy 215.898305 136.61606) (xy 215.898305 136.60233) (xy 215.898305 136.58859) (xy 215.898305 136.57486)
			(xy 215.898305 136.56113) (xy 215.898305 136.5474) (xy 215.898305 136.53367) (xy 215.898305 136.51994)
			(xy 215.898305 136.5062) (xy 215.898305 136.49247) (xy 215.898305 136.47874) (xy 215.898305 136.46501)
			(xy 215.898305 136.45128) (xy 215.898305 136.43755) (xy 215.898305 136.42381) (xy 215.898305 136.41008)
			(xy 215.898305 136.39635) (xy 215.898305 136.38262) (xy 215.898305 136.36889) (xy 215.898305 136.35515)
			(xy 215.898305 136.34142) (xy 215.898305 136.32769) (xy 215.898305 136.31396) (xy 215.898305 136.30023)
			(xy 215.898305 136.28649) (xy 215.898305 136.27276) (xy 215.898305 136.25903) (xy 215.898305 136.2453)
			(xy 215.898305 136.23157) (xy 215.898305 136.21784) (xy 215.898305 136.2041) (xy 215.898305 136.19037)
			(xy 215.898305 136.17664) (xy 215.898305 136.16291) (xy 215.898305 136.14918) (xy 215.898305 136.13545)
			(xy 215.898305 136.12171) (xy 215.898305 136.10798) (xy 215.898305 136.09425) (xy 215.898305 136.08052)
			(xy 215.898305 136.06679) (xy 215.898305 136.05306) (xy 215.898305 136.03932) (xy 215.898305 136.02559)
			(xy 215.898305 136.01186) (xy 215.898305 135.99813) (xy 215.898305 135.9844) (xy 215.898305 135.97067)
			(xy 215.898305 135.95693) (xy 215.898305 135.9432) (xy 215.898305 135.92947) (xy 215.898305 135.91574)
			(xy 215.898305 135.90201) (xy 215.898305 135.88827) (xy 215.898305 135.87454) (xy 215.898305 135.86081)
			(xy 215.898305 135.84708) (xy 215.898305 135.83335) (xy 215.898305 135.81961) (xy 215.898305 135.80588)
			(xy 215.898305 135.79215) (xy 215.898305 135.77842) (xy 215.898305 135.76469) (xy 215.898305 135.75096)
			(xy 215.898305 135.73722) (xy 215.898305 135.72349) (xy 215.898305 135.70976) (xy 215.898305 135.69603)
			(xy 215.898305 135.6823) (xy 215.898305 135.66857) (xy 215.898305 135.65483) (xy 215.898305 135.6411)
			(xy 215.898305 135.62737) (xy 215.898305 135.61364) (xy 215.898305 135.59991) (xy 215.898305 135.58618)
			(xy 215.898305 135.57244) (xy 215.898305 135.55871) (xy 215.898305 135.54498) (xy 215.898305 135.53125)
			(xy 215.898305 135.51752) (xy 215.898305 135.50379) (xy 215.898305 135.49005) (xy 215.898305 135.47632)
			(xy 215.898305 135.46259) (xy 215.898305 135.44886) (xy 215.898305 135.43513) (xy 215.898305 135.4214)
			(xy 215.898305 135.40766) (xy 215.898305 135.39393) (xy 215.898305 135.3802) (xy 215.898305 135.36647)
			(xy 215.898305 135.35274) (xy 215.898305 135.339) (xy 215.898305 135.32527) (xy 215.898305 135.31154)
			(xy 215.898305 135.29781) (xy 215.898305 135.28408) (xy 215.898305 135.27034) (xy 215.898305 135.25661)
			(xy 215.898305 135.24288) (xy 215.898305 135.22915) (xy 215.898305 135.21542) (xy 215.898305 135.20169)
			(xy 215.898305 135.18795) (xy 215.898305 135.17422) (xy 215.898305 135.16049) (xy 215.898305 135.14676)
			(xy 215.898305 135.13303) (xy 215.898305 135.1193) (xy 215.898305 135.10556) (xy 215.898305 135.09183)
			(xy 215.898305 135.0781) (xy 215.898305 135.06437) (xy 215.898305 135.05064) (xy 215.898305 135.03691)
			(xy 215.898305 135.02317) (xy 215.898305 135.00944) (xy 215.898305 134.99571) (xy 215.898305 134.98198)
			(xy 215.898305 134.96825) (xy 215.898305 134.95452) (xy 215.898305 134.94078) (xy 215.898305 134.92705)
			(xy 215.898305 134.91332) (xy 215.898305 134.89959) (xy 215.898305 134.88586) (xy 215.898305 134.87213)
			(xy 215.898305 134.85839) (xy 215.898305 134.84466) (xy 215.898305 134.83093) (xy 215.898305 134.8172)
			(xy 215.898305 134.80347) (xy 215.898305 134.78973) (xy 215.898305 134.776) (xy 215.898305 134.76227)
			(xy 216.365185 134.76227) (xy 216.365185 134.776) (xy 216.365185 134.78973) (xy 216.365185 134.80347)
			(xy 216.365185 134.8172) (xy 216.365185 134.83093) (xy 216.365185 134.84466) (xy 216.365185 134.85839)
			(xy 216.365185 134.87213) (xy 216.365185 134.88586) (xy 216.365185 134.89959) (xy 216.365185 134.91332)
			(xy 216.365185 134.92705) (xy 216.365185 134.94078) (xy 216.365185 134.95452) (xy 216.365185 134.96825)
			(xy 216.365185 134.98198) (xy 216.365185 134.99571) (xy 216.365185 135.00944) (xy 216.365185 135.02317)
			(xy 216.365185 135.03691) (xy 216.365185 135.05064) (xy 216.365185 135.06437) (xy 216.365185 135.0781)
			(xy 216.365185 135.09183) (xy 216.365185 135.10556) (xy 216.365185 135.1193) (xy 216.365185 135.13303)
			(xy 216.365185 135.14676) (xy 216.365185 135.16049) (xy 216.365185 135.17422) (xy 216.365185 135.18795)
			(xy 216.365185 135.20169) (xy 216.365185 135.21542) (xy 216.365185 135.22915) (xy 216.365185 135.24288)
			(xy 216.365185 135.25661) (xy 216.365185 135.27034) (xy 216.365185 135.28408) (xy 216.365185 135.29781)
			(xy 216.365185 135.31154) (xy 216.365185 135.32527) (xy 216.365185 135.339) (xy 216.365185 135.35274)
			(xy 216.365185 135.36647) (xy 216.365185 135.3802) (xy 216.365185 135.39393) (xy 216.365185 135.40766)
			(xy 216.365185 135.4214) (xy 216.365185 135.43513) (xy 216.365185 135.44886) (xy 216.365185 135.46259)
			(xy 216.365185 135.47632) (xy 216.365185 135.49005) (xy 216.365185 135.50379) (xy 216.365185 135.51752)
			(xy 216.365185 135.53125) (xy 216.365185 135.54498) (xy 216.365185 135.55871) (xy 216.365185 135.57244)
			(xy 216.365185 135.58618) (xy 216.365185 135.59991) (xy 216.365185 135.61364) (xy 216.365185 135.62737)
			(xy 216.365185 135.6411) (xy 216.365185 135.65483) (xy 216.365185 135.66857) (xy 216.365185 135.6823)
			(xy 216.365185 135.69603) (xy 216.365185 135.70976) (xy 216.365185 135.72349) (xy 216.365185 135.73722)
			(xy 216.365185 135.75096) (xy 216.365185 135.76469) (xy 216.365185 135.77842) (xy 216.365185 135.79215)
			(xy 216.365185 135.80588) (xy 216.365185 135.81961) (xy 216.365185 135.83335) (xy 216.365185 135.84708)
			(xy 216.365185 135.86081) (xy 216.365185 135.87454) (xy 216.365185 135.88827) (xy 216.365185 135.90201)
			(xy 216.365185 135.91574) (xy 216.365185 135.92947) (xy 216.365185 135.9432) (xy 216.365185 135.95693)
			(xy 216.365185 135.97067) (xy 216.365185 135.9844) (xy 216.365185 135.99813) (xy 216.365185 136.01186)
			(xy 216.365185 136.02559) (xy 216.365185 136.03932) (xy 216.365185 136.05306) (xy 216.365185 136.06679)
			(xy 216.365185 136.08052) (xy 216.365185 136.09425) (xy 216.365185 136.10798) (xy 216.365185 136.12171)
			(xy 216.365185 136.13545) (xy 216.365185 136.14918) (xy 216.365185 136.16291) (xy 216.365185 136.17664)
			(xy 216.365185 136.19037) (xy 216.365185 136.2041) (xy 216.365185 136.21784) (xy 216.365185 136.23157)
			(xy 216.365185 136.2453) (xy 216.365185 136.25903) (xy 216.365185 136.27276) (xy 216.365185 136.28649)
			(xy 216.365185 136.30023) (xy 216.365185 136.31396) (xy 216.365185 136.32769) (xy 216.365185 136.34142)
			(xy 216.365185 136.35515) (xy 216.365185 136.36889) (xy 216.365185 136.38262) (xy 216.365185 136.39635)
			(xy 216.365185 136.41008) (xy 216.365185 136.42381) (xy 216.365185 136.43755) (xy 216.365185 136.45128)
			(xy 216.365185 136.46501) (xy 216.365185 136.47874) (xy 216.365185 136.49247) (xy 216.365185 136.5062)
			(xy 216.365185 136.51994) (xy 216.365185 136.53367) (xy 216.365185 136.5474) (xy 216.365185 136.56113)
			(xy 216.365185 136.57486) (xy 216.365185 136.58859) (xy 216.365185 136.60233) (xy 216.365185 136.61606)
			(xy 216.365185 136.62979) (xy 216.365185 136.64352) (xy 216.365185 136.65725) (xy 216.365185 136.67098)
			(xy 216.365185 136.68472) (xy 216.365185 136.69845) (xy 216.365185 136.71218) (xy 216.365185 136.72591)
			(xy 216.365185 136.73964) (xy 216.365185 136.75337) (xy 216.365185 136.76711) (xy 216.365185 136.78084)
			(xy 216.365185 136.79457) (xy 216.365185 136.8083) (xy 216.365185 136.82203) (xy 216.365185 136.83576)
			(xy 216.365185 136.8495) (xy 216.365185 136.86323) (xy 216.365185 136.87696) (xy 216.365185 136.89069)
			(xy 216.365185 136.90442) (xy 216.365185 136.91816) (xy 216.365185 136.93189) (xy 216.365185 136.94562)
			(xy 216.365185 136.95935) (xy 216.378925 136.95935) (xy 216.378925 136.97308) (xy 216.378925 136.98682)
			(xy 216.392655 136.98682) (xy 216.392655 137.00055) (xy 216.420115 137.00055) (xy 216.420115 137.01428)
			(xy 217.024315 137.01428) (xy 217.024315 137.00055) (xy 217.038045 137.00055) (xy 217.038045 136.98682)
			(xy 217.051775 136.98682) (xy 217.051775 136.97308) (xy 217.065505 136.97308) (xy 217.065505 136.95935)
			(xy 217.065505 136.94562) (xy 217.065505 136.93189) (xy 217.065505 136.91816) (xy 217.065505 136.90442)
			(xy 217.065505 136.89069) (xy 217.065505 136.87696) (xy 217.065505 136.86323) (xy 217.065505 136.8495)
			(xy 217.065505 136.83576) (xy 217.065505 136.82203) (xy 217.065505 136.8083) (xy 217.065505 136.79457)
			(xy 217.065505 136.78084) (xy 217.065505 136.76711) (xy 217.065505 136.75337) (xy 217.065505 136.73964)
			(xy 217.065505 136.72591) (xy 217.065505 136.71218) (xy 217.065505 136.69845) (xy 217.065505 136.68472)
			(xy 217.065505 136.67098) (xy 217.065505 136.65725) (xy 217.065505 136.64352) (xy 217.065505 136.62979)
			(xy 217.065505 136.61606) (xy 217.065505 136.60233) (xy 217.065505 136.58859) (xy 217.065505 136.57486)
			(xy 217.065505 136.56113) (xy 217.065505 136.5474) (xy 217.065505 136.53367) (xy 217.065505 136.51994)
			(xy 217.065505 136.5062) (xy 217.065505 136.49247) (xy 217.065505 136.47874) (xy 217.065505 136.46501)
			(xy 217.065505 136.45128) (xy 217.065505 136.43755) (xy 217.065505 136.42381) (xy 217.065505 136.41008)
			(xy 217.065505 136.39635) (xy 217.065505 136.38262) (xy 217.065505 136.36889) (xy 217.065505 136.35515)
			(xy 217.065505 136.34142) (xy 217.065505 136.32769) (xy 217.065505 136.31396) (xy 217.065505 136.30023)
			(xy 217.065505 136.28649) (xy 217.065505 136.27276) (xy 217.065505 136.25903) (xy 217.065505 136.2453)
			(xy 217.065505 136.23157) (xy 217.065505 136.21784) (xy 217.065505 136.2041) (xy 217.065505 136.19037)
			(xy 217.065505 136.17664) (xy 217.065505 136.16291) (xy 217.065505 136.14918) (xy 217.065505 136.13545)
			(xy 217.065505 136.12171) (xy 217.065505 136.10798) (xy 217.065505 136.09425) (xy 217.065505 136.08052)
			(xy 217.065505 136.06679) (xy 217.065505 136.05306) (xy 217.065505 136.03932) (xy 217.065505 136.02559)
			(xy 217.065505 136.01186) (xy 217.065505 135.99813) (xy 217.065505 135.9844) (xy 217.065505 135.97067)
			(xy 217.065505 135.95693) (xy 217.065505 135.9432) (xy 217.065505 135.92947) (xy 217.065505 135.91574)
			(xy 217.065505 135.90201) (xy 217.065505 135.88827) (xy 217.065505 135.87454) (xy 217.065505 135.86081)
			(xy 217.065505 135.84708) (xy 217.065505 135.83335) (xy 217.065505 135.81961) (xy 217.065505 135.80588)
			(xy 217.065505 135.79215) (xy 217.065505 135.77842) (xy 217.065505 135.76469) (xy 217.065505 135.75096)
			(xy 217.065505 135.73722) (xy 217.065505 135.72349) (xy 217.065505 135.70976) (xy 217.065505 135.69603)
			(xy 217.065505 135.6823) (xy 217.065505 135.66857) (xy 217.065505 135.65483) (xy 217.065505 135.6411)
			(xy 217.065505 135.62737) (xy 217.065505 135.61364) (xy 217.065505 135.59991) (xy 217.065505 135.58618)
			(xy 217.065505 135.57244) (xy 217.065505 135.55871) (xy 217.065505 135.54498) (xy 217.065505 135.53125)
			(xy 217.065505 135.51752) (xy 217.065505 135.50379) (xy 217.065505 135.49005) (xy 217.065505 135.47632)
			(xy 217.065505 135.46259) (xy 217.065505 135.44886) (xy 217.065505 135.43513) (xy 217.065505 135.4214)
			(xy 217.065505 135.40766) (xy 217.065505 135.39393) (xy 217.065505 135.3802) (xy 217.065505 135.36647)
			(xy 217.065505 135.35274) (xy 217.065505 135.339) (xy 217.065505 135.32527) (xy 217.065505 135.31154)
			(xy 217.065505 135.29781) (xy 217.065505 135.28408) (xy 217.065505 135.27034) (xy 217.065505 135.25661)
			(xy 217.065505 135.24288) (xy 217.065505 135.22915) (xy 217.065505 135.21542) (xy 217.065505 135.20169)
			(xy 217.065505 135.18795) (xy 217.065505 135.17422) (xy 217.065505 135.16049) (xy 217.065505 135.14676)
			(xy 217.065505 135.13303) (xy 217.065505 135.1193) (xy 217.065505 135.10556) (xy 217.065505 135.09183)
			(xy 217.065505 135.0781) (xy 217.065505 135.06437) (xy 217.065505 135.05064) (xy 217.065505 135.03691)
			(xy 217.065505 135.02317) (xy 217.065505 135.00944) (xy 217.065505 134.99571) (xy 217.065505 134.98198)
			(xy 217.065505 134.96825) (xy 217.065505 134.95452) (xy 217.065505 134.94078) (xy 217.065505 134.92705)
			(xy 217.065505 134.91332) (xy 217.065505 134.89959) (xy 217.065505 134.88586) (xy 217.065505 134.87213)
			(xy 217.065505 134.85839) (xy 217.065505 134.84466) (xy 217.065505 134.83093) (xy 217.065505 134.8172)
			(xy 217.065505 134.80347) (xy 217.065505 134.78973) (xy 217.065505 134.776) (xy 217.065505 134.76227)
			(xy 217.257755 134.76227) (xy 217.257755 134.74854) (xy 217.271485 134.74854) (xy 217.271485 134.76227)
			(xy 217.312685 134.76227) (xy 217.312685 134.74854) (xy 217.312685 134.73481) (xy 217.312685 134.72107)
			(xy 217.312685 134.70734) (xy 217.312685 134.69361) (xy 217.312685 134.67988) (xy 217.312685 134.66615)
			(xy 217.312685 134.65242) (xy 217.312685 134.63868) (xy 217.312685 134.62495) (xy 217.312685 134.61122)
			(xy 217.312685 134.59749) (xy 217.312685 134.58376) (xy 217.312685 134.57003) (xy 217.312685 134.55629)
			(xy 217.312685 134.54256) (xy 217.312685 134.52883) (xy 217.312685 134.5151) (xy 217.312685 134.50137)
			(xy 217.312685 134.48764) (xy 217.312685 134.4739) (xy 217.312685 134.46017) (xy 217.312685 134.44644)
			(xy 217.312685 134.43271) (xy 217.312685 134.41898) (xy 217.312685 134.40525) (xy 217.312685 134.39151)
			(xy 217.312685 134.37778) (xy 217.312685 134.36405) (xy 217.312685 134.35032) (xy 217.312685 134.33659)
			(xy 217.312685 134.32286) (xy 217.312685 134.30912) (xy 217.312685 134.29539) (xy 217.312685 134.28166)
			(xy 217.312685 134.26793) (xy 217.312685 134.2542) (xy 217.312685 134.24046) (xy 217.312685 134.22673)
			(xy 217.312685 134.213) (xy 217.312685 134.19927) (xy 217.312685 134.18554) (xy 217.312685 134.1718)
			(xy 217.312685 134.15807) (xy 217.312685 134.14434) (xy 217.312685 134.13061) (xy 217.312685 134.11688)
			(xy 217.312685 134.10315) (xy 217.312685 134.08941) (xy 217.312685 134.07568) (xy 217.312685 134.06195)
			(xy 217.312685 134.04822) (xy 217.312685 134.03449) (xy 217.312685 134.02076) (xy 215.211725 134.02076)
			(xy 215.211725 134.03449) (xy 215.170525 134.03449) (xy 215.170525 134.04822) (xy 215.156795 134.04822)
			(xy 215.156795 134.06195) (xy 215.156795 134.07568) (xy 215.143065 134.07568) (xy 214.799765 134.07568)
			(xy 214.799765 134.06195) (xy 214.786035 134.06195) (xy 214.786035 134.04822) (xy 214.772305 134.04822)
			(xy 214.772305 134.03449) (xy 214.744845 134.03449) (xy 214.744845 134.02076) (xy 214.113185 134.02076)
			(xy 214.113185 134.03449) (xy 214.071985 134.03449) (xy 214.071985 134.04822) (xy 214.071985 134.06195)
			(xy 214.058255 134.06195) (xy 214.058255 134.07568) (xy 214.058255 134.08941) (xy 214.044525 134.08941)
			(xy 213.866005 134.08941) (xy 213.866005 134.07568) (xy 213.866005 134.06195) (xy 213.852275 134.06195)
			(xy 213.852275 134.04822) (xy 213.838545 134.04822) (xy 213.838545 134.03449) (xy 213.811085 134.03449)
			(xy 213.811085 134.02076) (xy 213.783615 134.02076) (xy 213.783615 134.03449) (xy 213.769885 134.03449)
			(xy 213.769885 134.02076) (xy 211.655195 134.02076) (xy 211.655195 134.03449) (xy 211.614005 134.03449)
			(xy 211.614005 134.04822) (xy 211.600275 134.04822) (xy 211.600275 134.06195) (xy 211.600275 134.07568)
			(xy 211.586535 134.07568) (xy 209.526775 134.07568) (xy 209.526775 134.06195) (xy 209.526775 134.04822)
			(xy 209.526775 134.03449) (xy 209.526775 134.02076) (xy 209.526775 134.00702) (xy 209.526775 133.99329)
			(xy 209.526775 133.97956) (xy 209.526775 133.96583) (xy 209.526775 133.9521) (xy 209.526775 133.93837)
			(xy 209.526775 133.92463) (xy 209.526775 133.9109) (xy 209.526775 133.89717) (xy 209.526775 133.88344)
			(xy 209.526775 133.86971) (xy 209.526775 133.85598) (xy 209.526775 133.84224) (xy 209.526775 133.82851)
			(xy 209.526775 133.81478) (xy 209.526775 133.80105) (xy 209.526775 133.78732) (xy 213.866005 133.78732)
			(xy 213.866005 133.80105) (xy 214.085715 133.80105) (xy 214.085715 133.78732) (xy 214.099455 133.78732)
			(xy 214.099455 133.77359) (xy 214.113185 133.77359) (xy 214.113185 133.75985) (xy 214.113185 133.74612)
			(xy 214.126915 133.74612) (xy 214.126915 133.73239) (xy 214.140645 133.73239) (xy 214.140645 133.71866)
			(xy 214.154375 133.71866) (xy 214.154375 133.70493) (xy 214.168105 133.70493) (xy 214.168105 133.69119)
			(xy 214.181845 133.69119) (xy 214.181845 133.67746) (xy 214.195575 133.67746) (xy 214.195575 133.66373)
			(xy 214.209305 133.66373) (xy 214.209305 133.65) (xy 214.223035 133.65) (xy 214.223035 133.63627)
			(xy 214.223035 133.62253) (xy 214.236765 133.62253) (xy 214.236765 133.6088) (xy 214.250495 133.6088)
			(xy 214.250495 133.59507) (xy 214.264235 133.59507) (xy 214.264235 133.58134) (xy 214.277965 133.58134)
			(xy 214.277965 133.56761) (xy 214.291695 133.56761) (xy 214.291695 133.55388) (xy 214.305425 133.55388)
			(xy 214.305425 133.54014) (xy 214.319155 133.54014) (xy 214.319155 133.52641) (xy 214.332885 133.52641)
			(xy 214.332885 133.51268) (xy 214.346625 133.51268) (xy 214.346625 133.49895) (xy 214.360355 133.49895)
			(xy 214.360355 133.48522) (xy 214.374085 133.48522) (xy 214.374085 133.47149) (xy 214.387815 133.47149)
			(xy 214.387815 133.45775) (xy 214.401545 133.45775) (xy 214.401545 133.44402) (xy 214.415275 133.44402)
			(xy 214.415275 133.43029) (xy 214.429015 133.43029) (xy 214.429015 133.41656) (xy 214.442745 133.41656)
			(xy 214.442745 133.40283) (xy 214.456475 133.40283) (xy 214.456475 133.3891) (xy 214.470205 133.3891)
			(xy 214.470205 133.37536) (xy 214.483935 133.37536) (xy 214.483935 133.36163) (xy 214.497675 133.36163)
			(xy 214.497675 133.3479) (xy 214.525135 133.3479) (xy 214.525135 133.33417) (xy 214.538865 133.33417)
			(xy 214.538865 133.32044) (xy 214.552595 133.32044) (xy 214.552595 133.30671) (xy 214.566335 133.30671)
			(xy 214.566335 133.29297) (xy 214.580065 133.29297) (xy 214.580065 133.27924) (xy 214.593795 133.27924)
			(xy 214.593795 133.26551) (xy 214.607525 133.26551) (xy 214.607525 133.25178) (xy 214.621255 133.25178)
			(xy 214.621255 133.23805) (xy 214.634985 133.23805) (xy 214.634985 133.22431) (xy 214.662455 133.22431)
			(xy 214.662455 133.21058) (xy 214.676185 133.21058) (xy 214.676185 133.19685) (xy 214.689915 133.19685)
			(xy 214.689915 133.18312) (xy 214.703645 133.18312) (xy 214.703645 133.16939) (xy 214.717375 133.16939)
			(xy 214.717375 133.15565) (xy 214.744845 133.15565) (xy 214.744845 133.14192) (xy 214.758575 133.14192)
			(xy 214.758575 133.12819) (xy 214.772305 133.12819) (xy 214.772305 133.11446) (xy 214.786035 133.11446)
			(xy 214.786035 133.10073) (xy 214.813505 133.10073) (xy 214.813505 133.087) (xy 214.827235 133.087)
			(xy 214.827235 133.07326) (xy 214.840965 133.07326) (xy 214.840965 133.05953) (xy 214.854695 133.05953)
			(xy 214.854695 133.0458) (xy 214.882155 133.0458) (xy 214.882155 133.03207) (xy 214.895895 133.03207)
			(xy 214.895895 133.01834) (xy 214.909625 133.01834) (xy 214.909625 133.00461) (xy 214.937085 133.00461)
			(xy 214.937085 132.99087) (xy 214.950815 132.99087) (xy 214.950815 132.97714) (xy 214.964555 132.97714)
			(xy 214.964555 132.96341) (xy 214.992015 132.96341) (xy 214.992015 132.94968) (xy 215.005745 132.94968)
			(xy 215.005745 132.93595) (xy 215.019475 132.93595) (xy 215.019475 132.92222) (xy 215.046945 132.92222)
			(xy 215.046945 132.90848) (xy 215.060675 132.90848) (xy 215.060675 132.89475) (xy 215.088135 132.89475)
			(xy 215.088135 132.88102) (xy 215.101865 132.88102) (xy 215.101865 132.86729) (xy 215.129335 132.86729)
			(xy 215.129335 132.85356) (xy 215.143065 132.85356) (xy 215.143065 132.83983) (xy 215.170525 132.83983)
			(xy 215.170525 132.82609) (xy 215.184255 132.82609) (xy 215.184255 132.81236) (xy 215.211725 132.81236)
			(xy 215.211725 132.79863) (xy 215.225455 132.79863) (xy 215.225455 132.7849) (xy 215.252915 132.7849)
			(xy 215.252915 132.77117) (xy 215.266645 132.77117) (xy 215.266645 132.75744) (xy 215.294115 132.75744)
			(xy 215.294115 132.7437) (xy 215.321575 132.7437) (xy 215.321575 132.72997) (xy 215.335305 132.72997)
			(xy 215.335305 132.71624) (xy 215.362775 132.71624) (xy 215.362775 132.70251) (xy 215.390235 132.70251)
			(xy 215.390235 132.68878) (xy 215.403965 132.68878) (xy 215.403965 132.67504) (xy 215.431425 132.67504)
			(xy 215.431425 132.66131) (xy 215.458895 132.66131) (xy 215.458895 132.64758) (xy 215.472625 132.64758)
			(xy 215.472625 132.63385) (xy 215.500085 132.63385) (xy 215.500085 132.62012) (xy 215.527555 132.62012)
			(xy 215.527555 132.60638) (xy 215.555015 132.60638) (xy 215.555015 132.59265) (xy 215.582485 132.59265)
			(xy 215.582485 132.57892) (xy 215.609945 132.57892) (xy 215.609945 132.56519) (xy 215.637405 132.56519)
			(xy 215.637405 132.55146) (xy 215.651135 132.55146) (xy 215.651135 132.53773) (xy 215.678605 132.53773)
			(xy 215.678605 132.52399) (xy 215.706065 132.52399) (xy 215.706065 132.51026) (xy 215.733525 132.51026)
			(xy 215.733525 132.49653) (xy 215.760995 132.49653) (xy 215.760995 132.4828) (xy 215.802185 132.4828)
			(xy 215.802185 132.46907) (xy 215.829655 132.46907) (xy 215.829655 132.45534) (xy 215.857115 132.45534)
			(xy 215.857115 132.4416) (xy 215.884575 132.4416) (xy 215.884575 132.42787) (xy 215.912045 132.42787)
			(xy 215.912045 132.41414) (xy 215.939505 132.41414) (xy 215.939505 132.40041) (xy 215.980695 132.40041)
			(xy 215.980695 132.38668) (xy 216.008165 132.38668) (xy 216.008165 132.37295) (xy 216.035625 132.37295)
			(xy 216.035625 132.35921) (xy 216.076825 132.35921) (xy 216.076825 132.34548) (xy 216.104285 132.34548)
			(xy 216.104285 132.33175) (xy 216.145485 132.33175) (xy 216.145485 132.31802) (xy 216.186675 132.31802)
			(xy 216.186675 132.30429) (xy 216.214145 132.30429) (xy 216.214145 132.29056) (xy 216.255335 132.29056)
			(xy 216.255335 132.27682) (xy 216.296535 132.27682) (xy 216.296535 132.26309) (xy 216.337725 132.26309)
			(xy 216.337725 132.24936) (xy 216.365185 132.24936) (xy 216.365185 132.23563) (xy 216.420115 132.23563)
			(xy 216.420115 132.2219) (xy 216.461315 132.2219) (xy 216.461315 132.20817) (xy 216.502505 132.20817)
			(xy 216.502505 132.19443) (xy 216.543705 132.19443) (xy 216.543705 132.1807) (xy 216.598625 132.1807)
			(xy 216.598625 132.16697) (xy 216.639825 132.16697) (xy 216.639825 132.15324) (xy 216.694755 132.15324)
			(xy 216.694755 132.13951) (xy 216.749675 132.13951) (xy 216.749675 132.12577) (xy 216.804605 132.12577)
			(xy 216.804605 132.11204) (xy 216.859535 132.11204) (xy 216.859535 132.09831) (xy 216.928195 132.09831)
			(xy 216.928195 132.08458) (xy 216.996845 132.08458) (xy 216.996845 132.07085) (xy 217.051775 132.07085)
			(xy 217.051775 132.05711) (xy 217.147905 132.05711) (xy 217.147905 132.04338) (xy 217.230295 132.04338)
			(xy 217.230295 132.02965) (xy 217.326415 132.02965) (xy 217.326415 132.01592) (xy 217.436265 132.01592)
			(xy 217.436265 132.00219) (xy 217.587315 132.00219) (xy 217.587315 131.98846) (xy 217.834485 131.98846)
			(xy 217.834485 131.97472) (xy 218.177785 131.97472) (xy 218.177785 131.98846) (xy 218.191515 131.98846)
			(xy 218.191515 131.97472) (xy 218.205245 131.97472) (xy 218.205245 131.98846) (xy 218.424955 131.98846)
			(xy 218.424955 132.00219) (xy 218.575995 132.00219) (xy 218.575995 132.01592) (xy 218.699585 132.01592)
			(xy 218.699585 132.02965) (xy 218.781975 132.02965) (xy 218.781975 132.04338) (xy 218.864365 132.04338)
			(xy 218.864365 132.05711) (xy 218.946755 132.05711) (xy 218.946755 132.07085) (xy 219.015415 132.07085)
			(xy 219.015415 132.08458) (xy 219.084075 132.08458) (xy 219.084075 132.09831) (xy 219.152735 132.09831)
			(xy 219.152735 132.11204) (xy 219.207665 132.11204) (xy 219.207665 132.12577) (xy 219.262585 132.12577)
			(xy 219.262585 132.13951) (xy 219.317515 132.13951) (xy 219.317515 132.15324) (xy 219.372445 132.15324)
			(xy 219.372445 132.16697) (xy 219.413635 132.16697) (xy 219.413635 132.1807) (xy 219.468565 132.1807)
			(xy 219.468565 132.19443) (xy 219.509755 132.19443) (xy 219.509755 132.20817) (xy 219.550955 132.20817)
			(xy 219.550955 132.2219) (xy 219.592145 132.2219) (xy 219.592145 132.23563) (xy 219.633345 132.23563)
			(xy 219.633345 132.24936) (xy 219.674545 132.24936) (xy 219.674545 132.26309) (xy 219.715735 132.26309)
			(xy 219.715735 132.27682) (xy 219.756935 132.27682) (xy 219.756935 132.29056) (xy 219.798125 132.29056)
			(xy 219.798125 132.30429) (xy 219.825595 132.30429) (xy 219.825595 132.31802) (xy 219.866785 132.31802)
			(xy 219.866785 132.33175) (xy 219.894245 132.33175) (xy 219.894245 132.34548) (xy 219.935445 132.34548)
			(xy 219.935445 132.35921) (xy 219.962905 132.35921) (xy 219.962905 132.37295) (xy 220.004105 132.37295)
			(xy 220.004105 132.38668) (xy 220.031565 132.38668) (xy 220.031565 132.40041) (xy 220.059025 132.40041)
			(xy 220.059025 132.41414) (xy 220.100225 132.41414) (xy 220.100225 132.42787) (xy 220.127685 132.42787)
			(xy 220.127685 132.4416) (xy 220.155155 132.4416) (xy 220.155155 132.45534) (xy 220.182615 132.45534)
			(xy 220.182615 132.46907) (xy 220.210075 132.46907) (xy 220.210075 132.4828) (xy 220.251275 132.4828)
			(xy 220.251275 132.49653) (xy 220.278735 132.49653) (xy 220.278735 132.51026) (xy 220.292475 132.51026)
			(xy 220.292475 132.52399) (xy 220.319935 132.52399) (xy 220.319935 132.53773) (xy 220.347395 132.53773)
			(xy 220.347395 132.55146) (xy 220.374865 132.55146) (xy 220.374865 132.56519) (xy 220.402325 132.56519)
			(xy 220.402325 132.57892) (xy 220.429785 132.57892) (xy 220.429785 132.59265) (xy 220.457255 132.59265)
			(xy 220.457255 132.60638) (xy 220.484715 132.60638) (xy 220.484715 132.62012) (xy 220.512175 132.62012)
			(xy 220.512175 132.63385) (xy 220.525905 132.63385) (xy 220.525905 132.64758) (xy 220.553375 132.64758)
			(xy 220.553375 132.66131) (xy 220.580835 132.66131) (xy 220.580835 132.67504) (xy 220.608295 132.67504)
			(xy 220.608295 132.68878) (xy 220.622035 132.68878) (xy 220.622035 132.70251) (xy 220.649495 132.70251)
			(xy 220.649495 132.71624) (xy 220.676955 132.71624) (xy 220.676955 132.72997) (xy 220.690685 132.72997)
			(xy 220.690685 132.7437) (xy 220.718155 132.7437) (xy 220.718155 132.75744) (xy 220.745615 132.75744)
			(xy 220.745615 132.77117) (xy 220.759345 132.77117) (xy 220.759345 132.7849) (xy 220.786815 132.7849)
			(xy 220.786815 132.79863) (xy 220.800545 132.79863) (xy 220.800545 132.81236) (xy 220.828005 132.81236)
			(xy 220.828005 132.82609) (xy 220.841745 132.82609) (xy 220.841745 132.83983) (xy 220.869205 132.83983)
			(xy 220.869205 132.85356) (xy 220.882935 132.85356) (xy 220.882935 132.86729) (xy 220.910395 132.86729)
			(xy 220.910395 132.88102) (xy 220.924135 132.88102) (xy 220.924135 132.89475) (xy 220.951595 132.89475)
			(xy 220.951595 132.90848) (xy 220.965325 132.90848) (xy 220.965325 132.92222) (xy 220.979055 132.92222)
			(xy 220.979055 132.93595) (xy 221.006525 132.93595) (xy 221.006525 132.94968) (xy 221.020255 132.94968)
			(xy 221.020255 132.96341) (xy 221.047715 132.96341) (xy 221.047715 132.97714) (xy 221.061445 132.97714)
			(xy 221.061445 132.99087) (xy 221.075175 132.99087) (xy 221.075175 133.00461) (xy 221.102645 133.00461)
			(xy 221.102645 133.01834) (xy 221.116375 133.01834) (xy 221.116375 133.03207) (xy 221.130105 133.03207)
			(xy 221.130105 133.0458) (xy 221.157565 133.0458) (xy 221.157565 133.05953) (xy 221.171305 133.05953)
			(xy 221.171305 133.07326) (xy 221.185035 133.07326) (xy 221.185035 133.087) (xy 221.198765 133.087)
			(xy 221.198765 133.10073) (xy 221.226225 133.10073) (xy 221.226225 133.11446) (xy 221.239955 133.11446)
			(xy 221.239955 133.12819) (xy 221.253695 133.12819) (xy 221.253695 133.14192) (xy 221.267425 133.14192)
			(xy 221.267425 133.15565) (xy 221.294885 133.15565) (xy 221.294885 133.16939) (xy 221.308615 133.16939)
			(xy 221.308615 133.18312) (xy 221.322355 133.18312) (xy 221.322355 133.19685) (xy 221.336085 133.19685)
			(xy 221.336085 133.21058) (xy 221.349815 133.21058) (xy 221.349815 133.22431) (xy 221.363545 133.22431)
			(xy 221.363545 133.23805) (xy 221.391015 133.23805) (xy 221.391015 133.25178) (xy 221.404745 133.25178)
			(xy 221.404745 133.26551) (xy 221.418475 133.26551) (xy 221.418475 133.27924) (xy 221.432205 133.27924)
			(xy 221.432205 133.29297) (xy 221.445935 133.29297) (xy 221.445935 133.30671) (xy 221.459665 133.30671)
			(xy 221.459665 133.32044) (xy 221.473405 133.32044) (xy 221.473405 133.33417) (xy 221.487135 133.33417)
			(xy 221.487135 133.3479) (xy 221.500865 133.3479) (xy 221.500865 133.36163) (xy 221.528325 133.36163)
			(xy 221.528325 133.37536) (xy 221.542055 133.37536) (xy 221.542055 133.3891) (xy 221.555795 133.3891)
			(xy 221.555795 133.40283) (xy 221.569525 133.40283) (xy 221.569525 133.41656) (xy 221.583255 133.41656)
			(xy 221.583255 133.43029) (xy 221.596985 133.43029) (xy 221.596985 133.44402) (xy 221.610715 133.44402)
			(xy 221.610715 133.45775) (xy 221.624445 133.45775) (xy 221.624445 133.47149) (xy 221.638185 133.47149)
			(xy 221.638185 133.48522) (xy 221.651915 133.48522) (xy 221.651915 133.49895) (xy 221.665645 133.49895)
			(xy 221.665645 133.51268) (xy 221.679375 133.51268) (xy 221.679375 133.52641) (xy 221.693105 133.52641)
			(xy 221.693105 133.54014) (xy 221.706835 133.54014) (xy 221.706835 133.55388) (xy 221.720575 133.55388)
			(xy 221.720575 133.56761) (xy 221.734305 133.56761) (xy 221.734305 133.58134) (xy 221.748035 133.58134)
			(xy 221.748035 133.59507) (xy 221.761765 133.59507) (xy 221.761765 133.6088) (xy 221.761765 133.62253)
			(xy 221.775495 133.62253) (xy 221.775495 133.63627) (xy 221.789235 133.63627) (xy 221.789235 133.65)
			(xy 221.802965 133.65) (xy 221.802965 133.66373) (xy 221.816695 133.66373) (xy 221.816695 133.67746)
			(xy 221.830425 133.67746) (xy 221.830425 133.69119) (xy 221.844155 133.69119) (xy 221.844155 133.70493)
			(xy 221.857895 133.70493) (xy 221.857895 133.71866) (xy 221.871625 133.71866) (xy 221.871625 133.73239)
			(xy 221.885355 133.73239) (xy 221.885355 133.74612) (xy 221.885355 133.75985) (xy 221.899085 133.75985)
			(xy 221.899085 133.77359) (xy 221.912815 133.77359) (xy 221.912815 133.78732) (xy 221.926545 133.78732)
			(xy 221.926545 133.80105) (xy 221.940285 133.80105) (xy 221.940285 133.81478) (xy 221.954015 133.81478)
			(xy 221.954015 133.82851) (xy 221.967745 133.82851) (xy 221.967745 133.84224) (xy 221.967745 133.85598)
			(xy 221.981475 133.85598) (xy 221.981475 133.86971) (xy 221.995205 133.86971) (xy 221.995205 133.88344)
			(xy 222.008935 133.88344) (xy 222.008935 133.89717) (xy 222.022675 133.89717) (xy 222.022675 133.9109)
			(xy 222.022675 133.92463) (xy 222.036405 133.92463) (xy 222.036405 133.93837) (xy 222.050135 133.93837)
			(xy 222.050135 133.9521) (xy 222.063865 133.9521) (xy 222.063865 133.96583) (xy 222.077595 133.96583)
			(xy 222.077595 133.97956) (xy 222.077595 133.99329) (xy 222.091325 133.99329) (xy 222.091325 134.00702)
			(xy 222.105065 134.00702) (xy 222.105065 134.02076) (xy 222.118795 134.02076) (xy 222.118795 134.03449)
			(xy 222.118795 134.04822) (xy 222.132525 134.04822) (xy 222.132525 134.06195) (xy 222.146255 134.06195)
			(xy 222.146255 134.07568) (xy 222.159985 134.07568) (xy 222.159985 134.08941) (xy 222.159985 134.10315)
			(xy 222.173715 134.10315) (xy 222.173715 134.11688) (xy 222.187455 134.11688) (xy 222.187455 134.13061)
			(xy 222.187455 134.14434) (xy 222.201185 134.14434) (xy 222.201185 134.15807) (xy 222.214915 134.15807)
			(xy 222.214915 134.1718) (xy 222.228645 134.1718) (xy 222.228645 134.18554) (xy 222.228645 134.19927)
			(xy 222.242375 134.19927) (xy 222.242375 134.213) (xy 222.256105 134.213) (xy 222.256105 134.22673)
			(xy 222.256105 134.24046) (xy 222.269845 134.24046) (xy 222.269845 134.2542) (xy 222.283575 134.2542)
			(xy 222.283575 134.26793) (xy 222.283575 134.28166) (xy 222.297305 134.28166) (xy 222.297305 134.29539)
			(xy 222.311035 134.29539) (xy 222.311035 134.30912) (xy 222.311035 134.32286) (xy 222.324765 134.32286)
			(xy 222.324765 134.33659) (xy 222.338505 134.33659) (xy 222.338505 134.35032) (xy 222.338505 134.36405)
			(xy 222.352235 134.36405) (xy 222.352235 134.37778) (xy 222.365965 134.37778) (xy 222.365965 134.39151)
			(xy 222.365965 134.40525) (xy 222.379695 134.40525) (xy 222.379695 134.41898) (xy 222.379695 134.43271)
			(xy 222.393425 134.43271) (xy 222.393425 134.44644) (xy 222.407165 134.44644) (xy 222.407165 134.46017)
			(xy 222.407165 134.4739) (xy 222.420895 134.4739) (xy 222.420895 134.48764) (xy 222.420895 134.50137)
			(xy 222.434625 134.50137) (xy 222.434625 134.5151) (xy 222.448355 134.5151) (xy 222.448355 134.52883)
			(xy 222.448355 134.54256) (xy 222.462085 134.54256) (xy 222.462085 134.55629) (xy 222.462085 134.57003)
			(xy 222.475815 134.57003) (xy 222.475815 134.58376) (xy 222.475815 134.59749) (xy 222.489555 134.59749)
			(xy 222.489555 134.61122) (xy 222.503285 134.61122) (xy 222.503285 134.62495) (xy 222.503285 134.63868)
			(xy 222.517015 134.63868) (xy 222.517015 134.65242) (xy 222.517015 134.66615) (xy 222.530745 134.66615)
			(xy 222.530745 134.67988) (xy 222.530745 134.69361) (xy 222.544475 134.69361) (xy 222.544475 134.70734)
			(xy 222.544475 134.72107) (xy 222.558205 134.72107) (xy 222.558205 134.73481) (xy 222.558205 134.74854)
			(xy 222.571945 134.74854) (xy 222.571945 134.76227) (xy 222.585675 134.76227) (xy 222.585675 134.776)
			(xy 222.585675 134.78973) (xy 222.599405 134.78973) (xy 222.599405 134.80347) (xy 222.599405 134.8172)
			(xy 222.613135 134.8172) (xy 222.613135 134.83093) (xy 222.613135 134.84466) (xy 222.626865 134.84466)
			(xy 222.626865 134.85839) (xy 222.626865 134.87213) (xy 222.640595 134.87213) (xy 222.640595 134.88586)
			(xy 222.640595 134.89959) (xy 222.640595 134.91332) (xy 222.654335 134.91332) (xy 222.654335 134.92705)
			(xy 222.654335 134.94078) (xy 222.668065 134.94078) (xy 222.668065 134.95452) (xy 222.668065 134.96825)
			(xy 222.681795 134.96825) (xy 222.681795 134.98198) (xy 222.681795 134.99571) (xy 222.695525 134.99571)
			(xy 222.695525 135.00944) (xy 222.695525 135.02317) (xy 222.709255 135.02317) (xy 222.709255 135.03691)
			(xy 222.709255 135.05064) (xy 222.722985 135.05064) (xy 222.722985 135.06437) (xy 222.722985 135.0781)
			(xy 222.722985 135.09183) (xy 222.736725 135.09183) (xy 222.736725 135.10556) (xy 222.736725 135.1193)
			(xy 222.750455 135.1193) (xy 222.750455 135.13303) (xy 222.750455 135.14676) (xy 222.764185 135.14676)
			(xy 222.764185 135.16049) (xy 222.764185 135.17422) (xy 222.764185 135.18795) (xy 222.777915 135.18795)
			(xy 222.777915 135.20169) (xy 222.777915 135.21542) (xy 222.791645 135.21542) (xy 222.791645 135.22915)
			(xy 222.791645 135.24288) (xy 222.791645 135.25661) (xy 222.805375 135.25661) (xy 222.805375 135.27034)
			(xy 222.805375 135.28408) (xy 222.819115 135.28408) (xy 222.819115 135.29781) (xy 222.819115 135.31154)
			(xy 222.819115 135.32527) (xy 222.832845 135.32527) (xy 222.832845 135.339) (xy 222.832845 135.35274)
			(xy 222.832845 135.36647) (xy 222.846575 135.36647) (xy 222.846575 135.3802) (xy 222.846575 135.39393)
			(xy 222.846575 135.40766) (xy 222.860305 135.40766) (xy 222.860305 135.4214) (xy 222.860305 135.43513)
			(xy 222.874035 135.43513) (xy 222.874035 135.44886) (xy 222.874035 135.46259) (xy 222.874035 135.47632)
			(xy 222.887775 135.47632) (xy 222.887775 135.49005) (xy 222.887775 135.50379) (xy 222.887775 135.51752)
			(xy 222.901505 135.51752) (xy 222.901505 135.53125) (xy 222.901505 135.54498) (xy 222.901505 135.55871)
			(xy 222.901505 135.57244) (xy 222.915235 135.57244) (xy 222.915235 135.58618) (xy 222.915235 135.59991)
			(xy 222.915235 135.61364) (xy 222.928965 135.61364) (xy 222.928965 135.62737) (xy 222.928965 135.6411)
			(xy 222.928965 135.65483) (xy 222.942695 135.65483) (xy 222.942695 135.66857) (xy 222.942695 135.6823)
			(xy 222.942695 135.69603) (xy 222.942695 135.70976) (xy 222.956435 135.70976) (xy 222.956435 135.72349)
			(xy 222.956435 135.73722) (xy 222.956435 135.75096) (xy 222.970165 135.75096) (xy 222.970165 135.76469)
			(xy 222.970165 135.77842) (xy 222.970165 135.79215) (xy 222.970165 135.80588) (xy 222.983895 135.80588)
			(xy 222.983895 135.81961) (xy 222.983895 135.83335) (xy 222.983895 135.84708) (xy 222.983895 135.86081)
			(xy 222.997625 135.86081) (xy 222.997625 135.87454) (xy 222.997625 135.88827) (xy 222.997625 135.90201)
			(xy 222.997625 135.91574) (xy 223.011355 135.91574) (xy 223.011355 135.92947) (xy 223.011355 135.9432)
			(xy 223.011355 135.95693) (xy 223.011355 135.97067) (xy 223.025085 135.97067) (xy 223.025085 135.9844)
			(xy 223.025085 135.99813) (xy 223.025085 136.01186) (xy 223.025085 136.02559) (xy 223.025085 136.03932)
			(xy 223.038825 136.03932) (xy 223.038825 136.05306) (xy 223.038825 136.06679) (xy 223.038825 136.08052)
			(xy 223.038825 136.09425) (xy 223.052555 136.09425) (xy 223.052555 136.10798) (xy 223.052555 136.12171)
			(xy 223.052555 136.13545) (xy 223.052555 136.14918) (xy 223.052555 136.16291) (xy 223.052555 136.17664)
			(xy 223.066285 136.17664) (xy 223.066285 136.19037) (xy 223.066285 136.2041) (xy 223.066285 136.21784)
			(xy 223.066285 136.23157) (xy 223.066285 136.2453) (xy 223.080015 136.2453) (xy 223.080015 136.25903)
			(xy 223.080015 136.27276) (xy 223.080015 136.28649) (xy 223.080015 136.30023) (xy 223.080015 136.31396)
			(xy 223.080015 136.32769) (xy 223.093745 136.32769) (xy 223.093745 136.34142) (xy 223.093745 136.35515)
			(xy 223.093745 136.36889) (xy 223.093745 136.38262) (xy 223.093745 136.39635) (xy 223.093745 136.41008)
			(xy 223.093745 136.42381) (xy 223.107475 136.42381) (xy 223.107475 136.43755) (xy 223.107475 136.45128)
			(xy 223.107475 136.46501) (xy 223.107475 136.47874) (xy 223.107475 136.49247) (xy 223.107475 136.5062)
			(xy 223.107475 136.51994) (xy 223.107475 136.53367) (xy 223.107475 136.5474) (xy 223.121215 136.5474)
			(xy 223.121215 136.56113) (xy 223.121215 136.57486) (xy 223.121215 136.58859) (xy 223.121215 136.60233)
			(xy 223.121215 136.61606) (xy 223.121215 136.62979) (xy 223.121215 136.64352) (xy 223.121215 136.65725)
			(xy 223.121215 136.67098) (xy 223.134945 136.67098) (xy 223.134945 136.68472) (xy 223.134945 136.69845)
			(xy 223.134945 136.71218) (xy 223.134945 136.72591) (xy 223.134945 136.73964) (xy 223.134945 136.75337)
			(xy 223.134945 136.76711) (xy 223.134945 136.78084) (xy 223.134945 136.79457) (xy 223.134945 136.8083)
			(xy 223.134945 136.82203) (xy 223.134945 136.83576) (xy 223.134945 136.8495) (xy 223.134945 136.86323)
			(xy 223.134945 136.87696) (xy 223.134945 136.89069) (xy 223.134945 136.90442) (xy 223.148675 136.90442)
			(xy 223.148675 136.91816) (xy 223.148675 136.93189) (xy 223.148675 136.94562) (xy 223.148675 136.95935)
			(xy 223.148675 136.97308) (xy 223.148675 136.98682) (xy 223.148675 137.00055) (xy 223.148675 137.01428)
			(xy 223.148675 137.02801) (xy 223.148675 137.04174) (xy 223.148675 137.05547) (xy 223.313455 137.05547)
			(xy 223.313455 137.04174) (xy 223.313455 137.02801) (xy 223.313455 137.01428) (xy 223.313455 137.00055)
			(xy 223.313455 136.98682) (xy 223.313455 136.97308) (xy 223.313455 136.95935) (xy 223.313455 136.94562)
			(xy 223.313455 136.93189) (xy 223.313455 136.91816) (xy 223.313455 136.90442) (xy 223.313455 136.89069)
			(xy 223.299725 136.89069) (xy 223.299725 136.87696) (xy 223.313455 136.87696) (xy 223.313455 136.86323)
			(xy 223.313455 136.8495) (xy 223.313455 136.83576) (xy 223.299725 136.83576) (xy 223.299725 136.82203)
			(xy 223.299725 136.8083) (xy 223.299725 136.79457) (xy 223.299725 136.78084) (xy 223.299725 136.76711)
			(xy 223.299725 136.75337) (xy 223.299725 136.73964) (xy 223.299725 136.72591) (xy 223.299725 136.71218)
			(xy 223.299725 136.69845) (xy 223.299725 136.68472) (xy 223.299725 136.67098) (xy 223.299725 136.65725)
			(xy 223.299725 136.64352) (xy 223.285995 136.64352) (xy 223.285995 136.62979) (xy 223.285995 136.61606)
			(xy 223.285995 136.60233) (xy 223.285995 136.58859) (xy 223.285995 136.57486) (xy 223.285995 136.56113)
			(xy 223.285995 136.5474) (xy 223.285995 136.53367) (xy 223.285995 136.51994) (xy 223.285995 136.5062)
			(xy 223.272255 136.5062) (xy 223.272255 136.49247) (xy 223.272255 136.47874) (xy 223.272255 136.46501)
			(xy 223.272255 136.45128) (xy 223.272255 136.43755) (xy 223.272255 136.42381) (xy 223.272255 136.41008)
			(xy 223.272255 136.39635) (xy 223.258525 136.39635) (xy 223.258525 136.38262) (xy 223.258525 136.36889)
			(xy 223.258525 136.35515) (xy 223.258525 136.34142) (xy 223.258525 136.32769) (xy 223.258525 136.31396)
			(xy 223.258525 136.30023) (xy 223.244795 136.30023) (xy 223.244795 136.28649) (xy 223.244795 136.27276)
			(xy 223.244795 136.25903) (xy 223.244795 136.2453) (xy 223.244795 136.23157) (xy 223.244795 136.21784)
			(xy 223.231065 136.21784) (xy 223.231065 136.2041) (xy 223.231065 136.19037) (xy 223.231065 136.17664)
			(xy 223.231065 136.16291) (xy 223.231065 136.14918) (xy 223.217335 136.14918) (xy 223.217335 136.13545)
			(xy 223.217335 136.12171) (xy 223.217335 136.10798) (xy 223.217335 136.09425) (xy 223.217335 136.08052)
			(xy 223.203605 136.08052) (xy 223.203605 136.06679) (xy 223.203605 136.05306) (xy 223.203605 136.03932)
			(xy 223.203605 136.02559) (xy 223.203605 136.01186) (xy 223.189865 136.01186) (xy 223.189865 135.99813)
			(xy 223.189865 135.9844) (xy 223.189865 135.97067) (xy 223.189865 135.95693) (xy 223.189865 135.9432)
			(xy 223.176135 135.9432) (xy 223.176135 135.92947) (xy 223.176135 135.91574) (xy 223.176135 135.90201)
			(xy 223.176135 135.88827) (xy 223.162405 135.88827) (xy 223.162405 135.87454) (xy 223.162405 135.86081)
			(xy 223.162405 135.84708) (xy 223.162405 135.83335) (xy 223.148675 135.83335) (xy 223.148675 135.81961)
			(xy 223.148675 135.80588) (xy 223.148675 135.79215) (xy 223.148675 135.77842) (xy 223.134945 135.77842)
			(xy 223.134945 135.76469) (xy 223.134945 135.75096) (xy 223.134945 135.73722) (xy 223.134945 135.72349)
			(xy 223.121215 135.72349) (xy 223.121215 135.70976) (xy 223.121215 135.69603) (xy 223.121215 135.6823)
			(xy 223.107475 135.6823) (xy 223.107475 135.66857) (xy 223.107475 135.65483) (xy 223.107475 135.6411)
			(xy 223.107475 135.62737) (xy 223.093745 135.62737) (xy 223.093745 135.61364) (xy 223.093745 135.59991)
			(xy 223.093745 135.58618) (xy 223.080015 135.58618) (xy 223.080015 135.57244) (xy 223.080015 135.55871)
			(xy 223.080015 135.54498) (xy 223.080015 135.53125) (xy 223.066285 135.53125) (xy 223.066285 135.51752)
			(xy 223.066285 135.50379) (xy 223.066285 135.49005) (xy 223.052555 135.49005) (xy 223.052555 135.47632)
			(xy 223.052555 135.46259) (xy 223.052555 135.44886) (xy 223.038825 135.44886) (xy 223.038825 135.43513)
			(xy 223.038825 135.4214) (xy 223.038825 135.40766) (xy 223.025085 135.40766) (xy 223.025085 135.39393)
			(xy 223.025085 135.3802) (xy 223.025085 135.36647) (xy 223.011355 135.36647) (xy 223.011355 135.35274)
			(xy 223.011355 135.339) (xy 223.011355 135.32527) (xy 222.997625 135.32527) (xy 222.997625 135.31154)
			(xy 222.997625 135.29781) (xy 222.983895 135.29781) (xy 222.983895 135.28408) (xy 222.983895 135.27034)
			(xy 222.983895 135.25661) (xy 222.970165 135.25661) (xy 222.970165 135.24288) (xy 222.970165 135.22915)
			(xy 222.970165 135.21542) (xy 222.956435 135.21542) (xy 222.956435 135.20169) (xy 222.956435 135.18795)
			(xy 222.942695 135.18795) (xy 222.942695 135.17422) (xy 222.942695 135.16049) (xy 222.942695 135.14676)
			(xy 222.928965 135.14676) (xy 222.928965 135.13303) (xy 222.928965 135.1193) (xy 222.915235 135.1193)
			(xy 222.915235 135.10556) (xy 222.915235 135.09183) (xy 222.915235 135.0781) (xy 222.901505 135.0781)
			(xy 222.901505 135.06437) (xy 222.901505 135.05064) (xy 222.887775 135.05064) (xy 222.887775 135.03691)
			(xy 222.887775 135.02317) (xy 222.874035 135.02317) (xy 222.874035 135.00944) (xy 222.874035 134.99571)
			(xy 222.874035 134.98198) (xy 222.860305 134.98198) (xy 222.860305 134.96825) (xy 222.860305 134.95452)
			(xy 222.846575 134.95452) (xy 222.846575 134.94078) (xy 222.846575 134.92705) (xy 222.832845 134.92705)
			(xy 222.832845 134.91332) (xy 222.832845 134.89959) (xy 222.819115 134.89959) (xy 222.819115 134.88586)
			(xy 222.819115 134.87213) (xy 222.819115 134.85839) (xy 222.805375 134.85839) (xy 222.805375 134.84466)
			(xy 222.805375 134.83093) (xy 222.791645 134.83093) (xy 222.791645 134.8172) (xy 222.791645 134.80347)
			(xy 222.777915 134.80347) (xy 222.777915 134.78973) (xy 222.777915 134.776) (xy 222.764185 134.776)
			(xy 222.764185 134.76227) (xy 222.764185 134.74854) (xy 222.750455 134.74854) (xy 222.750455 134.73481)
			(xy 222.750455 134.72107) (xy 222.736725 134.72107) (xy 222.736725 134.70734) (xy 222.736725 134.69361)
			(xy 222.722985 134.69361) (xy 222.722985 134.67988) (xy 222.722985 134.66615) (xy 222.709255 134.66615)
			(xy 222.709255 134.65242) (xy 222.709255 134.63868) (xy 222.695525 134.63868) (xy 222.695525 134.62495)
			(xy 222.695525 134.61122) (xy 222.681795 134.61122) (xy 222.681795 134.59749) (xy 222.668065 134.59749)
			(xy 222.668065 134.58376) (xy 222.668065 134.57003) (xy 222.654335 134.57003) (xy 222.654335 134.55629)
			(xy 222.654335 134.54256) (xy 222.640595 134.54256) (xy 222.640595 134.52883) (xy 222.640595 134.5151)
			(xy 222.626865 134.5151) (xy 222.626865 134.50137) (xy 222.626865 134.48764) (xy 222.613135 134.48764)
			(xy 222.613135 134.4739) (xy 222.599405 134.4739) (xy 222.599405 134.46017) (xy 222.599405 134.44644)
			(xy 222.585675 134.44644) (xy 222.585675 134.43271) (xy 222.585675 134.41898) (xy 222.571945 134.41898)
			(xy 222.571945 134.40525) (xy 222.558205 134.40525) (xy 222.558205 134.39151) (xy 222.558205 134.37778)
			(xy 222.544475 134.37778) (xy 222.544475 134.36405) (xy 222.544475 134.35032) (xy 222.530745 134.35032)
			(xy 222.530745 134.33659) (xy 222.517015 134.33659) (xy 222.517015 134.32286) (xy 222.517015 134.30912)
			(xy 222.503285 134.30912) (xy 222.503285 134.29539) (xy 222.503285 134.28166) (xy 222.489555 134.28166)
			(xy 222.489555 134.26793) (xy 222.475815 134.26793) (xy 222.475815 134.2542) (xy 222.475815 134.24046)
			(xy 222.462085 134.24046) (xy 222.462085 134.22673) (xy 222.448355 134.22673) (xy 222.448355 134.213)
			(xy 222.448355 134.19927) (xy 222.434625 134.19927) (xy 222.434625 134.18554) (xy 222.420895 134.18554)
			(xy 222.420895 134.1718) (xy 222.420895 134.15807) (xy 222.407165 134.15807) (xy 222.407165 134.14434)
			(xy 222.393425 134.14434) (xy 222.393425 134.13061) (xy 222.393425 134.11688) (xy 222.379695 134.11688)
			(xy 222.379695 134.10315) (xy 222.365965 134.10315) (xy 222.365965 134.08941) (xy 222.365965 134.07568)
			(xy 222.352235 134.07568) (xy 222.352235 134.06195) (xy 222.338505 134.06195) (xy 222.338505 134.04822)
			(xy 222.324765 134.04822) (xy 222.324765 134.03449) (xy 222.324765 134.02076) (xy 222.311035 134.02076)
			(xy 222.311035 134.00702) (xy 222.297305 134.00702) (xy 222.297305 133.99329) (xy 222.297305 133.97956)
			(xy 222.283575 133.97956) (xy 222.283575 133.96583) (xy 222.269845 133.96583) (xy 222.269845 133.9521)
			(xy 222.256105 133.9521) (xy 222.256105 133.93837) (xy 222.256105 133.92463) (xy 222.242375 133.92463)
			(xy 222.242375 133.9109) (xy 222.228645 133.9109) (xy 222.228645 133.89717) (xy 222.214915 133.89717)
			(xy 222.214915 133.88344) (xy 222.201185 133.88344) (xy 222.201185 133.86971) (xy 222.201185 133.85598)
			(xy 222.187455 133.85598) (xy 222.187455 133.84224) (xy 222.173715 133.84224) (xy 222.173715 133.82851)
			(xy 222.159985 133.82851) (xy 222.159985 133.81478) (xy 222.159985 133.80105) (xy 222.146255 133.80105)
			(xy 222.146255 133.78732) (xy 222.132525 133.78732) (xy 222.132525 133.77359) (xy 222.118795 133.77359)
			(xy 222.118795 133.75985) (xy 222.105065 133.75985) (xy 222.105065 133.74612) (xy 222.091325 133.74612)
			(xy 222.091325 133.73239) (xy 222.091325 133.71866) (xy 222.077595 133.71866) (xy 222.077595 133.70493)
			(xy 222.063865 133.70493) (xy 222.063865 133.69119) (xy 222.050135 133.69119) (xy 222.050135 133.67746)
			(xy 222.036405 133.67746) (xy 222.036405 133.66373) (xy 222.022675 133.66373) (xy 222.022675 133.65)
			(xy 222.022675 133.63627) (xy 222.008935 133.63627) (xy 222.008935 133.62253) (xy 221.995205 133.62253)
			(xy 221.995205 133.6088) (xy 221.981475 133.6088) (xy 221.981475 133.59507) (xy 221.967745 133.59507)
			(xy 221.967745 133.58134) (xy 221.954015 133.58134) (xy 221.954015 133.56761) (xy 221.940285 133.56761)
			(xy 221.940285 133.55388) (xy 221.926545 133.55388) (xy 221.926545 133.54014) (xy 221.912815 133.54014)
			(xy 221.912815 133.52641) (xy 221.912815 133.51268) (xy 221.899085 133.51268) (xy 221.899085 133.49895)
			(xy 221.885355 133.49895) (xy 221.885355 133.48522) (xy 221.871625 133.48522) (xy 221.871625 133.47149)
			(xy 221.857895 133.47149) (xy 221.857895 133.45775) (xy 221.844155 133.45775) (xy 221.844155 133.44402)
			(xy 221.830425 133.44402) (xy 221.830425 133.43029) (xy 221.816695 133.43029) (xy 221.816695 133.41656)
			(xy 221.802965 133.41656) (xy 221.802965 133.40283) (xy 221.789235 133.40283) (xy 221.789235 133.3891)
			(xy 221.775495 133.3891) (xy 221.775495 133.37536) (xy 221.761765 133.37536) (xy 221.761765 133.36163)
			(xy 221.748035 133.36163) (xy 221.748035 133.3479) (xy 221.734305 133.3479) (xy 221.734305 133.33417)
			(xy 221.720575 133.33417) (xy 221.720575 133.32044) (xy 221.706835 133.32044) (xy 221.706835 133.30671)
			(xy 221.693105 133.30671) (xy 221.693105 133.29297) (xy 221.679375 133.29297) (xy 221.679375 133.27924)
			(xy 221.665645 133.27924) (xy 221.665645 133.26551) (xy 221.651915 133.26551) (xy 221.651915 133.25178)
			(xy 221.638185 133.25178) (xy 221.638185 133.23805) (xy 221.624445 133.23805) (xy 221.624445 133.22431)
			(xy 221.596985 133.22431) (xy 221.596985 133.21058) (xy 221.583255 133.21058) (xy 221.583255 133.19685)
			(xy 221.569525 133.19685) (xy 221.569525 133.18312) (xy 221.555795 133.18312) (xy 221.555795 133.16939)
			(xy 221.542055 133.16939) (xy 221.542055 133.15565) (xy 221.528325 133.15565) (xy 221.528325 133.14192)
			(xy 221.514595 133.14192) (xy 221.514595 133.12819) (xy 221.500865 133.12819) (xy 221.500865 133.11446)
			(xy 221.487135 133.11446) (xy 221.487135 133.10073) (xy 221.459665 133.10073) (xy 221.459665 133.087)
			(xy 221.445935 133.087) (xy 221.445935 133.07326) (xy 221.432205 133.07326) (xy 221.432205 133.05953)
			(xy 221.418475 133.05953) (xy 221.418475 133.0458) (xy 221.404745 133.0458) (xy 221.404745 133.03207)
			(xy 221.377275 133.03207) (xy 221.377275 133.01834) (xy 221.363545 133.01834) (xy 221.363545 133.00461)
			(xy 221.349815 133.00461) (xy 221.349815 132.99087) (xy 221.336085 132.99087) (xy 221.336085 132.97714)
			(xy 221.322355 132.97714) (xy 221.322355 132.96341) (xy 221.294885 132.96341) (xy 221.294885 132.94968)
			(xy 221.281155 132.94968) (xy 221.281155 132.93595) (xy 221.267425 132.93595) (xy 221.267425 132.92222)
			(xy 221.239955 132.92222) (xy 221.239955 132.90848) (xy 221.226225 132.90848) (xy 221.226225 132.89475)
			(xy 221.212495 132.89475) (xy 221.212495 132.88102) (xy 221.198765 132.88102) (xy 221.198765 132.86729)
			(xy 221.171305 132.86729) (xy 221.171305 132.85356) (xy 221.157565 132.85356) (xy 221.157565 132.83983)
			(xy 221.130105 132.83983) (xy 221.130105 132.82609) (xy 221.116375 132.82609) (xy 221.116375 132.81236)
			(xy 221.102645 132.81236) (xy 221.102645 132.79863) (xy 221.075175 132.79863) (xy 221.075175 132.7849)
			(xy 221.061445 132.7849) (xy 221.061445 132.77117) (xy 221.047715 132.77117) (xy 221.047715 132.75744)
			(xy 221.020255 132.75744) (xy 221.020255 132.7437) (xy 221.006525 132.7437) (xy 221.006525 132.72997)
			(xy 220.979055 132.72997) (xy 220.979055 132.71624) (xy 220.965325 132.71624) (xy 220.965325 132.70251)
			(xy 220.937865 132.70251) (xy 220.937865 132.68878) (xy 220.924135 132.68878) (xy 220.924135 132.67504)
			(xy 220.896665 132.67504) (xy 220.896665 132.66131) (xy 220.882935 132.66131) (xy 220.882935 132.64758)
			(xy 220.855475 132.64758) (xy 220.855475 132.63385) (xy 220.828005 132.63385) (xy 220.828005 132.62012)
			(xy 220.814275 132.62012) (xy 220.814275 132.60638) (xy 220.786815 132.60638) (xy 220.786815 132.59265)
			(xy 220.773085 132.59265) (xy 220.773085 132.57892) (xy 220.745615 132.57892) (xy 220.745615 132.56519)
			(xy 220.718155 132.56519) (xy 220.718155 132.55146) (xy 220.704425 132.55146) (xy 220.704425 132.53773)
			(xy 220.676955 132.53773) (xy 220.676955 132.52399) (xy 220.649495 132.52399) (xy 220.649495 132.51026)
			(xy 220.622035 132.51026) (xy 220.622035 132.49653) (xy 220.608295 132.49653) (xy 220.608295 132.4828)
			(xy 220.580835 132.4828) (xy 220.580835 132.46907) (xy 220.553375 132.46907) (xy 220.553375 132.45534)
			(xy 220.525905 132.45534) (xy 220.525905 132.4416) (xy 220.498445 132.4416) (xy 220.498445 132.42787)
			(xy 220.484715 132.42787) (xy 220.484715 132.41414) (xy 220.443515 132.41414) (xy 220.443515 132.40041)
			(xy 220.429785 132.40041) (xy 220.429785 132.38668) (xy 220.402325 132.38668) (xy 220.402325 132.37295)
			(xy 220.361125 132.37295) (xy 220.361125 132.35921) (xy 220.333665 132.35921) (xy 220.333665 132.34548)
			(xy 220.319935 132.34548) (xy 220.319935 132.33175) (xy 220.292475 132.33175) (xy 220.292475 132.31802)
			(xy 220.251275 132.31802) (xy 220.251275 132.30429) (xy 220.223815 132.30429) (xy 220.223815 132.29056)
			(xy 220.196345 132.29056) (xy 220.196345 132.27682) (xy 220.168885 132.27682) (xy 220.168885 132.26309)
			(xy 220.141415 132.26309) (xy 220.141415 132.24936) (xy 220.100225 132.24936) (xy 220.100225 132.23563)
			(xy 220.072765 132.23563) (xy 220.072765 132.2219) (xy 220.045295 132.2219) (xy 220.045295 132.20817)
			(xy 220.004105 132.20817) (xy 220.004105 132.19443) (xy 219.976635 132.19443) (xy 219.976635 132.1807)
			(xy 219.935445 132.1807) (xy 219.935445 132.16697) (xy 219.894245 132.16697) (xy 219.894245 132.15324)
			(xy 219.866785 132.15324) (xy 219.866785 132.13951) (xy 219.825595 132.13951) (xy 219.825595 132.12577)
			(xy 219.784395 132.12577) (xy 219.784395 132.11204) (xy 219.743205 132.11204) (xy 219.743205 132.09831)
			(xy 219.715735 132.09831) (xy 219.715735 132.08458) (xy 219.674545 132.08458) (xy 219.674545 132.07085)
			(xy 219.633345 132.07085) (xy 219.633345 132.05711) (xy 219.578415 132.05711) (xy 219.578415 132.04338)
			(xy 219.537225 132.04338) (xy 219.537225 132.02965) (xy 219.496025 132.02965) (xy 219.496025 132.01592)
			(xy 219.441105 132.01592) (xy 219.441105 132.00219) (xy 219.399905 132.00219) (xy 219.399905 131.98846)
			(xy 219.344975 131.98846) (xy 219.344975 131.97472) (xy 219.290055 131.97472) (xy 219.290055 131.96099)
			(xy 219.235125 131.96099) (xy 219.235125 131.94726) (xy 219.180195 131.94726) (xy 219.180195 131.93353)
			(xy 219.111535 131.93353) (xy 219.111535 131.9198) (xy 219.042875 131.9198) (xy 219.042875 131.90607)
			(xy 218.974225 131.90607) (xy 218.974225 131.89233) (xy 218.891835 131.89233) (xy 218.891835 131.8786)
			(xy 218.809445 131.8786) (xy 218.809445 131.86487) (xy 218.699585 131.86487) (xy 218.699585 131.85114)
			(xy 218.589735 131.85114) (xy 218.589735 131.83741) (xy 218.466145 131.83741) (xy 218.466145 131.82368)
			(xy 218.260175 131.82368) (xy 218.260175 131.80995) (xy 217.752095 131.80995) (xy 217.752095 131.82368)
			(xy 217.546115 131.82368) (xy 217.546115 131.83741) (xy 217.408805 131.83741) (xy 217.408805 131.85114)
			(xy 217.298945 131.85114) (xy 217.298945 131.86487) (xy 217.216555 131.86487) (xy 217.216555 131.8786)
			(xy 217.120435 131.8786) (xy 217.120435 131.89233) (xy 217.038045 131.89233) (xy 217.038045 131.90607)
			(xy 216.969385 131.90607) (xy 216.969385 131.9198) (xy 216.900725 131.9198) (xy 216.900725 131.93353)
			(xy 216.832065 131.93353) (xy 216.832065 131.94726) (xy 216.777145 131.94726) (xy 216.777145 131.96099)
			(xy 216.722215 131.96099) (xy 216.722215 131.97472) (xy 216.667285 131.97472) (xy 216.667285 131.98846)
			(xy 216.612365 131.98846) (xy 216.612365 132.00219) (xy 216.571165 132.00219) (xy 216.571165 132.01592)
			(xy 216.516235 132.01592) (xy 216.516235 132.02965) (xy 216.475045 132.02965) (xy 216.475045 132.04338)
			(xy 216.433845 132.04338) (xy 216.433845 132.05711) (xy 216.378925 132.05711) (xy 216.378925 132.07085)
			(xy 216.337725 132.07085) (xy 216.337725 132.08458) (xy 216.296535 132.08458) (xy 216.296535 132.09831)
			(xy 216.255335 132.09831) (xy 216.255335 132.11204) (xy 216.227875 132.11204) (xy 216.227875 132.12577)
			(xy 216.186675 132.12577) (xy 216.186675 132.13951) (xy 216.145485 132.13951) (xy 216.145485 132.15324)
			(xy 216.104285 132.15324) (xy 216.104285 132.16697) (xy 216.076825 132.16697) (xy 216.076825 132.1807)
			(xy 216.035625 132.1807) (xy 216.035625 132.19443) (xy 216.008165 132.19443) (xy 216.008165 132.20817)
			(xy 215.966965 132.20817) (xy 215.966965 132.2219) (xy 215.939505 132.2219) (xy 215.939505 132.23563)
			(xy 215.912045 132.23563) (xy 215.912045 132.24936) (xy 215.870845 132.24936) (xy 215.870845 132.26309)
			(xy 215.843385 132.26309) (xy 215.843385 132.27682) (xy 215.815915 132.27682) (xy 215.815915 132.29056)
			(xy 215.788455 132.29056) (xy 215.788455 132.30429) (xy 215.747265 132.30429) (xy 215.747265 132.31802)
			(xy 215.719795 132.31802) (xy 215.719795 132.33175) (xy 215.692335 132.33175) (xy 215.692335 132.34548)
			(xy 215.664875 132.34548) (xy 215.664875 132.35921) (xy 215.637405 132.35921) (xy 215.637405 132.37295)
			(xy 215.609945 132.37295) (xy 215.609945 132.38668) (xy 215.582485 132.38668) (xy 215.582485 132.40041)
			(xy 215.555015 132.40041) (xy 215.555015 132.41414) (xy 215.527555 132.41414) (xy 215.527555 132.42787)
			(xy 215.500085 132.42787) (xy 215.500085 132.4416) (xy 215.486355 132.4416) (xy 215.486355 132.45534)
			(xy 215.458895 132.45534) (xy 215.458895 132.46907) (xy 215.431425 132.46907) (xy 215.431425 132.4828)
			(xy 215.403965 132.4828) (xy 215.403965 132.49653) (xy 215.376505 132.49653) (xy 215.376505 132.51026)
			(xy 215.362775 132.51026) (xy 215.362775 132.52399) (xy 215.335305 132.52399) (xy 215.335305 132.53773)
			(xy 215.307845 132.53773) (xy 215.307845 132.55146) (xy 215.294115 132.55146) (xy 215.294115 132.56519)
			(xy 215.266645 132.56519) (xy 215.266645 132.57892) (xy 215.239185 132.57892) (xy 215.239185 132.59265)
			(xy 215.225455 132.59265) (xy 215.225455 132.60638) (xy 215.197995 132.60638) (xy 215.197995 132.62012)
			(xy 215.170525 132.62012) (xy 215.170525 132.63385) (xy 215.156795 132.63385) (xy 215.156795 132.64758)
			(xy 215.129335 132.64758) (xy 215.129335 132.66131) (xy 215.115605 132.66131) (xy 215.115605 132.67504)
			(xy 215.088135 132.67504) (xy 215.088135 132.68878) (xy 215.074405 132.68878) (xy 215.074405 132.70251)
			(xy 215.046945 132.70251) (xy 215.046945 132.71624) (xy 215.033215 132.71624) (xy 215.033215 132.72997)
			(xy 215.005745 132.72997) (xy 215.005745 132.7437) (xy 214.992015 132.7437) (xy 214.992015 132.75744)
			(xy 214.964555 132.75744) (xy 214.964555 132.77117) (xy 214.950815 132.77117) (xy 214.950815 132.7849)
			(xy 214.937085 132.7849) (xy 214.937085 132.79863) (xy 214.909625 132.79863) (xy 214.909625 132.81236)
			(xy 214.895895 132.81236) (xy 214.895895 132.82609) (xy 214.868425 132.82609) (xy 214.868425 132.83983)
			(xy 214.854695 132.83983) (xy 214.854695 132.85356) (xy 214.840965 132.85356) (xy 214.840965 132.86729)
			(xy 214.813505 132.86729) (xy 214.813505 132.88102) (xy 214.799765 132.88102) (xy 214.799765 132.89475)
			(xy 214.786035 132.89475) (xy 214.786035 132.90848) (xy 214.758575 132.90848) (xy 214.758575 132.92222)
			(xy 214.744845 132.92222) (xy 214.744845 132.93595) (xy 214.731115 132.93595) (xy 214.731115 132.94968)
			(xy 214.717375 132.94968) (xy 214.717375 132.96341) (xy 214.689915 132.96341) (xy 214.689915 132.97714)
			(xy 214.676185 132.97714) (xy 214.676185 132.99087) (xy 214.662455 132.99087) (xy 214.662455 133.00461)
			(xy 214.648725 133.00461) (xy 214.648725 133.01834) (xy 214.621255 133.01834) (xy 214.621255 133.03207)
			(xy 214.607525 133.03207) (xy 214.607525 133.0458) (xy 214.593795 133.0458) (xy 214.593795 133.05953)
			(xy 214.580065 133.05953) (xy 214.580065 133.07326) (xy 214.566335 133.07326) (xy 214.566335 133.087)
			(xy 214.538865 133.087) (xy 214.538865 133.10073) (xy 214.525135 133.10073) (xy 214.525135 133.11446)
			(xy 214.511405 133.11446) (xy 214.511405 133.12819) (xy 214.497675 133.12819) (xy 214.497675 133.14192)
			(xy 214.483935 133.14192) (xy 214.483935 133.15565) (xy 214.470205 133.15565) (xy 214.470205 133.16939)
			(xy 214.456475 133.16939) (xy 214.456475 133.18312) (xy 214.442745 133.18312) (xy 214.442745 133.19685)
			(xy 214.415275 133.19685) (xy 214.415275 133.21058) (xy 214.401545 133.21058) (xy 214.401545 133.22431)
			(xy 214.387815 133.22431) (xy 214.387815 133.23805) (xy 214.374085 133.23805) (xy 214.374085 133.25178)
			(xy 214.360355 133.25178) (xy 214.360355 133.26551) (xy 214.346625 133.26551) (xy 214.346625 133.27924)
			(xy 214.332885 133.27924) (xy 214.332885 133.29297) (xy 214.319155 133.29297) (xy 214.319155 133.30671)
			(xy 214.305425 133.30671) (xy 214.305425 133.32044) (xy 214.291695 133.32044) (xy 214.291695 133.33417)
			(xy 214.277965 133.33417) (xy 214.277965 133.3479) (xy 214.264235 133.3479) (xy 214.264235 133.36163)
			(xy 214.250495 133.36163) (xy 214.250495 133.37536) (xy 214.236765 133.37536) (xy 214.236765 133.3891)
			(xy 214.223035 133.3891) (xy 214.223035 133.40283) (xy 214.209305 133.40283) (xy 214.209305 133.41656)
			(xy 214.195575 133.41656) (xy 214.195575 133.43029) (xy 214.181845 133.43029) (xy 214.181845 133.44402)
			(xy 214.168105 133.44402) (xy 214.168105 133.45775) (xy 214.154375 133.45775) (xy 214.154375 133.47149)
			(xy 214.140645 133.47149) (xy 214.140645 133.48522) (xy 214.126915 133.48522) (xy 214.126915 133.49895)
			(xy 214.113185 133.49895) (xy 214.113185 133.51268) (xy 214.099455 133.51268) (xy 214.099455 133.52641)
			(xy 214.085715 133.52641) (xy 214.085715 133.54014) (xy 214.085715 133.55388) (xy 214.071985 133.55388)
			(xy 214.071985 133.56761) (xy 214.058255 133.56761) (xy 214.058255 133.58134) (xy 214.044525 133.58134)
			(xy 214.044525 133.59507) (xy 214.030795 133.59507) (xy 214.030795 133.6088) (xy 214.017065 133.6088)
			(xy 214.017065 133.62253) (xy 214.003325 133.62253) (xy 214.003325 133.63627) (xy 213.989595 133.63627)
			(xy 213.989595 133.65) (xy 213.975865 133.65) (xy 213.975865 133.66373) (xy 213.975865 133.67746)
			(xy 213.962135 133.67746) (xy 213.962135 133.69119) (xy 213.948405 133.69119) (xy 213.948405 133.70493)
			(xy 213.934665 133.70493) (xy 213.934665 133.71866) (xy 213.920935 133.71866) (xy 213.920935 133.73239)
			(xy 213.907205 133.73239) (xy 213.907205 133.74612) (xy 213.907205 133.75985) (xy 213.893475 133.75985)
			(xy 213.893475 133.77359) (xy 213.879745 133.77359) (xy 213.879745 133.78732) (xy 213.866005 133.78732)
			(xy 209.526775 133.78732) (xy 209.526775 133.77359) (xy 209.526775 133.75985) (xy 209.526775 133.74612)
			(xy 209.526775 133.73239) (xy 209.526775 133.71866) (xy 209.526775 133.70493) (xy 209.526775 133.69119)
			(xy 209.526775 133.67746) (xy 209.526775 133.66373) (xy 209.526775 133.65) (xy 209.526775 133.63627)
			(xy 209.526775 133.62253) (xy 209.526775 133.6088) (xy 209.526775 133.59507) (xy 209.526775 133.58134)
			(xy 209.526775 133.56761) (xy 209.526775 133.55388) (xy 209.526775 133.54014) (xy 209.526775 133.52641)
			(xy 209.526775 133.51268) (xy 209.526775 133.49895) (xy 209.526775 133.48522) (xy 209.526775 133.47149)
			(xy 209.526775 133.45775) (xy 209.526775 133.44402) (xy 209.526775 133.43029) (xy 209.526775 133.41656)
			(xy 209.526775 133.40283) (xy 209.526775 133.3891) (xy 209.526775 133.37536) (xy 209.526775 133.36163)
			(xy 209.526775 133.3479) (xy 209.526775 133.33417) (xy 209.526775 133.32044) (xy 209.526775 133.30671)
			(xy 209.526775 133.29297) (xy 209.526775 133.27924) (xy 209.526775 133.26551) (xy 209.526775 133.25178)
			(xy 209.526775 133.23805) (xy 209.526775 133.22431) (xy 209.526775 133.21058) (xy 209.526775 133.19685)
			(xy 209.526775 133.18312) (xy 209.526775 133.16939) (xy 209.526775 133.15565) (xy 209.526775 133.14192)
			(xy 209.526775 133.12819) (xy 209.526775 133.11446) (xy 209.526775 133.10073) (xy 209.526775 133.087)
			(xy 209.526775 133.07326) (xy 209.526775 133.05953) (xy 209.526775 133.0458) (xy 209.526775 133.03207)
			(xy 209.526775 133.01834) (xy 209.526775 133.00461) (xy 209.526775 132.99087) (xy 209.526775 132.97714)
			(xy 209.526775 132.96341) (xy 209.526775 132.94968) (xy 209.526775 132.93595) (xy 209.526775 132.92222)
			(xy 209.526775 132.90848) (xy 209.526775 132.89475) (xy 209.526775 132.88102) (xy 209.526775 132.86729)
			(xy 209.526775 132.85356) (xy 209.526775 132.83983) (xy 209.526775 132.82609) (xy 209.526775 132.81236)
			(xy 209.526775 132.79863) (xy 209.526775 132.7849) (xy 209.526775 132.77117) (xy 209.526775 132.75744)
			(xy 209.526775 132.7437) (xy 209.526775 132.72997) (xy 209.526775 132.71624) (xy 209.526775 132.70251)
			(xy 209.526775 132.68878) (xy 209.526775 132.67504) (xy 209.526775 132.66131) (xy 209.526775 132.64758)
			(xy 209.526775 132.63385) (xy 209.526775 132.62012) (xy 209.526775 132.60638) (xy 209.526775 132.59265)
			(xy 209.526775 132.57892) (xy 209.526775 132.56519) (xy 209.526775 132.55146) (xy 209.526775 132.53773)
			(xy 209.526775 132.52399) (xy 209.526775 132.51026) (xy 209.526775 132.49653) (xy 209.526775 132.4828)
			(xy 209.526775 132.46907) (xy 209.526775 132.45534) (xy 209.526775 132.4416) (xy 209.526775 132.42787)
			(xy 209.526775 132.41414) (xy 209.526775 132.40041) (xy 209.526775 132.38668) (xy 209.526775 132.37295)
			(xy 209.526775 132.35921) (xy 209.526775 132.34548) (xy 209.526775 132.33175) (xy 209.526775 132.31802)
			(xy 209.526775 132.30429) (xy 209.526775 132.29056) (xy 209.526775 132.27682) (xy 209.526775 132.26309)
			(xy 209.526775 132.24936) (xy 209.526775 132.23563) (xy 209.526775 132.2219) (xy 209.526775 132.20817)
			(xy 209.526775 132.19443) (xy 209.526775 132.1807) (xy 209.526775 132.16697) (xy 209.526775 132.15324)
			(xy 209.526775 132.13951) (xy 209.526775 132.12577) (xy 209.526775 132.11204) (xy 209.526775 132.09831)
			(xy 209.526775 132.08458) (xy 209.526775 132.07085) (xy 209.526775 132.05711) (xy 209.526775 132.04338)
			(xy 209.526775 132.02965) (xy 209.526775 132.01592) (xy 209.526775 132.00219) (xy 209.526775 131.98846)
			(xy 209.526775 131.97472) (xy 209.526775 131.96099) (xy 209.526775 131.94726) (xy 209.526775 131.93353)
			(xy 209.526775 131.9198) (xy 209.526775 131.90607) (xy 209.526775 131.89233) (xy 209.526775 131.8786)
			(xy 209.526775 131.86487) (xy 209.526775 131.85114) (xy 209.526775 131.83741) (xy 209.526775 131.82368)
			(xy 209.526775 131.80995) (xy 209.526775 131.79621) (xy 209.526775 131.78248) (xy 209.526775 131.76875)
			(xy 209.526775 131.75502) (xy 209.526775 131.74129) (xy 209.526775 131.72756) (xy 209.526775 131.71382)
			(xy 209.526775 131.70009) (xy 209.526775 131.68636) (xy 209.526775 131.67263) (xy 209.526775 131.6589)
			(xy 209.526775 131.64516) (xy 209.526775 131.63143) (xy 209.526775 131.6177) (xy 209.526775 131.60397)
			(xy 209.526775 131.59024) (xy 209.526775 131.5765) (xy 209.526775 131.56277) (xy 209.526775 131.54904)
			(xy 209.526775 131.53531) (xy 209.526775 131.52158) (xy 209.526775 131.50785) (xy 209.526775 131.49411)
			(xy 209.526775 131.48038) (xy 209.526775 131.46665) (xy 209.526775 131.45292) (xy 209.526775 131.43919)
			(xy 209.526775 131.42546) (xy 209.526775 131.41172) (xy 209.526775 131.39799) (xy 209.526775 131.38426)
			(xy 209.526775 131.37053) (xy 209.526775 131.3568) (xy 209.526775 131.34307) (xy 209.526775 131.32933)
			(xy 209.526775 131.3156) (xy 209.526775 131.30187) (xy 209.526775 131.28814) (xy 209.526775 131.27441)
			(xy 209.526775 131.26068) (xy 209.526775 131.24694) (xy 209.526775 131.23321) (xy 209.526775 131.21948)
			(xy 209.526775 131.20575) (xy 209.526775 131.19202) (xy 209.526775 131.17828) (xy 209.526775 131.16455)
			(xy 209.526775 131.15082) (xy 209.526775 131.13709) (xy 209.526775 131.12336) (xy 209.526775 131.10962)
			(xy 209.526775 131.09589) (xy 209.526775 131.08216) (xy 209.526775 131.06843) (xy 209.526775 131.0547)
			(xy 209.526775 131.04097) (xy 209.526775 131.02723) (xy 209.526775 131.0135) (xy 209.526775 130.99977)
			(xy 209.526775 130.98604) (xy 209.526775 130.97231) (xy 209.526775 130.95858) (xy 209.526775 130.94484)
			(xy 209.526775 130.93111) (xy 209.526775 130.91738) (xy 209.526775 130.90365) (xy 209.526775 130.88992)
			(xy 209.526775 130.87619) (xy 209.526775 130.86245) (xy 209.526775 130.84872) (xy 209.526775 130.83499)
			(xy 209.526775 130.82126) (xy 209.526775 130.80753) (xy 209.526775 130.7938) (xy 209.526775 130.78006)
			(xy 209.526775 130.76633) (xy 209.526775 130.7526) (xy 209.526775 130.73887) (xy 209.526775 130.72514)
			(xy 209.526775 130.71141) (xy 209.526775 130.69767) (xy 209.526775 130.68394) (xy 209.540505 130.68394)
			(xy 209.540505 130.67021) (xy 226.869975 130.67021)
		)
		(stroke
			(width 0)
			(type default)
		)
		(fill yes)
		(layer "F.Cu")
	)
	(gr_rect
		(start 103.788595 154.6036)
		(end 106.463595 152.8786)
		(stroke
			(width 0)
			(type default)
		)
		(fill yes)
		(layer "F.Cu")
		(net "+12V_PCIE")
	)
	(gr_rect
		(start 110.738595 154.5786)
		(end 113.543575 152.8786)
		(stroke
			(width 0)
			(type default)
		)
		(fill yes)
		(layer "F.Cu")
		(net "+3.3V_PCIE")
	)
	(gr_rect
		(start 104.588595 154.6036)
		(end 106.463595 152.8786)
		(stroke
			(width 0)
			(type default)
		)
		(fill yes)
		(layer "B.Cu")
		(net "+12V_PCIE")
	)
	(gr_rect
		(start 111.668575 154.62058)
		(end 113.543575 152.89558)
		(stroke
			(width 0)
			(type default)
		)
		(fill yes)
		(layer "B.Cu")
		(net "+3.3V_PCIE")
	)
	(gr_line
		(start 58.488595 49.4286)
		(end 58.488595 156.0786)
		(stroke
			(width 0.05)
			(type solid)
		)
		(layer "Edge.Cuts")
	)
	(gr_line
		(start 58.488595 156.0786)
		(end 73.488595 156.0786)
		(stroke
			(width 0.05)
			(type solid)
		)
		(layer "Edge.Cuts")
	)
	(gr_line
		(start 73.488595 147.8286)
		(end 91.838595 147.8286)
		(stroke
			(width 0.05)
			(type solid)
		)
		(layer "Edge.Cuts")
	)
	(gr_line
		(start 73.488595 156.0786)
		(end 73.488595 147.8286)
		(stroke
			(width 0.05)
			(type solid)
		)
		(layer "Edge.Cuts")
	)
	(gr_line
		(start 91.838595 147.8286)
		(end 91.838595 156.0786)
		(stroke
			(width 0.05)
			(type solid)
		)
		(layer "Edge.Cuts")
	)
	(gr_line
		(start 91.838595 156.0786)
		(end 99.838595 156.0786)
		(stroke
			(width 0.05)
			(type solid)
		)
		(layer "Edge.Cuts")
	)
	(gr_arc
		(start 99.838595 149.6536)
		(mid 101.663595 147.8286)
		(end 103.488595 149.6536)
		(stroke
			(width 0.05)
			(type solid)
		)
		(layer "Edge.Cuts")
	)
	(gr_line
		(start 99.838595 156.0786)
		(end 99.838595 149.6536)
		(stroke
			(width 0.05)
			(type solid)
		)
		(layer "Edge.Cuts")
	)
	(gr_line
		(start 103.488595 149.6536)
		(end 103.488595 160.0786)
		(stroke
			(width 0.05)
			(type solid)
		)
		(layer "Edge.Cuts")
	)
	(gr_line
		(start 103.488595 160.0786)
		(end 103.988595 160.5786)
		(stroke
			(width 0.05)
			(type solid)
		)
		(layer "Edge.Cuts")
	)
	(gr_line
		(start 103.988595 160.5786)
		(end 114.188595 160.5786)
		(stroke
			(width 0.05)
			(type solid)
		)
		(layer "Edge.Cuts")
	)
	(gr_line
		(start 114.188595 160.5786)
		(end 114.688595 160.0786)
		(stroke
			(width 0.05)
			(type solid)
		)
		(layer "Edge.Cuts")
	)
	(gr_arc
		(start 114.688595 153.1286)
		(mid 115.638595 152.1786)
		(end 116.588595 153.1286)
		(stroke
			(width 0.05)
			(type solid)
		)
		(layer "Edge.Cuts")
	)
	(gr_line
		(start 114.688595 160.0786)
		(end 114.688595 153.1286)
		(stroke
			(width 0.05)
			(type solid)
		)
		(layer "Edge.Cuts")
	)
	(gr_line
		(start 116.588595 153.1286)
		(end 116.588595 160.0786)
		(stroke
			(width 0.05)
			(type solid)
		)
		(layer "Edge.Cuts")
	)
	(gr_line
		(start 116.588595 160.0786)
		(end 117.088595 160.5786)
		(stroke
			(width 0.05)
			(type solid)
		)
		(layer "Edge.Cuts")
	)
	(gr_line
		(start 117.088595 160.5786)
		(end 137.288595 160.5786)
		(stroke
			(width 0.05)
			(type solid)
		)
		(layer "Edge.Cuts")
	)
	(gr_line
		(start 137.288595 160.5786)
		(end 137.788595 160.0786)
		(stroke
			(width 0.05)
			(type solid)
		)
		(layer "Edge.Cuts")
	)
	(gr_line
		(start 137.788595 147.8286)
		(end 238.513605 147.8286)
		(stroke
			(width 0.05)
			(type solid)
		)
		(layer "Edge.Cuts")
	)
	(gr_line
		(start 137.788595 160.0786)
		(end 137.788595 147.8286)
		(stroke
			(width 0.05)
			(type solid)
		)
		(layer "Edge.Cuts")
	)
	(gr_line
		(start 238.513595 49.4286)
		(end 58.488595 49.4286)
		(stroke
			(width 0.05)
			(type solid)
		)
		(layer "Edge.Cuts")
	)
	(gr_line
		(start 238.513605 147.8286)
		(end 238.513595 49.4286)
		(stroke
			(width 0.05)
			(type solid)
		)
		(layer "Edge.Cuts")
	)
	(segment
		(start 150.888595 84.1786)
		(end 150.888595 74.2786)
		(width 0.2032)
		(layer "F.Cu")
		(net "EXT_EEPROM_WP")
	)
	(segment
		(start 151.225895 118.08331)
		(end 151.228255 118.08096)
		(width 0.2032)
		(layer "F.Cu")
		(net "EXT_EEPROM_WP")
	)
	(segment
		(start 169.638595 62.51239)
		(end 169.638595 61.7286)
		(width 0.2032)
		(layer "F.Cu")
		(net "EXT_EEPROM_WP")
	)
	(segment
		(start 153.188595 71.4786)
		(end 168.188595 71.4786)
		(width 0.2032)
		(layer "F.Cu")
		(net "EXT_EEPROM_WP")
	)
	(segment
		(start 169.638595 61.7286)
		(end 169.888595 61.4786)
		(width 0.2032)
		(layer "F.Cu")
		(net "EXT_EEPROM_WP")
	)
	(segment
		(start 150.788595 74.1786)
		(end 150.788595 73.8786)
		(width 0.2032)
		(layer "F.Cu")
		(net "EXT_EEPROM_WP")
	)
	(segment
		(start 152.788595 118.0786)
		(end 155.888595 114.9786)
		(width 0.2032)
		(layer "F.Cu")
		(net "EXT_EEPROM_WP")
	)
	(segment
		(start 151.228255 118.08096)
		(end 152.786245 118.08096)
		(width 0.2032)
		(layer "F.Cu")
		(net "EXT_EEPROM_WP")
	)
	(segment
		(start 150.788595 73.8786)
		(end 153.188595 71.4786)
		(width 0.2032)
		(layer "F.Cu")
		(net "EXT_EEPROM_WP")
	)
	(segment
		(start 170.088595 60.7536)
		(end 170.088595 59.5786)
		(width 0.2032)
		(layer "F.Cu")
		(net "EXT_EEPROM_WP")
	)
	(segment
		(start 150.888595 84.1786)
		(end 155.888595 89.1786)
		(width 0.2032)
		(layer "F.Cu")
		(net "EXT_EEPROM_WP")
	)
	(segment
		(start 155.888595 114.9786)
		(end 155.888595 89.1786)
		(width 0.2032)
		(layer "F.Cu")
		(net "EXT_EEPROM_WP")
	)
	(segment
		(start 169.888595 61.4786)
		(end 169.888595 61.0036)
		(width 0.2032)
		(layer "F.Cu")
		(net "EXT_EEPROM_WP")
	)
	(segment
		(start 169.888595 61.0036)
		(end 170.113595 60.7786)
		(width 0.2032)
		(layer "F.Cu")
		(net "EXT_EEPROM_WP")
	)
	(segment
		(start 150.788595 74.1786)
		(end 150.888595 74.2786)
		(width 0.2032)
		(layer "F.Cu")
		(net "EXT_EEPROM_WP")
	)
	(segment
		(start 152.786245 118.08096)
		(end 152.788595 118.0786)
		(width 0.2032)
		(layer "F.Cu")
		(net "EXT_EEPROM_WP")
	)
	(segment
		(start 170.088595 60.7536)
		(end 170.113595 60.7786)
		(width 0.2032)
		(layer "F.Cu")
		(net "EXT_EEPROM_WP")
	)
	(via
		(at 168.188595 71.4786)
		(size 0.4064)
		(drill 0.2032)
		(layers "F.Cu" "B.Cu")
		(net "EXT_EEPROM_WP")
	)
	(via
		(at 170.088595 59.5786)
		(size 0.4064)
		(drill 0.2032)
		(layers "F.Cu" "B.Cu")
		(net "EXT_EEPROM_WP")
	)
	(via
		(at 152.788595 118.0786)
		(size 0.4064)
		(drill 0.2032)
		(layers "F.Cu" "B.Cu")
		(net "EXT_EEPROM_WP")
	)
	(segment
		(start 170.088595 65.1786)
		(end 170.088595 59.5786)
		(width 0.2032)
		(layer "In3.Cu")
		(net "EXT_EEPROM_WP")
	)
	(segment
		(start 168.188595 71.4786)
		(end 168.188595 67.0786)
		(width 0.2032)
		(layer "In3.Cu")
		(net "EXT_EEPROM_WP")
	)
	(segment
		(start 168.188595 67.0786)
		(end 170.088595 65.1786)
		(width 0.2032)
		(layer "In3.Cu")
		(net "EXT_EEPROM_WP")
	)
	(segment
		(start 162.725595 64.7786)
		(end 162.751595 64.8046)
		(width 0.2032)
		(layer "F.Cu")
		(net "NetC54_2")
	)
	(segment
		(start 164.795595 66.5716)
		(end 165.037595 66.3296)
		(width 0.2032)
		(layer "F.Cu")
		(net "NetC54_2")
	)
	(segment
		(start 162.851595 64.7046)
		(end 165.037595 64.7046)
		(width 0.2032)
		(layer "F.Cu")
		(net "NetC54_2")
	)
	(segment
		(start 162.751595 64.8046)
		(end 162.851595 64.7046)
		(width 0.2032)
		(layer "F.Cu")
		(net "NetC54_2")
	)
	(segment
		(start 161.456095 65.1111)
		(end 161.788595 64.7786)
		(width 0.2032)
		(layer "F.Cu")
		(net "NetC54_2")
	)
	(segment
		(start 165.037595 66.3296)
		(end 165.037595 64.7046)
		(width 0.2032)
		(layer "F.Cu")
		(net "NetC54_2")
	)
	(segment
		(start 158.788595 65.0786)
		(end 159.729095 65.0786)
		(width 0.2032)
		(layer "F.Cu")
		(net "NetC54_2")
	)
	(segment
		(start 158.423595 64.7136)
		(end 158.788595 65.0786)
		(width 0.2032)
		(layer "F.Cu")
		(net "NetC54_2")
	)
	(segment
		(start 159.761595 65.1111)
		(end 161.456095 65.1111)
		(width 0.2032)
		(layer "F.Cu")
		(net "NetC54_2")
	)
	(segment
		(start 164.330595 66.5716)
		(end 164.795595 66.5716)
		(width 0.2032)
		(layer "F.Cu")
		(net "NetC54_2")
	)
	(segment
		(start 159.729095 65.0786)
		(end 159.761595 65.1111)
		(width 0.2032)
		(layer "F.Cu")
		(net "NetC54_2")
	)
	(segment
		(start 161.788595 64.7786)
		(end 162.725595 64.7786)
		(width 0.2032)
		(layer "F.Cu")
		(net "NetC54_2")
	)
	(segment
		(start 158.423595 64.7136)
		(end 158.423595 58.3766)
		(width 0.2032)
		(layer "F.Cu")
		(net "NetC54_2")
	)
	(segment
		(start 120.777595 70.0646)
		(end 122.111595 70.0646)
		(width 0.2032)
		(layer "F.Cu")
		(net "GPS1_TX")
	)
	(segment
		(start 133.643195 94.0036)
		(end 134.198185 94.55859)
		(width 0.2032)
		(layer "F.Cu")
		(net "GPS1_TX")
	)
	(segment
		(start 120.333595 70.5086)
		(end 120.777595 70.0646)
		(width 0.2032)
		(layer "F.Cu")
		(net "GPS1_TX")
	)
	(segment
		(start 134.198185 96.61497)
		(end 134.198185 94.55859)
		(width 0.2032)
		(layer "F.Cu")
		(net "GPS1_TX")
	)
	(via
		(at 133.643195 94.0036)
		(size 0.4064)
		(drill 0.2032)
		(layers "F.Cu" "B.Cu")
		(net "GPS1_TX")
	)
	(via
		(at 120.333595 70.5086)
		(size 0.4064)
		(drill 0.2032)
		(layers "F.Cu" "B.Cu")
		(net "GPS1_TX")
	)
	(via
		(at 120.190085 94.0036)
		(size 0.4064)
		(drill 0.2032)
		(layers "F.Cu" "B.Cu")
		(net "GPS1_TX")
	)
	(via
		(at 95.085995 70.2292)
		(size 0.4064)
		(drill 0.2032)
		(layers "F.Cu" "B.Cu")
		(net "GPS1_TX")
	)
	(segment
		(start 120.190085 94.0036)
		(end 133.643195 94.0036)
		(width 0.2032)
		(layer "In2.Cu")
		(net "GPS1_TX")
	)
	(segment
		(start 95.085995 70.2292)
		(end 120.054195 70.2292)
		(width 0.2032)
		(layer "In2.Cu")
		(net "GPS1_TX")
	)
	(segment
		(start 120.054195 70.2292)
		(end 120.333595 70.5086)
		(width 0.2032)
		(layer "In2.Cu")
		(net "GPS1_TX")
	)
	(segment
		(start 120.958775 74.3163)
		(end 120.958775 71.13378)
		(width 0.2032)
		(layer "In3.Cu")
		(net "GPS1_TX")
	)
	(segment
		(start 118.488595 92.30211)
		(end 120.190085 94.0036)
		(width 0.2032)
		(layer "In3.Cu")
		(net "GPS1_TX")
	)
	(segment
		(start 120.333595 70.5086)
		(end 120.958775 71.13378)
		(width 0.2032)
		(layer "In3.Cu")
		(net "GPS1_TX")
	)
	(segment
		(start 118.488595 76.78648)
		(end 120.958775 74.3163)
		(width 0.2032)
		(layer "In3.Cu")
		(net "GPS1_TX")
	)
	(segment
		(start 93.561995 68.7052)
		(end 93.561995 53.8462)
		(width 0.2032)
		(layer "In3.Cu")
		(net "GPS1_TX")
	)
	(segment
		(start 93.561995 68.7052)
		(end 95.085995 70.2292)
		(width 0.2032)
		(layer "In3.Cu")
		(net "GPS1_TX")
	)
	(segment
		(start 93.561995 53.8462)
		(end 95.035195 52.373)
		(width 0.2032)
		(layer "In3.Cu")
		(net "GPS1_TX")
	)
	(segment
		(start 118.488595 92.30211)
		(end 118.488595 76.78648)
		(width 0.2032)
		(layer "In3.Cu")
		(net "GPS1_TX")
	)
	(segment
		(start 151.235745 115.05995)
		(end 154.014245 115.05995)
		(width 0.2032)
		(layer "F.Cu")
		(net "GPS1_TP1")
	)
	(segment
		(start 82.888595 142.4286)
		(end 82.888595 142.3286)
		(width 0.2032)
		(layer "F.Cu")
		(net "GPS1_TP1")
	)
	(segment
		(start 82.888595 142.4286)
		(end 83.588585 143.1286)
		(width 0.2032)
		(layer "F.Cu")
		(net "GPS1_TP1")
	)
	(segment
		(start 117.666595 72.0646)
		(end 117.761595 72.1596)
		(width 0.2032)
		(layer "F.Cu")
		(net "GPS1_TP1")
	)
	(segment
		(start 117.761595 72.1596)
		(end 119.190595 72.1596)
		(width 0.2032)
		(layer "F.Cu")
		(net "GPS1_TP1")
	)
	(segment
		(start 83.588585 143.1286)
		(end 83.638595 143.1286)
		(width 0.2032)
		(layer "F.Cu")
		(net "GPS1_TP1")
	)
	(segment
		(start 155.131595 113.9426)
		(end 155.131595 113.841)
		(width 0.2032)
		(layer "F.Cu")
		(net "GPS1_TP1")
	)
	(segment
		(start 119.138595 85.4286)
		(end 119.190595 85.3766)
		(width 0.2032)
		(layer "F.Cu")
		(net "GPS1_TP1")
	)
	(segment
		(start 119.190595 85.3766)
		(end 119.190595 72.1596)
		(width 0.2032)
		(layer "F.Cu")
		(net "GPS1_TP1")
	)
	(segment
		(start 154.014245 115.05995)
		(end 155.131595 113.9426)
		(width 0.2032)
		(layer "F.Cu")
		(net "GPS1_TP1")
	)
	(via
		(at 83.638595 143.1286)
		(size 0.4064)
		(drill 0.2032)
		(layers "F.Cu" "B.Cu")
		(net "GPS1_TP1")
	)
	(via
		(at 119.063595 111.2756)
		(size 0.4064)
		(drill 0.2032)
		(layers "F.Cu" "B.Cu")
		(net "GPS1_TP1")
	)
	(via
		(at 93.888595 114.4286)
		(size 0.4064)
		(drill 0.2032)
		(layers "F.Cu" "B.Cu")
		(net "GPS1_TP1")
	)
	(via
		(at 119.190595 72.1596)
		(size 0.4064)
		(drill 0.2032)
		(layers "F.Cu" "B.Cu")
		(net "GPS1_TP1")
	)
	(via
		(at 155.131595 113.841)
		(size 0.4064)
		(drill 0.2032)
		(layers "F.Cu" "B.Cu")
		(net "GPS1_TP1")
	)
	(segment
		(start 97.041595 111.2756)
		(end 119.063595 111.2756)
		(width 0.2032)
		(layer "In2.Cu")
		(net "GPS1_TP1")
	)
	(segment
		(start 143.124615 111.2756)
		(end 143.759615 111.9106)
		(width 0.2032)
		(layer "In2.Cu")
		(net "GPS1_TP1")
	)
	(segment
		(start 119.063595 111.2756)
		(end 143.124615 111.2756)
		(width 0.2032)
		(layer "In2.Cu")
		(net "GPS1_TP1")
	)
	(segment
		(start 149.161095 111.9106)
		(end 149.643695 112.3932)
		(width 0.2032)
		(layer "In2.Cu")
		(net "GPS1_TP1")
	)
	(segment
		(start 153.683795 112.3932)
		(end 155.131595 113.841)
		(width 0.2032)
		(layer "In2.Cu")
		(net "GPS1_TP1")
	)
	(segment
		(start 143.759615 111.9106)
		(end 149.161095 111.9106)
		(width 0.2032)
		(layer "In2.Cu")
		(net "GPS1_TP1")
	)
	(segment
		(start 149.643695 112.3932)
		(end 153.683795 112.3932)
		(width 0.2032)
		(layer "In2.Cu")
		(net "GPS1_TP1")
	)
	(segment
		(start 93.888595 114.4286)
		(end 97.041595 111.2756)
		(width 0.2032)
		(layer "In2.Cu")
		(net "GPS1_TP1")
	)
	(segment
		(start 93.113595 139.4286)
		(end 93.113595 115.2036)
		(width 0.2032)
		(layer "In3.Cu")
		(net "GPS1_TP1")
	)
	(segment
		(start 117.963595 98.42262)
		(end 119.190595 99.64962)
		(width 0.2032)
		(layer "In3.Cu")
		(net "GPS1_TP1")
	)
	(segment
		(start 93.113595 115.2036)
		(end 93.888595 114.4286)
		(width 0.2032)
		(layer "In3.Cu")
		(net "GPS1_TP1")
	)
	(segment
		(start 119.063595 111.22061)
		(end 119.190595 111.09361)
		(width 0.2032)
		(layer "In3.Cu")
		(net "GPS1_TP1")
	)
	(segment
		(start 119.063595 111.2756)
		(end 119.063595 111.22061)
		(width 0.2032)
		(layer "In3.Cu")
		(net "GPS1_TP1")
	)
	(segment
		(start 119.190595 111.09361)
		(end 119.190595 99.64962)
		(width 0.2032)
		(layer "In3.Cu")
		(net "GPS1_TP1")
	)
	(segment
		(start 117.963595 73.44159)
		(end 119.190595 72.21459)
		(width 0.2032)
		(layer "In3.Cu")
		(net "GPS1_TP1")
	)
	(segment
		(start 117.963595 98.42262)
		(end 117.963595 73.44159)
		(width 0.2032)
		(layer "In3.Cu")
		(net "GPS1_TP1")
	)
	(segment
		(start 89.413595 143.1286)
		(end 93.113595 139.4286)
		(width 0.2032)
		(layer "In3.Cu")
		(net "GPS1_TP1")
	)
	(segment
		(start 119.190595 72.21459)
		(end 119.190595 72.1596)
		(width 0.2032)
		(layer "In3.Cu")
		(net "GPS1_TP1")
	)
	(segment
		(start 83.638595 143.1286)
		(end 89.413595 143.1286)
		(width 0.2032)
		(layer "In3.Cu")
		(net "GPS1_TP1")
	)
	(segment
		(start 122.111595 72.0646)
		(end 123.984595 72.0646)
		(width 0.2032)
		(layer "F.Cu")
		(net "GPS1_RX")
	)
	(segment
		(start 134.198185 100.66475)
		(end 134.198185 99.71479)
		(width 0.2032)
		(layer "F.Cu")
		(net "GPS1_RX")
	)
	(segment
		(start 133.389195 98.9058)
		(end 133.389195 98.79404)
		(width 0.2032)
		(layer "F.Cu")
		(net "GPS1_RX")
	)
	(segment
		(start 123.984595 72.0646)
		(end 124.016595 72.0326)
		(width 0.2032)
		(layer "F.Cu")
		(net "GPS1_RX")
	)
	(segment
		(start 133.374935 98.18444)
		(end 133.389135 98.78927)
		(width 0.2032)
		(layer "F.Cu")
		(net "GPS1_RX")
	)
	(segment
		(start 133.389195 98.9058)
		(end 134.198185 99.71479)
		(width 0.2032)
		(layer "F.Cu")
		(net "GPS1_RX")
	)
	(via
		(at 124.016595 72.0326)
		(size 0.4064)
		(drill 0.2032)
		(layers "F.Cu" "B.Cu")
		(net "GPS1_RX")
	)
	(via
		(at 122.644995 98.0168)
		(size 0.4064)
		(drill 0.2032)
		(layers "F.Cu" "B.Cu")
		(net "GPS1_RX")
	)
	(via
		(at 133.374935 98.18444)
		(size 0.4064)
		(drill 0.2032)
		(layers "F.Cu" "B.Cu")
		(net "GPS1_RX")
	)
	(arc
		(start 133.389139 98.789272)
		(mid 133.389181 98.791656)
		(end 133.389195 98.79404)
		(width 0.2032)
		(layer "F.Cu")
		(net "GPS1_RX")
	)
	(segment
		(start 132.814235 97.61964)
		(end 133.374935 98.18444)
		(width 0.2032)
		(layer "In2.Cu")
		(net "GPS1_RX")
	)
	(segment
		(start 132.670025 97.5596)
		(end 132.670025 97.5596)
		(width 0.2032)
		(layer "In2.Cu")
		(net "GPS1_RX")
	)
	(segment
		(start 122.644995 98.0168)
		(end 124.491975 98.0168)
		(width 0.2032)
		(layer "In2.Cu")
		(net "GPS1_RX")
	)
	(segment
		(start 124.949175 97.5596)
		(end 132.670025 97.5596)
		(width 0.2032)
		(layer "In2.Cu")
		(net "GPS1_RX")
	)
	(segment
		(start 124.491975 98.0168)
		(end 124.949175 97.5596)
		(width 0.2032)
		(layer "In2.Cu")
		(net "GPS1_RX")
	)
	(arc
		(start 132.670028 97.5596)
		(mid 132.748133 97.575211)
		(end 132.814239 97.619643)
		(width 0.2032)
		(layer "In2.Cu")
		(net "GPS1_RX")
	)
	(segment
		(start 122.695795 76.8858)
		(end 126.238595 80.4286)
		(width 0.2032)
		(layer "In3.Cu")
		(net "GPS1_RX")
	)
	(segment
		(start 113.438595 52.4286)
		(end 116.763595 55.7536)
		(width 0.2032)
		(layer "In3.Cu")
		(net "GPS1_RX")
	)
	(segment
		(start 122.695795 73.3534)
		(end 124.016595 72.0326)
		(width 0.2032)
		(layer "In3.Cu")
		(net "GPS1_RX")
	)
	(segment
		(start 124.016595 68.88975)
		(end 124.016595 68.89077)
		(width 0.2032)
		(layer "In3.Cu")
		(net "GPS1_RX")
	)
	(segment
		(start 122.695795 76.8858)
		(end 122.695795 73.3534)
		(width 0.2032)
		(layer "In3.Cu")
		(net "GPS1_RX")
	)
	(segment
		(start 122.644995 98.0168)
		(end 122.644995 94.20637)
		(width 0.2032)
		(layer "In3.Cu")
		(net "GPS1_RX")
	)
	(segment
		(start 110.388595 52.4286)
		(end 113.438595 52.4286)
		(width 0.2032)
		(layer "In3.Cu")
		(net "GPS1_RX")
	)
	(segment
		(start 116.823115 61.61312)
		(end 123.956375 68.74639)
		(width 0.2032)
		(layer "In3.Cu")
		(net "GPS1_RX")
	)
	(segment
		(start 122.704505 94.06268)
		(end 126.179085 90.58812)
		(width 0.2032)
		(layer "In3.Cu")
		(net "GPS1_RX")
	)
	(segment
		(start 126.238595 90.44443)
		(end 126.238595 80.4286)
		(width 0.2032)
		(layer "In3.Cu")
		(net "GPS1_RX")
	)
	(segment
		(start 122.644995 94.20637)
		(end 122.644995 94.20637)
		(width 0.2032)
		(layer "In3.Cu")
		(net "GPS1_RX")
	)
	(segment
		(start 116.763595 61.46943)
		(end 116.763595 55.7536)
		(width 0.2032)
		(layer "In3.Cu")
		(net "GPS1_RX")
	)
	(segment
		(start 124.016595 72.0326)
		(end 124.016595 68.89077)
		(width 0.2032)
		(layer "In3.Cu")
		(net "GPS1_RX")
	)
	(arc
		(start 123.956377 68.746383)
		(mid 124.000741 68.812081)
		(end 124.016592 68.889754)
		(width 0.2032)
		(layer "In3.Cu")
		(net "GPS1_RX")
	)
	(arc
		(start 116.823113 61.613117)
		(mid 116.779063 61.547193)
		(end 116.763594 61.46943)
		(width 0.2032)
		(layer "In3.Cu")
		(net "GPS1_RX")
	)
	(arc
		(start 122.644995 94.20637)
		(mid 122.660462 94.128609)
		(end 122.70451 94.062687)
		(width 0.2032)
		(layer "In3.Cu")
		(net "GPS1_RX")
	)
	(arc
		(start 126.238595 90.44443)
		(mid 126.223127 90.522192)
		(end 126.179078 90.588115)
		(width 0.2032)
		(layer "In3.Cu")
		(net "GPS1_RX")
	)
	(segment
		(start 118.174595 156.99168)
		(end 118.174595 152.2186)
		(width 0.127)
		(layer "B.Cu")
		(net "NetC44_1")
	)
	(segment
		(start 118.158595 157.7576)
		(end 118.174595 157.7416)
		(width 0.2032)
		(layer "B.Cu")
		(net "NetC44_1")
	)
	(arc
		(start 118.158585 152.25723)
		(mid 118.162744 152.236321)
		(end 118.174588 152.218594)
		(width 0.127)
		(layer "B.Cu")
		(net "NetC44_1")
	)
	(arc
		(start 118.174595 156.99168)
		(mid 118.165238 157.038719)
		(end 118.138593 157.078598)
		(width 0.127)
		(layer "B.Cu")
		(net "NetC44_1")
	)
	(segment
		(start 119.190595 156.95305)
		(end 119.190595 152.2186)
		(width 0.127)
		(layer "B.Cu")
		(net "NetC45_1")
	)
	(arc
		(start 119.190595 156.95305)
		(mid 119.17708 157.020995)
		(end 119.138592 157.078597)
		(width 0.127)
		(layer "B.Cu")
		(net "NetC45_1")
	)
	(segment
		(start 121.197195 156.93711)
		(end 121.197195 152.2186)
		(width 0.127)
		(layer "B.Cu")
		(net "NetC46_1")
	)
	(arc
		(start 121.197195 157.66439)
		(mid 121.187182 157.714783)
		(end 121.158666 157.757521)
		(width 0.127)
		(layer "B.Cu")
		(net "NetC46_1")
	)
	(arc
		(start 121.197195 156.93711)
		(mid 121.181963 157.013685)
		(end 121.138587 157.078602)
		(width 0.127)
		(layer "B.Cu")
		(net "NetC46_1")
	)
	(segment
		(start 122.289395 156.71451)
		(end 122.289395 152.2186)
		(width 0.127)
		(layer "B.Cu")
		(net "NetC47_1")
	)
	(arc
		(start 122.289395 156.71451)
		(mid 122.250201 156.911554)
		(end 122.138584 157.078599)
		(width 0.127)
		(layer "B.Cu")
		(net "NetC47_1")
	)
	(segment
		(start 126.175595 156.98923)
		(end 126.175595 152.2186)
		(width 0.127)
		(layer "B.Cu")
		(net "NetC48_1")
	)
	(arc
		(start 126.175595 156.98923)
		(mid 126.165974 157.037597)
		(end 126.138576 157.078601)
		(width 0.127)
		(layer "B.Cu")
		(net "NetC48_1")
	)
	(arc
		(start 126.175595 157.71651)
		(mid 126.171172 157.738744)
		(end 126.158578 157.757593)
		(width 0.127)
		(layer "B.Cu")
		(net "NetC48_1")
	)
	(segment
		(start 130.112595 157.01589)
		(end 130.112595 152.2186)
		(width 0.127)
		(layer "B.Cu")
		(net "NetC50_1")
	)
	(arc
		(start 130.112592 152.218603)
		(mid 130.146617 152.269524)
		(end 130.158564 152.32959)
		(width 0.127)
		(layer "B.Cu")
		(net "NetC50_1")
	)
	(arc
		(start 130.138569 157.078596)
		(mid 130.119346 157.049826)
		(end 130.112595 157.01589)
		(width 0.127)
		(layer "B.Cu")
		(net "NetC50_1")
	)
	(segment
		(start 131.001595 156.74792)
		(end 131.001595 152.2186)
		(width 0.127)
		(layer "B.Cu")
		(net "NetC51_1")
	)
	(arc
		(start 131.158095 157.757133)
		(mid 131.042263 157.583426)
		(end 131.001595 157.37864)
		(width 0.127)
		(layer "B.Cu")
		(net "NetC51_1")
	)
	(arc
		(start 131.138567 157.078598)
		(mid 131.037193 156.926882)
		(end 131.001596 156.74792)
		(width 0.127)
		(layer "B.Cu")
		(net "NetC51_1")
	)
	(segment
		(start 134.176595 156.98678)
		(end 134.176595 152.2186)
		(width 0.127)
		(layer "B.Cu")
		(net "NetC52_1")
	)
	(arc
		(start 134.176605 156.98678)
		(mid 134.16672 157.036475)
		(end 134.13857 157.078605)
		(width 0.127)
		(layer "B.Cu")
		(net "NetC52_1")
	)
	(arc
		(start 134.158565 152.26214)
		(mid 134.163252 152.238578)
		(end 134.176598 152.218603)
		(width 0.127)
		(layer "B.Cu")
		(net "NetC52_1")
	)
	(arc
		(start 134.176595 157.71406)
		(mid 134.171908 157.737622)
		(end 134.158562 157.757597)
		(width 0.127)
		(layer "B.Cu")
		(net "NetC52_1")
	)
	(segment
		(start 135.158555 157.7576)
		(end 135.192595 157.72356)
		(width 0.2032)
		(layer "B.Cu")
		(net "NetC53_1")
	)
	(segment
		(start 135.192595 156.94814)
		(end 135.192595 152.2186)
		(width 0.127)
		(layer "B.Cu")
		(net "NetC53_1")
	)
	(arc
		(start 135.158555 152.30077)
		(mid 135.167401 152.256298)
		(end 135.192592 152.218597)
		(width 0.127)
		(layer "B.Cu")
		(net "NetC53_1")
	)
	(arc
		(start 135.192595 156.94814)
		(mid 135.178552 157.018741)
		(end 135.138559 157.078594)
		(width 0.127)
		(layer "B.Cu")
		(net "NetC53_1")
	)
	(segment
		(start 164.562215 89.711)
		(end 164.859795 89.41342)
		(width 0.508)
		(layer "F.Cu")
		(net "NetC72_2")
	)
	(segment
		(start 165.732595 88.4716)
		(end 166.053595 88.1506)
		(width 0.508)
		(layer "F.Cu")
		(net "NetC72_2")
	)
	(segment
		(start 164.859795 89.41342)
		(end 164.859795 88.949)
		(width 0.508)
		(layer "F.Cu")
		(net "NetC72_2")
	)
	(segment
		(start 166.053595 88.1506)
		(end 168.720595 88.1506)
		(width 0.508)
		(layer "F.Cu")
		(net "NetC72_2")
	)
	(segment
		(start 164.859795 88.949)
		(end 165.337195 88.4716)
		(width 0.508)
		(layer "F.Cu")
		(net "NetC72_2")
	)
	(segment
		(start 163.899195 89.711)
		(end 164.562215 89.711)
		(width 0.508)
		(layer "F.Cu")
		(net "NetC72_2")
	)
	(segment
		(start 165.337195 88.4716)
		(end 165.732595 88.4716)
		(width 0.508)
		(layer "F.Cu")
		(net "NetC72_2")
	)
	(segment
		(start 163.894595 89.7156)
		(end 163.899195 89.711)
		(width 0.508)
		(layer "F.Cu")
		(net "NetC72_2")
	)
	(segment
		(start 168.720595 88.1506)
		(end 170.041395 88.1506)
		(width 0.508)
		(layer "F.Cu")
		(net "NetC72_2")
	)
	(segment
		(start 170.276395 88.3856)
		(end 171.133595 88.3856)
		(width 0.508)
		(layer "F.Cu")
		(net "NetC72_2")
	)
	(segment
		(start 170.041395 88.1506)
		(end 170.276395 88.3856)
		(width 0.508)
		(layer "F.Cu")
		(net "NetC72_2")
	)
	(segment
		(start 226.233595 79.5056)
		(end 226.251595 79.4876)
		(width 0.2032)
		(layer "F.Cu")
		(net "NetC85_2")
	)
	(segment
		(start 228.795195 79.4876)
		(end 229.343595 80.036)
		(width 0.2032)
		(layer "F.Cu")
		(net "NetC85_2")
	)
	(segment
		(start 226.251595 79.4876)
		(end 228.795195 79.4876)
		(width 0.2032)
		(layer "F.Cu")
		(net "NetC85_2")
	)
	(segment
		(start 223.877095 79.5056)
		(end 226.233595 79.5056)
		(width 0.2032)
		(layer "F.Cu")
		(net "NetC85_2")
	)
	(segment
		(start 229.343595 80.1096)
		(end 229.343595 80.036)
		(width 0.2032)
		(layer "F.Cu")
		(net "NetC85_2")
	)
	(segment
		(start 228.795195 77.6586)
		(end 229.343595 77.1102)
		(width 0.2032)
		(layer "F.Cu")
		(net "NetC86_2")
	)
	(segment
		(start 224.929595 79.0056)
		(end 226.251595 77.6836)
		(width 0.2032)
		(layer "F.Cu")
		(net "NetC86_2")
	)
	(segment
		(start 226.251595 77.6836)
		(end 226.251595 77.6586)
		(width 0.2032)
		(layer "F.Cu")
		(net "NetC86_2")
	)
	(segment
		(start 226.251595 77.6586)
		(end 228.795195 77.6586)
		(width 0.2032)
		(layer "F.Cu")
		(net "NetC86_2")
	)
	(segment
		(start 223.877095 79.0056)
		(end 224.929595 79.0056)
		(width 0.2032)
		(layer "F.Cu")
		(net "NetC86_2")
	)
	(segment
		(start 229.343595 77.1102)
		(end 229.343595 76.9096)
		(width 0.2032)
		(layer "F.Cu")
		(net "NetC86_2")
	)
	(segment
		(start 74.867595 56.4614)
		(end 74.867595 53.9616)
		(width 0.2032)
		(layer "F.Cu")
		(net "NetD11_1")
	)
	(segment
		(start 74.718395 56.6106)
		(end 74.867595 56.4614)
		(width 0.2032)
		(layer "F.Cu")
		(net "NetD11_1")
	)
	(segment
		(start 79.989925 56.4614)
		(end 79.989925 54.0886)
		(width 0.2032)
		(layer "F.Cu")
		(net "NetD12_1")
	)
	(segment
		(start 79.840725 56.6106)
		(end 79.989925 56.4614)
		(width 0.2032)
		(layer "F.Cu")
		(net "NetD12_1")
	)
	(segment
		(start 122.188595 153.6786)
		(end 122.988595 152.8786)
		(width 0.2032)
		(layer "F.Cu")
		(net "NetP2_B17")
	)
	(segment
		(start 122.088595 148.7786)
		(end 122.988595 149.6786)
		(width 0.2032)
		(layer "F.Cu")
		(net "NetP2_B17")
	)
	(segment
		(start 122.188595 157.02859)
		(end 122.188595 153.6786)
		(width 0.2032)
		(layer "F.Cu")
		(net "NetP2_B17")
	)
	(segment
		(start 122.088595 148.7786)
		(end 122.088595 146.0036)
		(width 0.2032)
		(layer "F.Cu")
		(net "NetP2_B17")
	)
	(segment
		(start 122.138585 157.0786)
		(end 122.188595 157.02859)
		(width 0.2032)
		(layer "F.Cu")
		(net "NetP2_B17")
	)
	(segment
		(start 122.988595 152.8786)
		(end 122.988595 149.6786)
		(width 0.2032)
		(layer "F.Cu")
		(net "NetP2_B17")
	)
	(segment
		(start 136.088595 156.53334)
		(end 136.088595 146.0036)
		(width 0.2032)
		(layer "F.Cu")
		(net "NetP2_B31")
	)
	(segment
		(start 136.038555 146.05364)
		(end 136.088595 146.0036)
		(width 0.2032)
		(layer "F.Cu")
		(net "NetP2_B31")
	)
	(segment
		(start 136.088595 156.53334)
		(end 136.138555 156.5833)
		(width 0.2032)
		(layer "F.Cu")
		(net "NetP2_B31")
	)
	(segment
		(start 136.158555 157.2623)
		(end 136.208595 157.21226)
		(width 0.2032)
		(layer "F.Cu")
		(net "NetP2_B31")
	)
	(segment
		(start 216.853595 105.1246)
		(end 216.853595 103.6526)
		(width 0.2032)
		(layer "F.Cu")
		(net "NetR3_1")
	)
	(segment
		(start 215.586595 102.3856)
		(end 216.853595 103.6526)
		(width 0.2032)
		(layer "F.Cu")
		(net "NetR3_1")
	)
	(segment
		(start 214.886595 102.3856)
		(end 215.586595 102.3856)
		(width 0.2032)
		(layer "F.Cu")
		(net "NetR3_1")
	)
	(segment
		(start 231.328595 112.7996)
		(end 232.028595 112.7996)
		(width 0.2032)
		(layer "F.Cu")
		(net "NetR4_2")
	)
	(segment
		(start 231.328595 112.7996)
		(end 232.028595 112.7996)
		(width 0.2032)
		(layer "F.Cu")
		(net "NetR4_2")
	)
	(segment
		(start 232.028595 112.7996)
		(end 233.259595 112.7996)
		(width 0.2032)
		(layer "F.Cu")
		(net "NetR4_2")
	)
	(segment
		(start 230.751595 112.9656)
		(end 230.917595 112.7996)
		(width 0.2032)
		(layer "F.Cu")
		(net "NetR4_2")
	)
	(segment
		(start 233.259595 112.7996)
		(end 233.672595 113.2126)
		(width 0.2032)
		(layer "F.Cu")
		(net "NetR4_2")
	)
	(segment
		(start 233.672595 114.4506)
		(end 233.672595 113.2126)
		(width 0.2032)
		(layer "F.Cu")
		(net "NetR4_2")
	)
	(segment
		(start 230.917595 112.7996)
		(end 231.328595 112.7996)
		(width 0.2032)
		(layer "F.Cu")
		(net "NetR4_2")
	)
	(segment
		(start 230.751595 112.9656)
		(end 230.751595 114.4506)
		(width 0.2032)
		(layer "F.Cu")
		(net "NetR4_2")
	)
	(segment
		(start 214.626025 99.6622)
		(end 214.809425 99.8456)
		(width 0.2032)
		(layer "F.Cu")
		(net "NetR5_1")
	)
	(segment
		(start 215.586595 99.8456)
		(end 217.110595 98.3216)
		(width 0.2032)
		(layer "F.Cu")
		(net "NetR5_1")
	)
	(segment
		(start 214.886595 99.8456)
		(end 215.586595 99.8456)
		(width 0.2032)
		(layer "F.Cu")
		(net "NetR5_1")
	)
	(segment
		(start 214.626025 99.6622)
		(end 214.626025 99.37483)
		(width 0.2032)
		(layer "F.Cu")
		(net "NetR5_1")
	)
	(segment
		(start 214.008795 98.7576)
		(end 214.148795 98.7576)
		(width 0.2032)
		(layer "F.Cu")
		(net "NetR5_1")
	)
	(segment
		(start 214.407195 99.156)
		(end 214.407195 99.016)
		(width 0.2032)
		(layer "F.Cu")
		(net "NetR5_1")
	)
	(segment
		(start 217.110595 98.3216)
		(end 218.830595 98.3216)
		(width 0.2032)
		(layer "F.Cu")
		(net "NetR5_1")
	)
	(segment
		(start 214.809425 99.8456)
		(end 214.886595 99.8456)
		(width 0.2032)
		(layer "F.Cu")
		(net "NetR5_1")
	)
	(segment
		(start 214.407195 99.156)
		(end 214.626025 99.37483)
		(width 0.2032)
		(layer "F.Cu")
		(net "NetR5_1")
	)
	(segment
		(start 214.148795 98.7576)
		(end 214.407195 99.016)
		(width 0.2032)
		(layer "F.Cu")
		(net "NetR5_1")
	)
	(segment
		(start 133.287595 65.4446)
		(end 133.287595 60.2216)
		(width 0.2032)
		(layer "F.Cu")
		(net "NetR18_2")
	)
	(segment
		(start 138.367595 65.4446)
		(end 138.367595 60.2216)
		(width 0.2032)
		(layer "F.Cu")
		(net "NetR20_2")
	)
	(segment
		(start 143.574595 65.4446)
		(end 143.574595 60.3486)
		(width 0.2032)
		(layer "F.Cu")
		(net "NetR21_2")
	)
	(segment
		(start 143.447595 60.2216)
		(end 143.574595 60.3486)
		(width 0.2032)
		(layer "F.Cu")
		(net "NetR21_2")
	)
	(segment
		(start 159.761595 65.7461)
		(end 162.265095 65.7461)
		(width 0.2032)
		(layer "F.Cu")
		(net "NetR27_2")
	)
	(segment
		(start 162.265095 65.7461)
		(end 162.950595 66.4316)
		(width 0.2032)
		(layer "F.Cu")
		(net "NetR27_2")
	)
	(segment
		(start 162.950595 66.5716)
		(end 162.950595 66.4316)
		(width 0.2032)
		(layer "F.Cu")
		(net "NetR27_2")
	)
	(segment
		(start 189.538595 55.0786)
		(end 189.568595 55.0486)
		(width 0.508)
		(layer "F.Cu")
		(net "NetR34_1")
	)
	(segment
		(start 187.819595 53.7446)
		(end 187.885595 53.6786)
		(width 0.508)
		(layer "F.Cu")
		(net "NetR34_1")
	)
	(segment
		(start 189.568595 53.7086)
		(end 189.598595 53.6786)
		(width 0.508)
		(layer "F.Cu")
		(net "NetR34_1")
	)
	(segment
		(start 189.568595 55.0486)
		(end 189.568595 53.7086)
		(width 0.508)
		(layer "F.Cu")
		(net "NetR34_1")
	)
	(segment
		(start 187.885595 53.6786)
		(end 189.598595 53.6786)
		(width 0.508)
		(layer "F.Cu")
		(net "NetR34_1")
	)
	(segment
		(start 174.518595 53.7786)
		(end 176.298595 53.7786)
		(width 0.508)
		(layer "F.Cu")
		(net "NetR33_1")
	)
	(segment
		(start 176.298595 55.1786)
		(end 176.298595 55.1786)
		(width 0.508)
		(layer "F.Cu")
		(net "NetR33_1")
	)
	(segment
		(start 176.298595 55.1786)
		(end 176.298595 53.7786)
		(width 0.508)
		(layer "F.Cu")
		(net "NetR33_1")
	)
	(segment
		(start 174.484595 53.7446)
		(end 174.518595 53.7786)
		(width 0.508)
		(layer "F.Cu")
		(net "NetR33_1")
	)
	(segment
		(start 147.003595 89.3512)
		(end 147.003595 87.1132)
		(width 0.254)
		(layer "F.Cu")
		(net "NetR42_1")
	)
	(segment
		(start 146.821595 89.5332)
		(end 147.003595 89.3512)
		(width 0.254)
		(layer "F.Cu")
		(net "NetR42_1")
	)
	(segment
		(start 107.599695 57.0847)
		(end 107.608195 57.0762)
		(width 0.2032)
		(layer "F.Cu")
		(net "NetR43_2")
	)
	(segment
		(start 105.380195 57.0847)
		(end 107.599695 57.0847)
		(width 0.2032)
		(layer "F.Cu")
		(net "NetR43_2")
	)
	(segment
		(start 154.311595 63.8411)
		(end 155.703095 63.8411)
		(width 0.2032)
		(layer "F.Cu")
		(net "NetU6_3")
	)
	(segment
		(start 161.454595 68.086)
		(end 161.454595 67.0443)
		(width 0.2032)
		(layer "F.Cu")
		(net "NetU6_3")
	)
	(segment
		(start 160.791395 66.3811)
		(end 161.454595 67.0443)
		(width 0.2032)
		(layer "F.Cu")
		(net "NetU6_3")
	)
	(segment
		(start 159.761595 66.3811)
		(end 160.791395 66.3811)
		(width 0.2032)
		(layer "F.Cu")
		(net "NetU6_3")
	)
	(segment
		(start 155.703095 63.8411)
		(end 155.766595 63.9046)
		(width 0.2032)
		(layer "F.Cu")
		(net "NetU6_3")
	)
	(via
		(at 161.454595 68.086)
		(size 0.4064)
		(drill 0.2032)
		(layers "F.Cu" "B.Cu")
		(net "NetU6_3")
	)
	(via
		(at 155.766595 63.9046)
		(size 0.4064)
		(drill 0.2032)
		(layers "F.Cu" "B.Cu")
		(net "NetU6_3")
	)
	(segment
		(start 161.454595 68.086)
		(end 161.454595 66.6716)
		(width 0.2032)
		(layer "B.Cu")
		(net "NetU6_3")
	)
	(segment
		(start 158.687595 63.9046)
		(end 161.454595 66.6716)
		(width 0.2032)
		(layer "B.Cu")
		(net "NetU6_3")
	)
	(segment
		(start 155.766595 63.9046)
		(end 158.687595 63.9046)
		(width 0.2032)
		(layer "B.Cu")
		(net "NetU6_3")
	)
	(segment
		(start 99.977415 55.22692)
		(end 101.064115 55.22692)
		(width 0.2032)
		(layer "F.Cu")
		(net "NetU16_3")
	)
	(segment
		(start 99.930195 55.1797)
		(end 99.977415 55.22692)
		(width 0.2032)
		(layer "F.Cu")
		(net "NetU16_3")
	)
	(segment
		(start 103.556895 57.7197)
		(end 105.380195 57.7197)
		(width 0.2032)
		(layer "F.Cu")
		(net "NetU16_3")
	)
	(segment
		(start 101.064115 55.22692)
		(end 103.556895 57.7197)
		(width 0.2032)
		(layer "F.Cu")
		(net "NetU16_3")
	)
	(segment
		(start 98.985275 53.95692)
		(end 99.882975 53.95692)
		(width 0.2032)
		(layer "F.Cu")
		(net "NetJP2_2")
	)
	(segment
		(start 98.363595 54.6286)
		(end 98.363595 54.5786)
		(width 0.2032)
		(layer "F.Cu")
		(net "NetJP2_2")
	)
	(segment
		(start 99.882975 53.95692)
		(end 99.930195 53.9097)
		(width 0.2032)
		(layer "F.Cu")
		(net "NetJP2_2")
	)
	(segment
		(start 98.363595 54.5786)
		(end 98.985275 53.95692)
		(width 0.2032)
		(layer "F.Cu")
		(net "NetJP2_2")
	)
	(segment
		(start 98.363595 54.6286)
		(end 98.363595 54.6286)
		(width 0.2032)
		(layer "F.Cu")
		(net "NetJP2_2")
	)
	(via
		(at 98.363595 54.6286)
		(size 0.4064)
		(drill 0.2032)
		(layers "F.Cu" "B.Cu")
		(net "NetJP2_2")
	)
	(segment
		(start 109.348685 55.1162)
		(end 110.388595 55.1162)
		(width 0.2032)
		(layer "In2.Cu")
		(net "NetJP2_2")
	)
	(segment
		(start 99.257595 55.5226)
		(end 108.942285 55.5226)
		(width 0.2032)
		(layer "In2.Cu")
		(net "NetJP2_2")
	)
	(segment
		(start 98.363595 54.6286)
		(end 99.257595 55.5226)
		(width 0.2032)
		(layer "In2.Cu")
		(net "NetJP2_2")
	)
	(segment
		(start 108.942285 55.5226)
		(end 109.348685 55.1162)
		(width 0.2032)
		(layer "In2.Cu")
		(net "NetJP2_2")
	)
	(segment
		(start 96.259695 55.8147)
		(end 99.930195 55.8147)
		(width 0.2032)
		(layer "F.Cu")
		(net "NetJP1_2")
	)
	(segment
		(start 95.513595 55.0686)
		(end 96.259695 55.8147)
		(width 0.2032)
		(layer "F.Cu")
		(net "NetJP1_2")
	)
	(segment
		(start 100.620375 58.4781)
		(end 100.632295 58.4781)
		(width 0.2032)
		(layer "F.Cu")
		(net "NetJ4_3")
	)
	(segment
		(start 100.496975 58.3547)
		(end 100.620375 58.4781)
		(width 0.2032)
		(layer "F.Cu")
		(net "NetJ4_3")
	)
	(segment
		(start 117.735795 57.6814)
		(end 117.735795 54.652)
		(width 0.2032)
		(layer "F.Cu")
		(net "NetJ4_3")
	)
	(segment
		(start 99.930195 58.3547)
		(end 100.496975 58.3547)
		(width 0.2032)
		(layer "F.Cu")
		(net "NetJ4_3")
	)
	(segment
		(start 115.513595 59.9036)
		(end 117.735795 57.6814)
		(width 0.2032)
		(layer "F.Cu")
		(net "NetJ4_3")
	)
	(segment
		(start 100.632295 58.4781)
		(end 102.057795 59.9036)
		(width 0.2032)
		(layer "F.Cu")
		(net "NetJ4_3")
	)
	(segment
		(start 102.057795 59.9036)
		(end 115.513595 59.9036)
		(width 0.2032)
		(layer "F.Cu")
		(net "NetJ4_3")
	)
	(segment
		(start 106.579795 58.5198)
		(end 106.846195 58.5198)
		(width 0.2032)
		(layer "F.Cu")
		(net "NetJ4_2")
	)
	(segment
		(start 118.263595 58.5286)
		(end 118.385795 58.4064)
		(width 0.2032)
		(layer "F.Cu")
		(net "NetJ4_2")
	)
	(segment
		(start 118.385795 58.4064)
		(end 118.385795 54.652)
		(width 0.2032)
		(layer "F.Cu")
		(net "NetJ4_2")
	)
	(segment
		(start 105.380195 58.3547)
		(end 106.414695 58.3547)
		(width 0.2032)
		(layer "F.Cu")
		(net "NetJ4_2")
	)
	(segment
		(start 106.414695 58.3547)
		(end 106.579795 58.5198)
		(width 0.2032)
		(layer "F.Cu")
		(net "NetJ4_2")
	)
	(via
		(at 106.846195 58.5198)
		(size 0.4064)
		(drill 0.2032)
		(layers "F.Cu" "B.Cu")
		(net "NetJ4_2")
	)
	(via
		(at 118.263595 58.5286)
		(size 0.4064)
		(drill 0.2032)
		(layers "F.Cu" "B.Cu")
		(net "NetJ4_2")
	)
	(segment
		(start 106.854995 58.5286)
		(end 118.263595 58.5286)
		(width 0.2032)
		(layer "In2.Cu")
		(net "NetJ4_2")
	)
	(segment
		(start 106.846195 58.5198)
		(end 106.854995 58.5286)
		(width 0.2032)
		(layer "In2.Cu")
		(net "NetJ4_2")
	)
	(segment
		(start 147.649595 74.3406)
		(end 147.864165 74.12603)
		(width 0.2032)
		(layer "F.Cu")
		(net "5721_STATUS")
	)
	(segment
		(start 130.163395 94.5116)
		(end 130.198195 94.5464)
		(width 0.2032)
		(layer "F.Cu")
		(net "5721_STATUS")
	)
	(segment
		(start 149.086395 72.0326)
		(end 150.508795 72.0326)
		(width 0.2032)
		(layer "F.Cu")
		(net "5721_STATUS")
	)
	(segment
		(start 147.864165 73.25483)
		(end 149.086395 72.0326)
		(width 0.2032)
		(layer "F.Cu")
		(net "5721_STATUS")
	)
	(segment
		(start 130.198195 96.61497)
		(end 130.198195 94.5464)
		(width 0.2032)
		(layer "F.Cu")
		(net "5721_STATUS")
	)
	(segment
		(start 147.864165 74.12603)
		(end 147.864165 73.25483)
		(width 0.2032)
		(layer "F.Cu")
		(net "5721_STATUS")
	)
	(via
		(at 130.163395 94.5116)
		(size 0.4064)
		(drill 0.2032)
		(layers "F.Cu" "B.Cu")
		(net "5721_STATUS")
	)
	(via
		(at 150.534195 94.8672)
		(size 0.4064)
		(drill 0.2032)
		(layers "F.Cu" "B.Cu")
		(net "5721_STATUS")
	)
	(via
		(at 150.508795 72.0326)
		(size 0.4064)
		(drill 0.2032)
		(layers "F.Cu" "B.Cu")
		(net "5721_STATUS")
	)
	(segment
		(start 149.079175 94.5116)
		(end 149.206175 94.3846)
		(width 0.2032)
		(layer "In2.Cu")
		(net "5721_STATUS")
	)
	(segment
		(start 130.163395 94.5116)
		(end 149.079175 94.5116)
		(width 0.2032)
		(layer "In2.Cu")
		(net "5721_STATUS")
	)
	(segment
		(start 149.206175 94.3846)
		(end 150.051595 94.3846)
		(width 0.2032)
		(layer "In2.Cu")
		(net "5721_STATUS")
	)
	(segment
		(start 150.051595 94.3846)
		(end 150.534195 94.8672)
		(width 0.2032)
		(layer "In2.Cu")
		(net "5721_STATUS")
	)
	(segment
		(start 150.508795 94.8418)
		(end 150.508795 72.0326)
		(width 0.2032)
		(layer "In3.Cu")
		(net "5721_STATUS")
	)
	(segment
		(start 150.508795 94.8418)
		(end 150.534195 94.8672)
		(width 0.2032)
		(layer "In3.Cu")
		(net "5721_STATUS")
	)
	(segment
		(start 137.513595 78.3536)
		(end 139.063595 78.3536)
		(width 0.2032)
		(layer "F.Cu")
		(net "SDA")
	)
	(segment
		(start 171.188595 67.5786)
		(end 171.188595 67.56018)
		(width 0.2032)
		(layer "F.Cu")
		(net "SDA")
	)
	(segment
		(start 147.003595 83.0632)
		(end 147.003595 81.98143)
		(width 0.2032)
		(layer "F.Cu")
		(net "SDA")
	)
	(segment
		(start 139.063595 78.3536)
		(end 139.913595 77.5036)
		(width 0.2032)
		(layer "F.Cu")
		(net "SDA")
	)
	(segment
		(start 147.003595 81.98143)
		(end 147.181395 81.80363)
		(width 0.2032)
		(layer "F.Cu")
		(net "SDA")
	)
	(segment
		(start 144.682365 75.85797)
		(end 144.682365 74.37336)
		(width 0.2032)
		(layer "F.Cu")
		(net "SDA")
	)
	(segment
		(start 144.649595 74.3406)
		(end 144.682365 74.37336)
		(width 0.2032)
		(layer "F.Cu")
		(net "SDA")
	)
	(segment
		(start 139.784645 89.0552)
		(end 139.978195 89.0552)
		(width 0.2032)
		(layer "F.Cu")
		(net "SDA")
	)
	(segment
		(start 139.913595 77.5036)
		(end 143.038595 77.5036)
		(width 0.2032)
		(layer "F.Cu")
		(net "SDA")
	)
	(segment
		(start 143.038595 77.5036)
		(end 144.613595 75.9286)
		(width 0.2032)
		(layer "F.Cu")
		(net "SDA")
	)
	(segment
		(start 144.682365 75.85797)
		(end 145.657595 76.8332)
		(width 0.2032)
		(layer "F.Cu")
		(net "SDA")
	)
	(segment
		(start 139.559295 88.82985)
		(end 139.784645 89.0552)
		(width 0.2032)
		(layer "F.Cu")
		(net "SDA")
	)
	(segment
		(start 141.063595 84.8036)
		(end 141.063595 83.3036)
		(width 0.2032)
		(layer "F.Cu")
		(net "SDA")
	)
	(segment
		(start 142.563565 81.80363)
		(end 147.083575 81.80363)
		(width 0.2032)
		(layer "F.Cu")
		(net "SDA")
	)
	(segment
		(start 139.978195 89.0552)
		(end 140.001595 89.0786)
		(width 0.2032)
		(layer "F.Cu")
		(net "SDA")
	)
	(segment
		(start 145.657595 76.8332)
		(end 147.181395 76.8332)
		(width 0.2032)
		(layer "F.Cu")
		(net "SDA")
	)
	(segment
		(start 129.698065 100.66475)
		(end 129.706195 100.67288)
		(width 0.2032)
		(layer "F.Cu")
		(net "SDA")
	)
	(segment
		(start 141.063595 83.3036)
		(end 142.563565 81.80363)
		(width 0.2032)
		(layer "F.Cu")
		(net "SDA")
	)
	(segment
		(start 139.559295 88.82985)
		(end 139.559295 86.3079)
		(width 0.2032)
		(layer "F.Cu")
		(net "SDA")
	)
	(segment
		(start 139.559295 86.3079)
		(end 141.063595 84.8036)
		(width 0.2032)
		(layer "F.Cu")
		(net "SDA")
	)
	(segment
		(start 171.188595 67.56018)
		(end 171.538595 67.21018)
		(width 0.2032)
		(layer "F.Cu")
		(net "SDA")
	)
	(segment
		(start 171.538595 67.21018)
		(end 171.538595 64.64481)
		(width 0.2032)
		(layer "F.Cu")
		(net "SDA")
	)
	(segment
		(start 129.706195 101.9792)
		(end 129.706195 100.67288)
		(width 0.2032)
		(layer "F.Cu")
		(net "SDA")
	)
	(via
		(at 171.188595 67.5786)
		(size 0.4064)
		(drill 0.2032)
		(layers "F.Cu" "B.Cu")
		(net "SDA")
	)
	(via
		(at 171.238595 75.37361)
		(size 0.4064)
		(drill 0.2032)
		(layers "F.Cu" "B.Cu")
		(net "SDA")
	)
	(via
		(at 147.181395 81.7608)
		(size 0.4064)
		(drill 0.2032)
		(layers "F.Cu" "B.Cu")
		(net "SDA")
	)
	(via
		(at 129.706195 101.9792)
		(size 0.4064)
		(drill 0.2032)
		(layers "F.Cu" "B.Cu")
		(net "SDA")
	)
	(via
		(at 147.359195 101.1156)
		(size 0.4064)
		(drill 0.2032)
		(layers "F.Cu" "B.Cu")
		(net "SDA")
	)
	(via
		(at 147.181395 76.8332)
		(size 0.4064)
		(drill 0.2032)
		(layers "F.Cu" "B.Cu")
		(net "SDA")
	)
	(segment
		(start 130.569795 101.1156)
		(end 147.359195 101.1156)
		(width 0.2032)
		(layer "In2.Cu")
		(net "SDA")
	)
	(segment
		(start 162.386205 75.37361)
		(end 171.238595 75.37361)
		(width 0.2032)
		(layer "In2.Cu")
		(net "SDA")
	)
	(segment
		(start 152.593795 75.7786)
		(end 153.293795 75.0786)
		(width 0.2032)
		(layer "In2.Cu")
		(net "SDA")
	)
	(segment
		(start 148.235995 75.7786)
		(end 152.593795 75.7786)
		(width 0.2032)
		(layer "In2.Cu")
		(net "SDA")
	)
	(segment
		(start 153.293795 75.0786)
		(end 162.091195 75.0786)
		(width 0.2032)
		(layer "In2.Cu")
		(net "SDA")
	)
	(segment
		(start 162.091195 75.0786)
		(end 162.386205 75.37361)
		(width 0.2032)
		(layer "In2.Cu")
		(net "SDA")
	)
	(segment
		(start 129.706195 101.9792)
		(end 130.569795 101.1156)
		(width 0.2032)
		(layer "In2.Cu")
		(net "SDA")
	)
	(segment
		(start 147.181395 76.8332)
		(end 148.235995 75.7786)
		(width 0.2032)
		(layer "In2.Cu")
		(net "SDA")
	)
	(segment
		(start 147.359195 101.1156)
		(end 147.384595 101.0902)
		(width 0.2032)
		(layer "In3.Cu")
		(net "SDA")
	)
	(segment
		(start 171.188595 74.76401)
		(end 171.188595 67.5786)
		(width 0.2032)
		(layer "In3.Cu")
		(net "SDA")
	)
	(segment
		(start 147.206795 100.7092)
		(end 147.435395 100.9378)
		(width 0.2032)
		(layer "In3.Cu")
		(net "SDA")
	)
	(segment
		(start 147.181395 76.8332)
		(end 147.206795 76.8586)
		(width 0.2032)
		(layer "In3.Cu")
		(net "SDA")
	)
	(segment
		(start 171.238595 75.37361)
		(end 171.238595 74.81401)
		(width 0.2032)
		(layer "In3.Cu")
		(net "SDA")
	)
	(segment
		(start 147.206795 100.7092)
		(end 147.206795 76.8586)
		(width 0.2032)
		(layer "In3.Cu")
		(net "SDA")
	)
	(segment
		(start 147.333795 101.0394)
		(end 147.384595 101.0902)
		(width 0.2032)
		(layer "In3.Cu")
		(net "SDA")
	)
	(segment
		(start 171.188595 74.76401)
		(end 171.238595 74.81401)
		(width 0.2032)
		(layer "In3.Cu")
		(net "SDA")
	)
	(segment
		(start 147.333795 101.0394)
		(end 147.435395 100.9378)
		(width 0.2032)
		(layer "In3.Cu")
		(net "SDA")
	)
	(segment
		(start 140.513595 88.3156)
		(end 140.513595 87.4126)
		(width 0.2032)
		(layer "F.Cu")
		(net "SCL")
	)
	(segment
		(start 143.457195 84.4882)
		(end 145.978595 84.4882)
		(width 0.2032)
		(layer "F.Cu")
		(net "SCL")
	)
	(segment
		(start 143.447595 84.4786)
		(end 143.457195 84.4882)
		(width 0.2032)
		(layer "F.Cu")
		(net "SCL")
	)
	(segment
		(start 130.671395 103.0968)
		(end 130.671395 102.1824)
		(width 0.2032)
		(layer "F.Cu")
		(net "SCL")
	)
	(segment
		(start 137.513595 77.0836)
		(end 137.928705 77.0836)
		(width 0.2032)
		(layer "F.Cu")
		(net "SCL")
	)
	(segment
		(start 145.225595 72.8156)
		(end 145.225595 72.81278)
		(width 0.2032)
		(layer "F.Cu")
		(net "SCL")
	)
	(segment
		(start 144.928015 72.5152)
		(end 145.225595 72.81278)
		(width 0.2032)
		(layer "F.Cu")
		(net "SCL")
	)
	(segment
		(start 138.111995 75.6302)
		(end 140.763595 72.9786)
		(width 0.2032)
		(layer "F.Cu")
		(net "SCL")
	)
	(segment
		(start 145.751195 73.9422)
		(end 146.149595 74.3406)
		(width 0.2032)
		(layer "F.Cu")
		(net "SCL")
	)
	(segment
		(start 137.928705 77.0836)
		(end 138.111995 76.9003)
		(width 0.2032)
		(layer "F.Cu")
		(net "SCL")
	)
	(segment
		(start 140.763595 72.9786)
		(end 143.783995 72.9786)
		(width 0.2032)
		(layer "F.Cu")
		(net "SCL")
	)
	(segment
		(start 145.751195 73.9422)
		(end 145.751195 73.34119)
		(width 0.2032)
		(layer "F.Cu")
		(net "SCL")
	)
	(segment
		(start 130.671395 102.1824)
		(end 131.198195 101.6556)
		(width 0.2032)
		(layer "F.Cu")
		(net "SCL")
	)
	(segment
		(start 131.198195 101.6556)
		(end 131.198195 100.66475)
		(width 0.2032)
		(layer "F.Cu")
		(net "SCL")
	)
	(segment
		(start 169.888595 67.5786)
		(end 169.888595 67.52361)
		(width 0.2032)
		(layer "F.Cu")
		(net "SCL")
	)
	(segment
		(start 145.225595 72.8156)
		(end 145.751195 73.34119)
		(width 0.2032)
		(layer "F.Cu")
		(net "SCL")
	)
	(segment
		(start 143.803195 72.9978)
		(end 144.285795 72.5152)
		(width 0.2032)
		(layer "F.Cu")
		(net "SCL")
	)
	(segment
		(start 143.783995 72.9786)
		(end 143.803195 72.9978)
		(width 0.2032)
		(layer "F.Cu")
		(net "SCL")
	)
	(segment
		(start 138.111995 76.9003)
		(end 138.111995 75.6302)
		(width 0.2032)
		(layer "F.Cu")
		(net "SCL")
	)
	(segment
		(start 140.513595 87.4126)
		(end 143.447595 84.4786)
		(width 0.2032)
		(layer "F.Cu")
		(net "SCL")
	)
	(segment
		(start 169.638595 67.27361)
		(end 169.888595 67.52361)
		(width 0.2032)
		(layer "F.Cu")
		(net "SCL")
	)
	(segment
		(start 144.285795 72.5152)
		(end 144.928015 72.5152)
		(width 0.2032)
		(layer "F.Cu")
		(net "SCL")
	)
	(segment
		(start 169.638595 67.27361)
		(end 169.638595 64.64481)
		(width 0.2032)
		(layer "F.Cu")
		(net "SCL")
	)
	(via
		(at 143.396795 103.0968)
		(size 0.4064)
		(drill 0.2032)
		(layers "F.Cu" "B.Cu")
		(net "SCL")
	)
	(via
		(at 169.888595 67.5786)
		(size 0.4064)
		(drill 0.2032)
		(layers "F.Cu" "B.Cu")
		(net "SCL")
	)
	(via
		(at 143.803195 72.9978)
		(size 0.4064)
		(drill 0.2032)
		(layers "F.Cu" "B.Cu")
		(net "SCL")
	)
	(via
		(at 130.671395 103.0968)
		(size 0.4064)
		(drill 0.2032)
		(layers "F.Cu" "B.Cu")
		(net "SCL")
	)
	(via
		(at 143.447595 84.4786)
		(size 0.4064)
		(drill 0.2032)
		(layers "F.Cu" "B.Cu")
		(net "SCL")
	)
	(segment
		(start 165.388595 67.5786)
		(end 169.888595 67.5786)
		(width 0.2032)
		(layer "In2.Cu")
		(net "SCL")
	)
	(segment
		(start 143.788595 72.3786)
		(end 145.088595 71.0786)
		(width 0.2032)
		(layer "In2.Cu")
		(net "SCL")
	)
	(segment
		(start 143.788595 72.9832)
		(end 143.788595 72.3786)
		(width 0.2032)
		(layer "In2.Cu")
		(net "SCL")
	)
	(segment
		(start 161.888595 71.0786)
		(end 165.388595 67.5786)
		(width 0.2032)
		(layer "In2.Cu")
		(net "SCL")
	)
	(segment
		(start 145.088595 71.0786)
		(end 161.888595 71.0786)
		(width 0.2032)
		(layer "In2.Cu")
		(net "SCL")
	)
	(segment
		(start 130.671395 103.0968)
		(end 143.396795 103.0968)
		(width 0.2032)
		(layer "In2.Cu")
		(net "SCL")
	)
	(segment
		(start 143.788595 72.9832)
		(end 143.803195 72.9978)
		(width 0.2032)
		(layer "In2.Cu")
		(net "SCL")
	)
	(segment
		(start 143.447595 77.09442)
		(end 143.803195 76.73882)
		(width 0.2032)
		(layer "In3.Cu")
		(net "SCL")
	)
	(segment
		(start 143.396795 103.0968)
		(end 143.447595 103.046)
		(width 0.2032)
		(layer "In3.Cu")
		(net "SCL")
	)
	(segment
		(start 143.447595 84.4786)
		(end 143.447595 77.09442)
		(width 0.2032)
		(layer "In3.Cu")
		(net "SCL")
	)
	(segment
		(start 143.803195 76.73882)
		(end 143.803195 72.9978)
		(width 0.2032)
		(layer "In3.Cu")
		(net "SCL")
	)
	(segment
		(start 143.447595 103.046)
		(end 143.447595 84.4786)
		(width 0.2032)
		(layer "In3.Cu")
		(net "SCL")
	)
	(segment
		(start 223.064595 75.9431)
		(end 223.064595 73.5686)
		(width 0.2032)
		(layer "F.Cu")
		(net "SCK")
	)
	(segment
		(start 145.177975 113.56477)
		(end 147.181015 113.56477)
		(width 0.2032)
		(layer "F.Cu")
		(net "SCK")
	)
	(segment
		(start 144.666795 113.0536)
		(end 145.177975 113.56477)
		(width 0.2032)
		(layer "F.Cu")
		(net "SCK")
	)
	(segment
		(start 147.181015 113.56477)
		(end 147.185965 113.55982)
		(width 0.2032)
		(layer "F.Cu")
		(net "SCK")
	)
	(segment
		(start 223.064595 73.5686)
		(end 223.076595 73.5566)
		(width 0.2032)
		(layer "F.Cu")
		(net "SCK")
	)
	(via
		(at 145.788595 72.2786)
		(size 0.4064)
		(drill 0.2032)
		(layers "F.Cu" "B.Cu")
		(net "SCK")
	)
	(via
		(at 144.666795 113.0536)
		(size 0.4064)
		(drill 0.2032)
		(layers "F.Cu" "B.Cu")
		(net "SCK")
	)
	(via
		(at 223.076595 73.5566)
		(size 0.4064)
		(drill 0.2032)
		(layers "F.Cu" "B.Cu")
		(net "SCK")
	)
	(segment
		(start 222.822595 73.3026)
		(end 223.076595 73.5566)
		(width 0.2032)
		(layer "In2.Cu")
		(net "SCK")
	)
	(segment
		(start 145.801795 72.7866)
		(end 145.801795 72.2918)
		(width 0.2032)
		(layer "In2.Cu")
		(net "SCK")
	)
	(segment
		(start 145.788595 72.2786)
		(end 145.801795 72.2918)
		(width 0.2032)
		(layer "In2.Cu")
		(net "SCK")
	)
	(segment
		(start 145.801795 72.7866)
		(end 146.317795 73.3026)
		(width 0.2032)
		(layer "In2.Cu")
		(net "SCK")
	)
	(segment
		(start 146.317795 73.3026)
		(end 222.822595 73.3026)
		(width 0.2032)
		(layer "In2.Cu")
		(net "SCK")
	)
	(segment
		(start 145.784395 72.2828)
		(end 145.788595 72.2786)
		(width 0.2032)
		(layer "In3.Cu")
		(net "SCK")
	)
	(segment
		(start 144.725575 111.01362)
		(end 145.725055 110.01414)
		(width 0.2032)
		(layer "In3.Cu")
		(net "SCK")
	)
	(segment
		(start 144.666795 113.0536)
		(end 144.666795 111.15555)
		(width 0.2032)
		(layer "In3.Cu")
		(net "SCK")
	)
	(segment
		(start 145.784395 109.87063)
		(end 145.784395 72.2828)
		(width 0.2032)
		(layer "In3.Cu")
		(net "SCK")
	)
	(arc
		(start 145.784395 109.87063)
		(mid 145.768974 109.948278)
		(end 145.725053 110.01414)
		(width 0.2032)
		(layer "In3.Cu")
		(net "SCK")
	)
	(arc
		(start 144.666798 111.155554)
		(mid 144.682257 111.078823)
		(end 144.725573 111.013629)
		(width 0.2032)
		(layer "In3.Cu")
		(net "SCK")
	)
	(segment
		(start 83.038595 129.6786)
		(end 83.788595 129.6786)
		(width 0.2032)
		(layer "F.Cu")
		(net "MAC_10Mout")
	)
	(segment
		(start 201.054795 104.3414)
		(end 201.613595 103.7826)
		(width 0.2032)
		(layer "F.Cu")
		(net "MAC_10Mout")
	)
	(segment
		(start 117.698095 104.3099)
		(end 117.698095 100.66475)
		(width 0.2032)
		(layer "F.Cu")
		(net "MAC_10Mout")
	)
	(segment
		(start 117.198215 100.66475)
		(end 117.698095 100.66475)
		(width 0.2032)
		(layer "F.Cu")
		(net "MAC_10Mout")
	)
	(segment
		(start 83.988595 130.6786)
		(end 83.988595 129.8786)
		(width 0.2032)
		(layer "F.Cu")
		(net "MAC_10Mout")
	)
	(segment
		(start 122.688235 103.05927)
		(end 122.688235 100.68812)
		(width 0.2032)
		(layer "F.Cu")
		(net "MAC_10Mout")
	)
	(segment
		(start 122.688235 103.05927)
		(end 122.698085 103.06911)
		(width 0.2032)
		(layer "F.Cu")
		(net "MAC_10Mout")
	)
	(segment
		(start 200.165795 104.3414)
		(end 201.054795 104.3414)
		(width 0.2032)
		(layer "F.Cu")
		(net "MAC_10Mout")
	)
	(segment
		(start 121.984595 103.7826)
		(end 122.698085 103.06911)
		(width 0.2032)
		(layer "F.Cu")
		(net "MAC_10Mout")
	)
	(segment
		(start 83.788595 129.6786)
		(end 83.988595 129.8786)
		(width 0.2032)
		(layer "F.Cu")
		(net "MAC_10Mout")
	)
	(segment
		(start 117.691995 104.316)
		(end 117.698095 104.3099)
		(width 0.2032)
		(layer "F.Cu")
		(net "MAC_10Mout")
	)
	(segment
		(start 83.038595 129.6786)
		(end 83.038595 129.6786)
		(width 0.2032)
		(layer "F.Cu")
		(net "MAC_10Mout")
	)
	(via
		(at 121.984595 103.7826)
		(size 0.4064)
		(drill 0.2032)
		(layers "F.Cu" "B.Cu")
		(net "MAC_10Mout")
	)
	(via
		(at 200.165795 104.3414)
		(size 0.4064)
		(drill 0.2032)
		(layers "F.Cu" "B.Cu")
		(net "MAC_10Mout")
	)
	(via
		(at 201.613595 103.7826)
		(size 0.4064)
		(drill 0.2032)
		(layers "F.Cu" "B.Cu")
		(net "MAC_10Mout")
	)
	(via
		(at 117.691995 104.316)
		(size 0.4064)
		(drill 0.2032)
		(layers "F.Cu" "B.Cu")
		(net "MAC_10Mout")
	)
	(via
		(at 83.988595 130.6786)
		(size 0.4064)
		(drill 0.2032)
		(layers "F.Cu" "B.Cu")
		(net "MAC_10Mout")
	)
	(segment
		(start 121.983905 103.78329)
		(end 121.984595 103.7826)
		(width 0.2032)
		(layer "In2.Cu")
		(net "MAC_10Mout")
	)
	(segment
		(start 83.833905 103.78329)
		(end 121.983905 103.78329)
		(width 0.2032)
		(layer "In2.Cu")
		(net "MAC_10Mout")
	)
	(segment
		(start 80.388595 129.6786)
		(end 81.388595 130.6786)
		(width 0.2032)
		(layer "In2.Cu")
		(net "MAC_10Mout")
	)
	(segment
		(start 81.388595 130.6786)
		(end 83.988595 130.6786)
		(width 0.2032)
		(layer "In2.Cu")
		(net "MAC_10Mout")
	)
	(segment
		(start 80.388595 107.2286)
		(end 83.833905 103.78329)
		(width 0.2032)
		(layer "In2.Cu")
		(net "MAC_10Mout")
	)
	(segment
		(start 121.984595 103.7826)
		(end 201.613595 103.7826)
		(width 0.2032)
		(layer "In2.Cu")
		(net "MAC_10Mout")
	)
	(segment
		(start 117.691995 104.316)
		(end 200.165795 104.316)
		(width 0.2032)
		(layer "In2.Cu")
		(net "MAC_10Mout")
	)
	(segment
		(start 80.388595 129.6786)
		(end 80.388595 107.2286)
		(width 0.2032)
		(layer "In2.Cu")
		(net "MAC_10Mout")
	)
	(segment
		(start 200.220785 104.3414)
		(end 200.333585 104.2286)
		(width 0.2032)
		(layer "In3.Cu")
		(net "MAC_10Mout")
	)
	(segment
		(start 201.613595 107.2286)
		(end 201.613595 103.7826)
		(width 0.2032)
		(layer "In3.Cu")
		(net "MAC_10Mout")
	)
	(segment
		(start 200.173665 104.33353)
		(end 200.173665 97.35689)
		(width 0.2032)
		(layer "In3.Cu")
		(net "MAC_10Mout")
	)
	(segment
		(start 173.673595 107.2286)
		(end 201.613595 107.2286)
		(width 0.2032)
		(layer "In3.Cu")
		(net "MAC_10Mout")
	)
	(segment
		(start 200.333585 104.2286)
		(end 200.388595 104.2286)
		(width 0.2032)
		(layer "In3.Cu")
		(net "MAC_10Mout")
	)
	(segment
		(start 200.165795 104.3414)
		(end 200.220785 104.3414)
		(width 0.2032)
		(layer "In3.Cu")
		(net "MAC_10Mout")
	)
	(segment
		(start 200.173665 137.95689)
		(end 201.613595 136.51696)
		(width 0.2032)
		(layer "In3.Cu")
		(net "MAC_10Mout")
	)
	(segment
		(start 200.165795 104.3414)
		(end 200.173665 104.33353)
		(width 0.2032)
		(layer "In3.Cu")
		(net "MAC_10Mout")
	)
	(segment
		(start 201.613595 136.51696)
		(end 201.613595 107.2286)
		(width 0.2032)
		(layer "In3.Cu")
		(net "MAC_10Mout")
	)
	(segment
		(start 168.413595 101.9686)
		(end 173.673595 107.2286)
		(width 0.2032)
		(layer "In3.Cu")
		(net "MAC_10Mout")
	)
	(segment
		(start 144.155985 83.0632)
		(end 145.828595 83.0632)
		(width 0.2032)
		(layer "F.Cu")
		(net "OE_5356")
	)
	(segment
		(start 144.112185 83.107)
		(end 144.155985 83.0632)
		(width 0.2032)
		(layer "F.Cu")
		(net "OE_5356")
	)
	(segment
		(start 144.057195 83.107)
		(end 144.112185 83.107)
		(width 0.2032)
		(layer "F.Cu")
		(net "OE_5356")
	)
	(segment
		(start 115.698095 96.61497)
		(end 115.698095 94.1941)
		(width 0.2032)
		(layer "F.Cu")
		(net "OE_5356")
	)
	(via
		(at 144.209595 77.4428)
		(size 0.4064)
		(drill 0.2032)
		(layers "F.Cu" "B.Cu")
		(net "OE_5356")
	)
	(via
		(at 115.698095 94.1941)
		(size 0.4064)
		(drill 0.2032)
		(layers "F.Cu" "B.Cu")
		(net "OE_5356")
	)
	(via
		(at 115.888595 77.7476)
		(size 0.4064)
		(drill 0.2032)
		(layers "F.Cu" "B.Cu")
		(net "OE_5356")
	)
	(via
		(at 144.057195 83.107)
		(size 0.4064)
		(drill 0.2032)
		(layers "F.Cu" "B.Cu")
		(net "OE_5356")
	)
	(segment
		(start 115.888595 77.7476)
		(end 119.590445 77.7476)
		(width 0.2032)
		(layer "In2.Cu")
		(net "OE_5356")
	)
	(segment
		(start 127.069555 77.4428)
		(end 144.209595 77.4428)
		(width 0.2032)
		(layer "In2.Cu")
		(net "OE_5356")
	)
	(segment
		(start 144.002415 77.5063)
		(end 144.027035 77.48168)
		(width 0.2032)
		(layer "In2.Cu")
		(net "OE_5356")
	)
	(segment
		(start 126.906755 77.6056)
		(end 127.069555 77.4428)
		(width 0.2032)
		(layer "In2.Cu")
		(net "OE_5356")
	)
	(segment
		(start 119.590445 77.7476)
		(end 119.732445 77.6056)
		(width 0.2032)
		(layer "In2.Cu")
		(net "OE_5356")
	)
	(segment
		(start 119.732445 77.6056)
		(end 126.906755 77.6056)
		(width 0.2032)
		(layer "In2.Cu")
		(net "OE_5356")
	)
	(segment
		(start 144.027035 77.48168)
		(end 144.170715 77.48168)
		(width 0.2032)
		(layer "In2.Cu")
		(net "OE_5356")
	)
	(segment
		(start 144.170715 77.48168)
		(end 144.209595 77.4428)
		(width 0.2032)
		(layer "In2.Cu")
		(net "OE_5356")
	)
	(segment
		(start 115.888595 94.0036)
		(end 115.888595 77.7476)
		(width 0.2032)
		(layer "In3.Cu")
		(net "OE_5356")
	)
	(segment
		(start 144.057195 77.65019)
		(end 144.209595 77.49779)
		(width 0.2032)
		(layer "In3.Cu")
		(net "OE_5356")
	)
	(segment
		(start 144.209595 77.49779)
		(end 144.209595 77.4428)
		(width 0.2032)
		(layer "In3.Cu")
		(net "OE_5356")
	)
	(segment
		(start 115.698095 94.1941)
		(end 115.888595 94.0036)
		(width 0.2032)
		(layer "In3.Cu")
		(net "OE_5356")
	)
	(segment
		(start 144.057195 83.107)
		(end 144.057195 77.65019)
		(width 0.2032)
		(layer "In3.Cu")
		(net "OE_5356")
	)
	(segment
		(start 135.827595 65.4446)
		(end 135.827595 60.2216)
		(width 0.2032)
		(layer "F.Cu")
		(net "NetR19_2")
	)
	(segment
		(start 229.934595 108.8656)
		(end 229.934595 107.5206)
		(width 0.2032)
		(layer "F.Cu")
		(net "NetR2_1")
	)
	(segment
		(start 229.934595 108.8656)
		(end 231.328595 110.2596)
		(width 0.2032)
		(layer "F.Cu")
		(net "NetR2_1")
	)
	(segment
		(start 231.328595 110.2596)
		(end 232.028595 110.2596)
		(width 0.2032)
		(layer "F.Cu")
		(net "NetR2_1")
	)
	(segment
		(start 154.983575 66.9109)
		(end 155.031045 66.9109)
		(width 0.2032)
		(layer "F.Cu")
		(net "NetJ3_3")
	)
	(segment
		(start 156.823595 65.11835)
		(end 156.823595 58.3766)
		(width 0.2032)
		(layer "F.Cu")
		(net "NetJ3_3")
	)
	(segment
		(start 155.031045 66.9109)
		(end 156.823595 65.11835)
		(width 0.2032)
		(layer "F.Cu")
		(net "NetJ3_3")
	)
	(segment
		(start 154.878375 67.0161)
		(end 154.983575 66.9109)
		(width 0.2032)
		(layer "F.Cu")
		(net "NetJ3_3")
	)
	(segment
		(start 154.311595 67.0161)
		(end 154.878375 67.0161)
		(width 0.2032)
		(layer "F.Cu")
		(net "NetJ3_3")
	)
	(segment
		(start 159.042145 66.9109)
		(end 159.089615 66.9109)
		(width 0.2032)
		(layer "F.Cu")
		(net "NetJ3_2")
	)
	(segment
		(start 159.194815 67.0161)
		(end 159.761595 67.0161)
		(width 0.2032)
		(layer "F.Cu")
		(net "NetJ3_2")
	)
	(segment
		(start 157.623595 65.49235)
		(end 157.623595 58.3766)
		(width 0.2032)
		(layer "F.Cu")
		(net "NetJ3_2")
	)
	(segment
		(start 157.623595 65.49235)
		(end 159.042145 66.9109)
		(width 0.2032)
		(layer "F.Cu")
		(net "NetJ3_2")
	)
	(segment
		(start 159.089615 66.9109)
		(end 159.194815 67.0161)
		(width 0.2032)
		(layer "F.Cu")
		(net "NetJ3_2")
	)
	(segment
		(start 90.085395 56.6106)
		(end 90.234595 56.4614)
		(width 0.2032)
		(layer "F.Cu")
		(net "NetD14_1")
	)
	(segment
		(start 90.234595 56.4614)
		(end 90.234595 54.0886)
		(width 0.2032)
		(layer "F.Cu")
		(net "NetD14_1")
	)
	(segment
		(start 85.112255 56.4614)
		(end 85.112255 54.0886)
		(width 0.2032)
		(layer "F.Cu")
		(net "NetD13_1")
	)
	(segment
		(start 84.963055 56.6106)
		(end 85.112255 56.4614)
		(width 0.2032)
		(layer "F.Cu")
		(net "NetD13_1")
	)
	(segment
		(start 149.670595 65.8996)
		(end 150.146595 65.8996)
		(width 0.2032)
		(layer "F.Cu")
		(net "NetD10_1")
	)
	(segment
		(start 150.146595 65.8996)
		(end 151.633595 64.4126)
		(width 0.2032)
		(layer "F.Cu")
		(net "NetD10_1")
	)
	(segment
		(start 151.633595 64.4126)
		(end 151.658595 64.4126)
		(width 0.2032)
		(layer "F.Cu")
		(net "NetD10_1")
	)
	(segment
		(start 150.400595 61.2746)
		(end 151.633595 62.5076)
		(width 0.2032)
		(layer "F.Cu")
		(net "NetD9_1")
	)
	(segment
		(start 151.633595 62.5076)
		(end 151.658595 62.5076)
		(width 0.2032)
		(layer "F.Cu")
		(net "NetD9_1")
	)
	(segment
		(start 149.670595 61.2746)
		(end 150.400595 61.2746)
		(width 0.2032)
		(layer "F.Cu")
		(net "NetD9_1")
	)
	(segment
		(start 165.293595 69.0536)
		(end 167.088595 69.0536)
		(width 0.2032)
		(layer "F.Cu")
		(net "NetD4_1")
	)
	(segment
		(start 225.257595 64.0006)
		(end 225.353595 63.9046)
		(width 0.508)
		(layer "F.Cu")
		(net "NetD2_2")
	)
	(segment
		(start 219.694595 70.0006)
		(end 220.566595 70.0006)
		(width 0.508)
		(layer "F.Cu")
		(net "NetD2_2")
	)
	(segment
		(start 225.353595 63.9046)
		(end 229.553595 63.9046)
		(width 0.508)
		(layer "F.Cu")
		(net "NetD2_2")
	)
	(segment
		(start 221.413595 69.1536)
		(end 221.413595 65.9286)
		(width 0.508)
		(layer "F.Cu")
		(net "NetD2_2")
	)
	(segment
		(start 220.566595 70.0006)
		(end 221.413595 69.1536)
		(width 0.508)
		(layer "F.Cu")
		(net "NetD2_2")
	)
	(segment
		(start 229.553595 63.9046)
		(end 233.753595 63.9046)
		(width 0.508)
		(layer "F.Cu")
		(net "NetD2_2")
	)
	(segment
		(start 223.341595 64.0006)
		(end 225.257595 64.0006)
		(width 0.508)
		(layer "F.Cu")
		(net "NetD2_2")
	)
	(segment
		(start 221.413595 65.9286)
		(end 223.341595 64.0006)
		(width 0.508)
		(layer "F.Cu")
		(net "NetD2_2")
	)
	(segment
		(start 213.174795 70.2546)
		(end 213.174795 70.1146)
		(width 0.508)
		(layer "F.Cu")
		(net "NetD2_1")
	)
	(segment
		(start 213.280795 70.3054)
		(end 214.719995 70.3054)
		(width 0.508)
		(layer "F.Cu")
		(net "NetD2_1")
	)
	(segment
		(start 203.913595 58.1286)
		(end 206.547595 55.4946)
		(width 0.508)
		(layer "F.Cu")
		(net "NetD2_1")
	)
	(segment
		(start 213.174795 70.1146)
		(end 213.280795 70.0086)
		(width 0.508)
		(layer "F.Cu")
		(net "NetD2_1")
	)
	(segment
		(start 215.973595 69.9296)
		(end 216.044595 70.0006)
		(width 0.508)
		(layer "F.Cu")
		(net "NetD2_1")
	)
	(segment
		(start 215.988595 66.37978)
		(end 216.637415 66.37978)
		(width 0.508)
		(layer "F.Cu")
		(net "NetD2_1")
	)
	(segment
		(start 214.719995 70.3054)
		(end 215.024795 70.0006)
		(width 0.508)
		(layer "F.Cu")
		(net "NetD2_1")
	)
	(segment
		(start 206.547595 55.4946)
		(end 216.154595 55.4946)
		(width 0.508)
		(layer "F.Cu")
		(net "NetD2_1")
	)
	(segment
		(start 213.280795 70.3054)
		(end 213.280795 70.0086)
		(width 0.508)
		(layer "F.Cu")
		(net "NetD2_1")
	)
	(segment
		(start 215.973595 69.9296)
		(end 215.973595 69.48802)
		(width 0.508)
		(layer "F.Cu")
		(net "NetD2_1")
	)
	(segment
		(start 215.917595 66.45078)
		(end 215.988595 66.37978)
		(width 0.508)
		(layer "F.Cu")
		(net "NetD2_1")
	)
	(segment
		(start 216.154595 55.4946)
		(end 217.338595 56.6786)
		(width 0.508)
		(layer "F.Cu")
		(net "NetD2_1")
	)
	(segment
		(start 216.637415 66.37978)
		(end 217.338595 65.6786)
		(width 0.508)
		(layer "F.Cu")
		(net "NetD2_1")
	)
	(segment
		(start 215.917595 69.43202)
		(end 215.973595 69.48802)
		(width 0.508)
		(layer "F.Cu")
		(net "NetD2_1")
	)
	(segment
		(start 215.917595 66.5716)
		(end 215.917595 66.45078)
		(width 0.508)
		(layer "F.Cu")
		(net "NetD2_1")
	)
	(segment
		(start 215.917595 69.43202)
		(end 215.917595 66.5716)
		(width 0.508)
		(layer "F.Cu")
		(net "NetD2_1")
	)
	(segment
		(start 215.024795 70.0006)
		(end 216.044595 70.0006)
		(width 0.508)
		(layer "F.Cu")
		(net "NetD2_1")
	)
	(segment
		(start 217.338595 65.6786)
		(end 217.338595 56.6786)
		(width 0.508)
		(layer "F.Cu")
		(net "NetD2_1")
	)
	(segment
		(start 213.932595 65.5048)
		(end 213.932595 63.5546)
		(width 0.508)
		(layer "F.Cu")
		(net "NetD1_2")
	)
	(segment
		(start 212.865795 66.5716)
		(end 213.932595 65.5048)
		(width 0.508)
		(layer "F.Cu")
		(net "NetD1_2")
	)
	(segment
		(start 211.693595 66.5716)
		(end 212.865795 66.5716)
		(width 0.508)
		(layer "F.Cu")
		(net "NetD1_2")
	)
	(segment
		(start 203.828595 64.4686)
		(end 203.828595 62.9286)
		(width 0.508)
		(layer "F.Cu")
		(net "NetD1_1")
	)
	(segment
		(start 205.931595 66.5716)
		(end 207.843595 66.5716)
		(width 0.508)
		(layer "F.Cu")
		(net "NetD1_1")
	)
	(segment
		(start 203.828595 64.4686)
		(end 205.931595 66.5716)
		(width 0.508)
		(layer "F.Cu")
		(net "NetD1_1")
	)
	(segment
		(start 207.843595 66.5716)
		(end 208.043595 66.3716)
		(width 0.508)
		(layer "F.Cu")
		(net "NetD1_1")
	)
	(segment
		(start 208.043595 66.5716)
		(end 208.043595 66.3716)
		(width 0.508)
		(layer "F.Cu")
		(net "NetD1_1")
	)
	(segment
		(start 127.158575 157.7576)
		(end 127.191595 157.72458)
		(width 0.2032)
		(layer "B.Cu")
		(net "NetC49_1")
	)
	(segment
		(start 127.191595 156.9506)
		(end 127.191595 152.2186)
		(width 0.127)
		(layer "B.Cu")
		(net "NetC49_1")
	)
	(arc
		(start 127.191595 157.67788)
		(mid 127.183013 157.721024)
		(end 127.158574 157.757599)
		(width 0.127)
		(layer "B.Cu")
		(net "NetC49_1")
	)
	(arc
		(start 127.191595 156.9506)
		(mid 127.177816 157.019873)
		(end 127.138575 157.0786)
		(width 0.127)
		(layer "B.Cu")
		(net "NetC49_1")
	)
	(segment
		(start 212.535595 99.9326)
		(end 212.581595 99.9786)
		(width 0.2032)
		(layer "F.Cu")
		(net "NetC22_2")
	)
	(segment
		(start 212.581595 99.9786)
		(end 213.188595 99.9786)
		(width 0.2032)
		(layer "F.Cu")
		(net "NetC22_2")
	)
	(segment
		(start 213.188595 99.9786)
		(end 213.388595 100.1786)
		(width 0.2032)
		(layer "F.Cu")
		(net "NetC22_2")
	)
	(segment
		(start 213.388595 100.8786)
		(end 213.625595 101.1156)
		(width 0.2032)
		(layer "F.Cu")
		(net "NetC22_2")
	)
	(segment
		(start 213.625595 101.1156)
		(end 214.886595 101.1156)
		(width 0.2032)
		(layer "F.Cu")
		(net "NetC22_2")
	)
	(segment
		(start 213.388595 100.8786)
		(end 213.388595 100.1786)
		(width 0.2032)
		(layer "F.Cu")
		(net "NetC22_2")
	)
	(segment
		(start 211.002595 101.2826)
		(end 212.535595 101.2826)
		(width 0.2032)
		(layer "F.Cu")
		(net "NetC22_1")
	)
	(segment
		(start 212.535595 101.0376)
		(end 212.613595 101.1156)
		(width 0.2032)
		(layer "F.Cu")
		(net "NetC22_1")
	)
	(segment
		(start 210.988595 101.2686)
		(end 211.002595 101.2826)
		(width 0.2032)
		(layer "F.Cu")
		(net "NetC22_1")
	)
	(segment
		(start 214.859595 103.6826)
		(end 214.886595 103.6556)
		(width 0.2032)
		(layer "F.Cu")
		(net "NetC21_2")
	)
	(segment
		(start 214.859595 105.4336)
		(end 214.859595 103.6826)
		(width 0.2032)
		(layer "F.Cu")
		(net "NetC21_2")
	)
	(segment
		(start 232.028595 111.5296)
		(end 233.439595 111.5296)
		(width 0.2032)
		(layer "F.Cu")
		(net "NetC20_2")
	)
	(segment
		(start 234.699595 112.7786)
		(end 234.760595 112.8396)
		(width 0.2032)
		(layer "F.Cu")
		(net "NetC20_2")
	)
	(segment
		(start 233.439595 111.5296)
		(end 233.688595 111.7786)
		(width 0.2032)
		(layer "F.Cu")
		(net "NetC20_2")
	)
	(segment
		(start 233.988595 112.7786)
		(end 234.699595 112.7786)
		(width 0.2032)
		(layer "F.Cu")
		(net "NetC20_2")
	)
	(segment
		(start 233.688595 112.4786)
		(end 233.988595 112.7786)
		(width 0.2032)
		(layer "F.Cu")
		(net "NetC20_2")
	)
	(segment
		(start 233.688595 112.4786)
		(end 233.688595 111.7786)
		(width 0.2032)
		(layer "F.Cu")
		(net "NetC20_2")
	)
	(segment
		(start 234.760595 111.4896)
		(end 236.287595 111.4896)
		(width 0.2032)
		(layer "F.Cu")
		(net "NetC20_1")
	)
	(segment
		(start 234.555595 111.5296)
		(end 234.760595 111.7346)
		(width 0.2032)
		(layer "F.Cu")
		(net "NetC20_1")
	)
	(segment
		(start 236.287595 111.4896)
		(end 236.288595 111.4886)
		(width 0.2032)
		(layer "F.Cu")
		(net "NetC20_1")
	)
	(segment
		(start 232.309595 108.8062)
		(end 232.309595 107.3386)
		(width 0.2032)
		(layer "F.Cu")
		(net "NetC19_2")
	)
	(segment
		(start 232.028595 108.9896)
		(end 232.126195 108.9896)
		(width 0.2032)
		(layer "F.Cu")
		(net "NetC19_2")
	)
	(segment
		(start 232.126195 108.9896)
		(end 232.309595 108.8062)
		(width 0.2032)
		(layer "F.Cu")
		(net "NetC19_2")
	)
	(segment
		(start 224.092595 110.9576)
		(end 224.664595 111.5296)
		(width 0.2032)
		(layer "F.Cu")
		(net "NetC4_2")
	)
	(segment
		(start 223.121595 110.9326)
		(end 224.092595 110.9326)
		(width 0.2032)
		(layer "F.Cu")
		(net "NetC4_2")
	)
	(segment
		(start 219.012595 113.7916)
		(end 220.262595 113.7916)
		(width 0.2032)
		(layer "F.Cu")
		(net "NetC4_2")
	)
	(segment
		(start 220.262595 113.7916)
		(end 223.121595 110.9326)
		(width 0.2032)
		(layer "F.Cu")
		(net "NetC4_2")
	)
	(segment
		(start 224.664595 111.5296)
		(end 227.078595 111.5296)
		(width 0.2032)
		(layer "F.Cu")
		(net "NetC4_2")
	)
	(segment
		(start 224.092595 110.9576)
		(end 224.092595 110.9326)
		(width 0.2032)
		(layer "F.Cu")
		(net "NetC4_2")
	)
	(segment
		(start 224.092595 109.3326)
		(end 224.435595 108.9896)
		(width 0.2032)
		(layer "F.Cu")
		(net "NetC4_1")
	)
	(segment
		(start 224.435595 108.9896)
		(end 227.078595 108.9896)
		(width 0.2032)
		(layer "F.Cu")
		(net "NetC4_1")
	)
	(segment
		(start 221.953595 102.0936)
		(end 222.822595 102.0936)
		(width 0.2032)
		(layer "F.Cu")
		(net "NetC3_2")
	)
	(segment
		(start 219.836595 101.1156)
		(end 220.975595 101.1156)
		(width 0.2032)
		(layer "F.Cu")
		(net "NetC3_2")
	)
	(segment
		(start 228.156595 101.1606)
		(end 228.156595 99.1076)
		(width 0.2032)
		(layer "F.Cu")
		(net "NetC3_2")
	)
	(segment
		(start 227.223595 102.0936)
		(end 228.156595 101.1606)
		(width 0.2032)
		(layer "F.Cu")
		(net "NetC3_2")
	)
	(segment
		(start 220.975595 101.1156)
		(end 221.953595 102.0936)
		(width 0.2032)
		(layer "F.Cu")
		(net "NetC3_2")
	)
	(segment
		(start 222.822595 102.0936)
		(end 227.223595 102.0936)
		(width 0.2032)
		(layer "F.Cu")
		(net "NetC3_2")
	)
	(segment
		(start 222.784595 103.6556)
		(end 222.822595 103.6936)
		(width 0.2032)
		(layer "F.Cu")
		(net "NetC3_1")
	)
	(segment
		(start 219.836595 103.6556)
		(end 222.784595 103.6556)
		(width 0.2032)
		(layer "F.Cu")
		(net "NetC3_1")
	)
	(segment
		(start 143.982375 110.57238)
		(end 144.151945 110.74195)
		(width 0.2032)
		(layer "F.Cu")
		(net "MOSI")
	)
	(segment
		(start 142.279195 110.5136)
		(end 143.839425 110.5136)
		(width 0.2032)
		(layer "F.Cu")
		(net "MOSI")
	)
	(segment
		(start 144.151945 110.74195)
		(end 145.911045 112.50105)
		(width 0.2032)
		(layer "F.Cu")
		(net "MOSI")
	)
	(segment
		(start 221.298595 74.9536)
		(end 221.679595 74.9536)
		(width 0.2032)
		(layer "F.Cu")
		(net "MOSI")
	)
	(segment
		(start 222.064595 75.9431)
		(end 222.064595 75.3386)
		(width 0.2032)
		(layer "F.Cu")
		(net "MOSI")
	)
	(segment
		(start 221.679595 74.9536)
		(end 222.064595 75.3386)
		(width 0.2032)
		(layer "F.Cu")
		(net "MOSI")
	)
	(segment
		(start 146.052975 112.55982)
		(end 147.185965 112.55982)
		(width 0.2032)
		(layer "F.Cu")
		(net "MOSI")
	)
	(via
		(at 142.279195 110.5136)
		(size 0.4064)
		(drill 0.2032)
		(layers "F.Cu" "B.Cu")
		(net "MOSI")
	)
	(via
		(at 221.298595 74.9536)
		(size 0.4064)
		(drill 0.2032)
		(layers "F.Cu" "B.Cu")
		(net "MOSI")
	)
	(via
		(at 142.380795 75.6394)
		(size 0.4064)
		(drill 0.2032)
		(layers "F.Cu" "B.Cu")
		(net "MOSI")
	)
	(arc
		(start 143.839425 110.5136)
		(mid 143.916703 110.528868)
		(end 143.982368 110.572379)
		(width 0.2032)
		(layer "F.Cu")
		(net "MOSI")
	)
	(arc
		(start 146.052966 112.559817)
		(mid 145.976236 112.544357)
		(end 145.911042 112.501041)
		(width 0.2032)
		(layer "F.Cu")
		(net "MOSI")
	)
	(segment
		(start 150.438575 75.4484)
		(end 151.138575 74.7484)
		(width 0.2032)
		(layer "In2.Cu")
		(net "MOSI")
	)
	(segment
		(start 146.341685 75.6394)
		(end 146.532685 75.4484)
		(width 0.2032)
		(layer "In2.Cu")
		(net "MOSI")
	)
	(segment
		(start 151.138575 74.7484)
		(end 186.088495 74.7484)
		(width 0.2032)
		(layer "In2.Cu")
		(net "MOSI")
	)
	(segment
		(start 186.088495 74.7484)
		(end 186.293685 74.9536)
		(width 0.2032)
		(layer "In2.Cu")
		(net "MOSI")
	)
	(segment
		(start 186.293685 74.9536)
		(end 221.298595 74.9536)
		(width 0.2032)
		(layer "In2.Cu")
		(net "MOSI")
	)
	(segment
		(start 146.532685 75.4484)
		(end 150.438575 75.4484)
		(width 0.2032)
		(layer "In2.Cu")
		(net "MOSI")
	)
	(segment
		(start 142.380795 75.6394)
		(end 146.341685 75.6394)
		(width 0.2032)
		(layer "In2.Cu")
		(net "MOSI")
	)
	(segment
		(start 142.279195 110.5136)
		(end 142.279195 110.45861)
		(width 0.2032)
		(layer "In3.Cu")
		(net "MOSI")
	)
	(segment
		(start 142.279195 110.45861)
		(end 142.380795 110.35701)
		(width 0.2032)
		(layer "In3.Cu")
		(net "MOSI")
	)
	(segment
		(start 142.380795 110.35701)
		(end 142.380795 75.6394)
		(width 0.2032)
		(layer "In3.Cu")
		(net "MOSI")
	)
	(segment
		(start 223.877095 76.0056)
		(end 223.877095 72.8331)
		(width 0.2032)
		(layer "F.Cu")
		(net "MISO")
	)
	(segment
		(start 223.838595 72.7946)
		(end 223.877095 72.8331)
		(width 0.2032)
		(layer "F.Cu")
		(net "MISO")
	)
	(segment
		(start 147.182795 113.05677)
		(end 147.185965 113.05995)
		(width 0.2032)
		(layer "F.Cu")
		(net "MISO")
	)
	(segment
		(start 145.845565 113.05677)
		(end 147.182795 113.05677)
		(width 0.2032)
		(layer "F.Cu")
		(net "MISO")
	)
	(via
		(at 145.845565 113.05677)
		(size 0.4064)
		(drill 0.2032)
		(layers "F.Cu" "B.Cu")
		(net "MISO")
	)
	(via
		(at 223.838595 72.7946)
		(size 0.4064)
		(drill 0.2032)
		(layers "F.Cu" "B.Cu")
		(net "MISO")
	)
	(via
		(at 146.622595 72.7946)
		(size 0.4064)
		(drill 0.2032)
		(layers "F.Cu" "B.Cu")
		(net "MISO")
	)
	(segment
		(start 146.622595 72.7946)
		(end 223.838595 72.7946)
		(width 0.2032)
		(layer "In2.Cu")
		(net "MISO")
	)
	(segment
		(start 145.845565 113.05677)
		(end 145.845565 112.95881)
		(width 0.2032)
		(layer "In3.Cu")
		(net "MISO")
	)
	(segment
		(start 145.836975 112.95022)
		(end 145.845565 112.95881)
		(width 0.2032)
		(layer "In3.Cu")
		(net "MISO")
	)
	(segment
		(start 145.836975 112.95022)
		(end 146.622595 112.1646)
		(width 0.2032)
		(layer "In3.Cu")
		(net "MISO")
	)
	(segment
		(start 146.622595 112.1646)
		(end 146.622595 72.7946)
		(width 0.2032)
		(layer "In3.Cu")
		(net "MISO")
	)
	(segment
		(start 116.198225 97.99623)
		(end 116.198225 96.61497)
		(width 0.2032)
		(layer "F.Cu")
		(net "MAC_USB_PWR")
	)
	(segment
		(start 157.840695 118.93417)
		(end 159.310365 118.93417)
		(width 0.254)
		(layer "F.Cu")
		(net "MAC_USB_PWR")
	)
	(segment
		(start 157.838695 118.93217)
		(end 157.840695 118.93417)
		(width 0.254)
		(layer "F.Cu")
		(net "MAC_USB_PWR")
	)
	(segment
		(start 160.944435 121.27944)
		(end 160.973595 121.3086)
		(width 0.254)
		(layer "F.Cu")
		(net "MAC_USB_PWR")
	)
	(segment
		(start 160.944435 121.27944)
		(end 160.944435 120.56824)
		(width 0.254)
		(layer "F.Cu")
		(net "MAC_USB_PWR")
	)
	(segment
		(start 159.310365 118.93417)
		(end 160.944435 120.56824)
		(width 0.254)
		(layer "F.Cu")
		(net "MAC_USB_PWR")
	)
	(via
		(at 160.973595 121.3086)
		(size 0.4064)
		(drill 0.2032)
		(layers "F.Cu" "B.Cu")
		(net "MAC_USB_PWR")
	)
	(via
		(at 116.269595 122.3246)
		(size 0.4064)
		(drill 0.2032)
		(layers "F.Cu" "B.Cu")
		(net "MAC_USB_PWR")
	)
	(via
		(at 116.198225 97.99623)
		(size 0.4064)
		(drill 0.2032)
		(layers "F.Cu" "B.Cu")
		(net "MAC_USB_PWR")
	)
	(segment
		(start 149.797595 123.5946)
		(end 158.128795 123.5946)
		(width 0.2032)
		(layer "In2.Cu")
		(net "MAC_USB_PWR")
	)
	(segment
		(start 159.119395 123.1628)
		(end 160.973595 121.3086)
		(width 0.2032)
		(layer "In2.Cu")
		(net "MAC_USB_PWR")
	)
	(segment
		(start 148.527595 122.3246)
		(end 149.797595 123.5946)
		(width 0.2032)
		(layer "In2.Cu")
		(net "MAC_USB_PWR")
	)
	(segment
		(start 158.128795 123.5946)
		(end 158.560595 123.1628)
		(width 0.2032)
		(layer "In2.Cu")
		(net "MAC_USB_PWR")
	)
	(segment
		(start 158.560595 123.1628)
		(end 159.119395 123.1628)
		(width 0.2032)
		(layer "In2.Cu")
		(net "MAC_USB_PWR")
	)
	(segment
		(start 116.269595 122.3246)
		(end 148.527595 122.3246)
		(width 0.2032)
		(layer "In2.Cu")
		(net "MAC_USB_PWR")
	)
	(segment
		(start 116.198225 102.43401)
		(end 116.198225 97.99623)
		(width 0.2032)
		(layer "In3.Cu")
		(net "MAC_USB_PWR")
	)
	(segment
		(start 116.269595 122.3246)
		(end 116.269595 102.50538)
		(width 0.2032)
		(layer "In3.Cu")
		(net "MAC_USB_PWR")
	)
	(segment
		(start 116.198225 102.43401)
		(end 116.269595 102.50538)
		(width 0.2032)
		(layer "In3.Cu")
		(net "MAC_USB_PWR")
	)
	(segment
		(start 132.675325 98.90313)
		(end 132.677995 98.9058)
		(width 0.2032)
		(layer "F.Cu")
		(net "MAC_USB-")
	)
	(segment
		(start 157.838695 119.44017)
		(end 157.840695 119.44217)
		(width 0.254)
		(layer "F.Cu")
		(net "MAC_USB-")
	)
	(segment
		(start 132.675325 98.90313)
		(end 132.675325 96.63771)
		(width 0.2032)
		(layer "F.Cu")
		(net "MAC_USB-")
	)
	(segment
		(start 132.675325 96.63771)
		(end 132.698065 96.61497)
		(width 0.2032)
		(layer "F.Cu")
		(net "MAC_USB-")
	)
	(segment
		(start 157.840695 119.44217)
		(end 159.183365 119.44217)
		(width 0.254)
		(layer "F.Cu")
		(net "MAC_USB-")
	)
	(segment
		(start 159.957595 121.1816)
		(end 159.957595 120.2164)
		(width 0.254)
		(layer "F.Cu")
		(net "MAC_USB-")
	)
	(segment
		(start 159.183365 119.44217)
		(end 159.957595 120.2164)
		(width 0.254)
		(layer "F.Cu")
		(net "MAC_USB-")
	)
	(via
		(at 132.677995 98.9058)
		(size 0.4064)
		(drill 0.2032)
		(layers "F.Cu" "B.Cu")
		(net "MAC_USB-")
	)
	(via
		(at 132.652595 121.5626)
		(size 0.4064)
		(drill 0.2032)
		(layers "F.Cu" "B.Cu")
		(net "MAC_USB-")
	)
	(via
		(at 159.957595 121.1816)
		(size 0.4064)
		(drill 0.2032)
		(layers "F.Cu" "B.Cu")
		(net "MAC_USB-")
	)
	(segment
		(start 157.492295 122.1722)
		(end 159.025015 122.1722)
		(width 0.2032)
		(layer "In2.Cu")
		(net "MAC_USB-")
	)
	(segment
		(start 159.830595 121.36359)
		(end 159.957595 121.23659)
		(width 0.2032)
		(layer "In2.Cu")
		(net "MAC_USB-")
	)
	(segment
		(start 156.882695 121.5626)
		(end 157.492295 122.1722)
		(width 0.2032)
		(layer "In2.Cu")
		(net "MAC_USB-")
	)
	(segment
		(start 159.957595 121.23659)
		(end 159.957595 121.1816)
		(width 0.2032)
		(layer "In2.Cu")
		(net "MAC_USB-")
	)
	(segment
		(start 132.652595 121.5626)
		(end 156.882695 121.5626)
		(width 0.2032)
		(layer "In2.Cu")
		(net "MAC_USB-")
	)
	(segment
		(start 159.025015 122.1722)
		(end 159.830595 121.36662)
		(width 0.2032)
		(layer "In2.Cu")
		(net "MAC_USB-")
	)
	(segment
		(start 159.830595 121.36662)
		(end 159.830595 121.36359)
		(width 0.2032)
		(layer "In2.Cu")
		(net "MAC_USB-")
	)
	(segment
		(start 132.652595 121.5626)
		(end 132.677995 121.5372)
		(width 0.2032)
		(layer "In3.Cu")
		(net "MAC_USB-")
	)
	(segment
		(start 132.677995 121.5372)
		(end 132.677995 98.9058)
		(width 0.2032)
		(layer "In3.Cu")
		(net "MAC_USB-")
	)
	(segment
		(start 159.322595 121.1562)
		(end 159.322595 120.4196)
		(width 0.254)
		(layer "F.Cu")
		(net "MAC_USB+")
	)
	(segment
		(start 132.017595 98.8296)
		(end 132.017595 97.9675)
		(width 0.2032)
		(layer "F.Cu")
		(net "MAC_USB+")
	)
	(segment
		(start 132.198185 97.7869)
		(end 132.198185 96.61497)
		(width 0.2032)
		(layer "F.Cu")
		(net "MAC_USB+")
	)
	(segment
		(start 157.838695 119.94817)
		(end 158.195905 119.94817)
		(width 0.254)
		(layer "F.Cu")
		(net "MAC_USB+")
	)
	(segment
		(start 158.853165 119.95017)
		(end 159.322595 120.4196)
		(width 0.254)
		(layer "F.Cu")
		(net "MAC_USB+")
	)
	(segment
		(start 158.197905 119.95017)
		(end 158.853165 119.95017)
		(width 0.254)
		(layer "F.Cu")
		(net "MAC_USB+")
	)
	(segment
		(start 158.195905 119.94817)
		(end 158.197905 119.95017)
		(width 0.254)
		(layer "F.Cu")
		(net "MAC_USB+")
	)
	(segment
		(start 132.017595 97.9675)
		(end 132.198185 97.7869)
		(width 0.2032)
		(layer "F.Cu")
		(net "MAC_USB+")
	)
	(via
		(at 132.017595 120.9276)
		(size 0.4064)
		(drill 0.2032)
		(layers "F.Cu" "B.Cu")
		(net "MAC_USB+")
	)
	(via
		(at 132.017595 98.8296)
		(size 0.4064)
		(drill 0.2032)
		(layers "F.Cu" "B.Cu")
		(net "MAC_USB+")
	)
	(via
		(at 159.322595 121.1562)
		(size 0.4064)
		(drill 0.2032)
		(layers "F.Cu" "B.Cu")
		(net "MAC_USB+")
	)
	(segment
		(start 158.331995 120.8529)
		(end 158.866895 120.8529)
		(width 0.2032)
		(layer "In2.Cu")
		(net "MAC_USB+")
	)
	(segment
		(start 155.207795 120.191)
		(end 157.670095 120.191)
		(width 0.2032)
		(layer "In2.Cu")
		(net "MAC_USB+")
	)
	(segment
		(start 158.866895 120.8529)
		(end 159.170195 121.1562)
		(width 0.2032)
		(layer "In2.Cu")
		(net "MAC_USB+")
	)
	(segment
		(start 143.015795 120.9276)
		(end 143.244395 121.1562)
		(width 0.2032)
		(layer "In2.Cu")
		(net "MAC_USB+")
	)
	(segment
		(start 132.017595 120.9276)
		(end 143.015795 120.9276)
		(width 0.2032)
		(layer "In2.Cu")
		(net "MAC_USB+")
	)
	(segment
		(start 157.670095 120.191)
		(end 158.331995 120.8529)
		(width 0.2032)
		(layer "In2.Cu")
		(net "MAC_USB+")
	)
	(segment
		(start 143.244395 121.1562)
		(end 154.242595 121.1562)
		(width 0.2032)
		(layer "In2.Cu")
		(net "MAC_USB+")
	)
	(segment
		(start 159.170195 121.1562)
		(end 159.322595 121.1562)
		(width 0.2032)
		(layer "In2.Cu")
		(net "MAC_USB+")
	)
	(segment
		(start 154.242595 121.1562)
		(end 155.207795 120.191)
		(width 0.2032)
		(layer "In2.Cu")
		(net "MAC_USB+")
	)
	(segment
		(start 132.017595 120.9276)
		(end 132.017595 98.8296)
		(width 0.2032)
		(layer "In3.Cu")
		(net "MAC_USB+")
	)
	(segment
		(start 167.673665 94.65689)
		(end 182.266885 94.65689)
		(width 0.2032)
		(layer "F.Cu")
		(net "MAC_TX")
	)
	(segment
		(start 120.698085 94.59411)
		(end 121.063595 94.2286)
		(width 0.2032)
		(layer "F.Cu")
		(net "MAC_TX")
	)
	(segment
		(start 182.266885 94.65689)
		(end 187.038595 99.4286)
		(width 0.2032)
		(layer "F.Cu")
		(net "MAC_TX")
	)
	(segment
		(start 121.063595 94.2286)
		(end 121.063595 92.6536)
		(width 0.2032)
		(layer "F.Cu")
		(net "MAC_TX")
	)
	(segment
		(start 187.038595 133.2936)
		(end 188.733595 134.9886)
		(width 0.2032)
		(layer "F.Cu")
		(net "MAC_TX")
	)
	(segment
		(start 120.698085 96.61497)
		(end 120.698085 94.59411)
		(width 0.2032)
		(layer "F.Cu")
		(net "MAC_TX")
	)
	(segment
		(start 121.063595 92.6536)
		(end 121.582085 92.13511)
		(width 0.2032)
		(layer "F.Cu")
		(net "MAC_TX")
	)
	(segment
		(start 187.038595 133.2936)
		(end 187.038595 99.4286)
		(width 0.2032)
		(layer "F.Cu")
		(net "MAC_TX")
	)
	(segment
		(start 92.738595 59.4786)
		(end 94.263595 59.4786)
		(width 0.2032)
		(layer "F.Cu")
		(net "MAC_TX")
	)
	(segment
		(start 121.582085 92.13511)
		(end 121.821085 92.13511)
		(width 0.2032)
		(layer "F.Cu")
		(net "MAC_TX")
	)
	(segment
		(start 121.821085 92.13511)
		(end 121.857595 92.0986)
		(width 0.2032)
		(layer "F.Cu")
		(net "MAC_TX")
	)
	(segment
		(start 92.688595 59.5286)
		(end 92.738595 59.4786)
		(width 0.2032)
		(layer "F.Cu")
		(net "MAC_TX")
	)
	(via
		(at 94.263595 59.4786)
		(size 0.4064)
		(drill 0.2032)
		(layers "F.Cu" "B.Cu")
		(net "MAC_TX")
	)
	(via
		(at 121.857595 92.0986)
		(size 0.4064)
		(drill 0.2032)
		(layers "F.Cu" "B.Cu")
		(net "MAC_TX")
	)
	(segment
		(start 121.857595 92.0986)
		(end 122.238595 92.4796)
		(width 0.2032)
		(layer "In2.Cu")
		(net "MAC_TX")
	)
	(segment
		(start 94.038595 82.4536)
		(end 94.038595 71.10609)
		(width 0.2032)
		(layer "In2.Cu")
		(net "MAC_TX")
	)
	(segment
		(start 114.813595 88.4286)
		(end 118.483595 92.0986)
		(width 0.2032)
		(layer "In2.Cu")
		(net "MAC_TX")
	)
	(segment
		(start 94.263595 59.49923)
		(end 94.263595 59.4786)
		(width 0.2032)
		(layer "In2.Cu")
		(net "MAC_TX")
	)
	(segment
		(start 94.063595 71.0811)
		(end 94.063595 59.69923)
		(width 0.2032)
		(layer "In2.Cu")
		(net "MAC_TX")
	)
	(segment
		(start 94.038595 71.10609)
		(end 94.063595 71.0811)
		(width 0.2032)
		(layer "In2.Cu")
		(net "MAC_TX")
	)
	(segment
		(start 94.038595 82.4536)
		(end 100.013595 88.4286)
		(width 0.2032)
		(layer "In2.Cu")
		(net "MAC_TX")
	)
	(segment
		(start 94.063595 59.69923)
		(end 94.263595 59.49923)
		(width 0.2032)
		(layer "In2.Cu")
		(net "MAC_TX")
	)
	(segment
		(start 100.013595 88.4286)
		(end 114.813595 88.4286)
		(width 0.2032)
		(layer "In2.Cu")
		(net "MAC_TX")
	)
	(segment
		(start 122.238595 92.4796)
		(end 165.496375 92.4796)
		(width 0.2032)
		(layer "In2.Cu")
		(net "MAC_TX")
	)
	(segment
		(start 118.483595 92.0986)
		(end 121.857595 92.0986)
		(width 0.2032)
		(layer "In2.Cu")
		(net "MAC_TX")
	)
	(segment
		(start 165.496375 92.4796)
		(end 167.673665 94.65689)
		(width 0.2032)
		(layer "In2.Cu")
		(net "MAC_TX")
	)
	(segment
		(start 114.688595 57.0786)
		(end 115.438595 57.0786)
		(width 0.2032)
		(layer "F.Cu")
		(net "MAC_RX")
	)
	(segment
		(start 121.180415 94.83959)
		(end 121.857595 94.16241)
		(width 0.2032)
		(layer "F.Cu")
		(net "MAC_RX")
	)
	(segment
		(start 182.788595 93.0536)
		(end 190.863595 101.1286)
		(width 0.2032)
		(layer "F.Cu")
		(net "MAC_RX")
	)
	(segment
		(start 164.673665 94.65689)
		(end 166.276955 93.0536)
		(width 0.2032)
		(layer "F.Cu")
		(net "MAC_RX")
	)
	(segment
		(start 166.276955 93.0536)
		(end 182.788595 93.0536)
		(width 0.2032)
		(layer "F.Cu")
		(net "MAC_RX")
	)
	(segment
		(start 121.857595 94.16241)
		(end 121.857595 92.9876)
		(width 0.2032)
		(layer "F.Cu")
		(net "MAC_RX")
	)
	(segment
		(start 121.180415 96.59718)
		(end 121.180415 94.83959)
		(width 0.2032)
		(layer "F.Cu")
		(net "MAC_RX")
	)
	(segment
		(start 190.863595 131.77859)
		(end 190.863595 101.1286)
		(width 0.2032)
		(layer "F.Cu")
		(net "MAC_RX")
	)
	(segment
		(start 190.863595 131.77859)
		(end 193.813595 134.72859)
		(width 0.2032)
		(layer "F.Cu")
		(net "MAC_RX")
	)
	(segment
		(start 193.813595 134.9886)
		(end 193.813595 134.72859)
		(width 0.2032)
		(layer "F.Cu")
		(net "MAC_RX")
	)
	(segment
		(start 115.438595 57.0786)
		(end 115.738595 56.7786)
		(width 0.2032)
		(layer "F.Cu")
		(net "MAC_RX")
	)
	(segment
		(start 121.180415 96.59718)
		(end 121.198215 96.61497)
		(width 0.2032)
		(layer "F.Cu")
		(net "MAC_RX")
	)
	(via
		(at 115.738595 56.7786)
		(size 0.4064)
		(drill 0.2032)
		(layers "F.Cu" "B.Cu")
		(net "MAC_RX")
	)
	(via
		(at 121.857595 92.9876)
		(size 0.4064)
		(drill 0.2032)
		(layers "F.Cu" "B.Cu")
		(net "MAC_RX")
	)
	(segment
		(start 121.857595 92.9876)
		(end 163.004375 92.9876)
		(width 0.2032)
		(layer "In2.Cu")
		(net "MAC_RX")
	)
	(segment
		(start 163.004375 92.9876)
		(end 164.673665 94.65689)
		(width 0.2032)
		(layer "In2.Cu")
		(net "MAC_RX")
	)
	(segment
		(start 115.738595 62.8536)
		(end 115.738595 56.7786)
		(width 0.2032)
		(layer "In3.Cu")
		(net "MAC_RX")
	)
	(segment
		(start 119.105695 90.2357)
		(end 119.105695 83.8957)
		(width 0.2032)
		(layer "In3.Cu")
		(net "MAC_RX")
	)
	(segment
		(start 119.088595 83.8786)
		(end 119.105695 83.8957)
		(width 0.2032)
		(layer "In3.Cu")
		(net "MAC_RX")
	)
	(segment
		(start 119.088595 76.8036)
		(end 121.463595 74.4286)
		(width 0.2032)
		(layer "In3.Cu")
		(net "MAC_RX")
	)
	(segment
		(start 115.738595 62.8536)
		(end 121.463595 68.5786)
		(width 0.2032)
		(layer "In3.Cu")
		(net "MAC_RX")
	)
	(segment
		(start 119.088595 83.8786)
		(end 119.088595 76.8036)
		(width 0.2032)
		(layer "In3.Cu")
		(net "MAC_RX")
	)
	(segment
		(start 119.105695 90.2357)
		(end 121.857595 92.9876)
		(width 0.2032)
		(layer "In3.Cu")
		(net "MAC_RX")
	)
	(segment
		(start 121.463595 74.4286)
		(end 121.463595 68.5786)
		(width 0.2032)
		(layer "In3.Cu")
		(net "MAC_RX")
	)
	(segment
		(start 161.735595 115.35277)
		(end 161.758995 115.37617)
		(width 0.2032)
		(layer "F.Cu")
		(net "MAC_PPS_OUT-")
	)
	(segment
		(start 125.159595 98.0676)
		(end 125.198205 98.10621)
		(width 0.2032)
		(layer "F.Cu")
		(net "MAC_PPS_OUT-")
	)
	(segment
		(start 161.758995 115.37617)
		(end 161.838695 115.37617)
		(width 0.2032)
		(layer "F.Cu")
		(net "MAC_PPS_OUT-")
	)
	(segment
		(start 125.159595 98.0676)
		(end 125.178895 98.0483)
		(width 0.2032)
		(layer "F.Cu")
		(net "MAC_PPS_OUT-")
	)
	(segment
		(start 125.198205 100.66475)
		(end 125.198205 98.10621)
		(width 0.2032)
		(layer "F.Cu")
		(net "MAC_PPS_OUT-")
	)
	(segment
		(start 161.735595 115.35277)
		(end 161.735595 114.9586)
		(width 0.2032)
		(layer "F.Cu")
		(net "MAC_PPS_OUT-")
	)
	(via
		(at 125.210395 115.619)
		(size 0.4064)
		(drill 0.2032)
		(layers "F.Cu" "B.Cu")
		(net "MAC_PPS_OUT-")
	)
	(via
		(at 125.159595 98.0676)
		(size 0.4064)
		(drill 0.2032)
		(layers "F.Cu" "B.Cu")
		(net "MAC_PPS_OUT-")
	)
	(via
		(at 161.735595 114.9586)
		(size 0.4064)
		(drill 0.2032)
		(layers "F.Cu" "B.Cu")
		(net "MAC_PPS_OUT-")
	)
	(segment
		(start 147.232195 115.2634)
		(end 152.567695 115.2634)
		(width 0.2032)
		(layer "In2.Cu")
		(net "MAC_PPS_OUT-")
	)
	(segment
		(start 159.928755 115.111)
		(end 160.081155 114.9586)
		(width 0.2032)
		(layer "In2.Cu")
		(net "MAC_PPS_OUT-")
	)
	(segment
		(start 125.265385 115.619)
		(end 125.366985 115.7206)
		(width 0.2032)
		(layer "In2.Cu")
		(net "MAC_PPS_OUT-")
	)
	(segment
		(start 152.567695 115.2634)
		(end 152.720095 115.111)
		(width 0.2032)
		(layer "In2.Cu")
		(net "MAC_PPS_OUT-")
	)
	(segment
		(start 152.720095 115.111)
		(end 159.928755 115.111)
		(width 0.2032)
		(layer "In2.Cu")
		(net "MAC_PPS_OUT-")
	)
	(segment
		(start 146.774995 115.7206)
		(end 147.232195 115.2634)
		(width 0.2032)
		(layer "In2.Cu")
		(net "MAC_PPS_OUT-")
	)
	(segment
		(start 125.366985 115.7206)
		(end 146.774995 115.7206)
		(width 0.2032)
		(layer "In2.Cu")
		(net "MAC_PPS_OUT-")
	)
	(segment
		(start 125.210395 115.619)
		(end 125.265385 115.619)
		(width 0.2032)
		(layer "In2.Cu")
		(net "MAC_PPS_OUT-")
	)
	(segment
		(start 160.081155 114.9586)
		(end 161.735595 114.9586)
		(width 0.2032)
		(layer "In2.Cu")
		(net "MAC_PPS_OUT-")
	)
	(segment
		(start 125.496595 102.38902)
		(end 125.496595 98.44902)
		(width 0.2032)
		(layer "In3.Cu")
		(net "MAC_PPS_OUT-")
	)
	(segment
		(start 125.184995 102.70062)
		(end 125.496595 102.38902)
		(width 0.2032)
		(layer "In3.Cu")
		(net "MAC_PPS_OUT-")
	)
	(segment
		(start 125.159595 98.11202)
		(end 125.159595 98.0676)
		(width 0.2032)
		(layer "In3.Cu")
		(net "MAC_PPS_OUT-")
	)
	(segment
		(start 125.184995 115.5936)
		(end 125.184995 102.70062)
		(width 0.2032)
		(layer "In3.Cu")
		(net "MAC_PPS_OUT-")
	)
	(segment
		(start 125.159595 98.11202)
		(end 125.496595 98.44902)
		(width 0.2032)
		(layer "In3.Cu")
		(net "MAC_PPS_OUT-")
	)
	(segment
		(start 125.184995 115.5936)
		(end 125.210395 115.619)
		(width 0.2032)
		(layer "In3.Cu")
		(net "MAC_PPS_OUT-")
	)
	(segment
		(start 84.247935 117.2536)
		(end 84.288595 117.2536)
		(width 0.2032)
		(layer "F.Cu")
		(net "MAC_PPS_OUT+")
	)
	(segment
		(start 164.440595 116.1016)
		(end 178.573595 101.9686)
		(width 0.2032)
		(layer "F.Cu")
		(net "MAC_PPS_OUT+")
	)
	(segment
		(start 82.863595 116.3036)
		(end 82.863595 116.2036)
		(width 0.2032)
		(layer "F.Cu")
		(net "MAC_PPS_OUT+")
	)
	(segment
		(start 82.863595 116.3036)
		(end 83.474715 116.91472)
		(width 0.2032)
		(layer "F.Cu")
		(net "MAC_PPS_OUT+")
	)
	(segment
		(start 162.969165 115.88417)
		(end 163.163595 116.0786)
		(width 0.2032)
		(layer "F.Cu")
		(net "MAC_PPS_OUT+")
	)
	(segment
		(start 124.698075 100.66475)
		(end 124.698075 98.98605)
		(width 0.2032)
		(layer "F.Cu")
		(net "MAC_PPS_OUT+")
	)
	(segment
		(start 161.838695 115.88417)
		(end 162.969165 115.88417)
		(width 0.2032)
		(layer "F.Cu")
		(net "MAC_PPS_OUT+")
	)
	(segment
		(start 163.490595 116.0786)
		(end 163.513595 116.1016)
		(width 0.2032)
		(layer "F.Cu")
		(net "MAC_PPS_OUT+")
	)
	(segment
		(start 124.524595 98.81257)
		(end 124.524595 98.7026)
		(width 0.2032)
		(layer "F.Cu")
		(net "MAC_PPS_OUT+")
	)
	(segment
		(start 83.909055 116.91472)
		(end 84.247935 117.2536)
		(width 0.2032)
		(layer "F.Cu")
		(net "MAC_PPS_OUT+")
	)
	(segment
		(start 163.513595 116.1016)
		(end 164.440595 116.1016)
		(width 0.2032)
		(layer "F.Cu")
		(net "MAC_PPS_OUT+")
	)
	(segment
		(start 163.163595 116.0786)
		(end 163.490595 116.0786)
		(width 0.2032)
		(layer "F.Cu")
		(net "MAC_PPS_OUT+")
	)
	(segment
		(start 124.524595 98.81257)
		(end 124.698075 98.98605)
		(width 0.2032)
		(layer "F.Cu")
		(net "MAC_PPS_OUT+")
	)
	(segment
		(start 83.474715 116.91472)
		(end 83.909055 116.91472)
		(width 0.2032)
		(layer "F.Cu")
		(net "MAC_PPS_OUT+")
	)
	(via
		(at 163.513595 116.1016)
		(size 0.4064)
		(drill 0.2032)
		(layers "F.Cu" "B.Cu")
		(net "MAC_PPS_OUT+")
	)
	(via
		(at 124.651595 116.5334)
		(size 0.4064)
		(drill 0.2032)
		(layers "F.Cu" "B.Cu")
		(net "MAC_PPS_OUT+")
	)
	(via
		(at 84.288595 117.2536)
		(size 0.4064)
		(drill 0.2032)
		(layers "F.Cu" "B.Cu")
		(net "MAC_PPS_OUT+")
	)
	(via
		(at 124.524595 98.7026)
		(size 0.4064)
		(drill 0.2032)
		(layers "F.Cu" "B.Cu")
		(net "MAC_PPS_OUT+")
	)
	(segment
		(start 163.057895 116.508)
		(end 163.464295 116.1016)
		(width 0.2032)
		(layer "In2.Cu")
		(net "MAC_PPS_OUT+")
	)
	(segment
		(start 123.931395 117.2536)
		(end 124.651595 116.5334)
		(width 0.2032)
		(layer "In2.Cu")
		(net "MAC_PPS_OUT+")
	)
	(segment
		(start 149.392695 116.5334)
		(end 149.418095 116.508)
		(width 0.2032)
		(layer "In2.Cu")
		(net "MAC_PPS_OUT+")
	)
	(segment
		(start 124.651595 116.5334)
		(end 149.392695 116.5334)
		(width 0.2032)
		(layer "In2.Cu")
		(net "MAC_PPS_OUT+")
	)
	(segment
		(start 163.464295 116.1016)
		(end 163.513595 116.1016)
		(width 0.2032)
		(layer "In2.Cu")
		(net "MAC_PPS_OUT+")
	)
	(segment
		(start 149.418095 116.508)
		(end 163.057895 116.508)
		(width 0.2032)
		(layer "In2.Cu")
		(net "MAC_PPS_OUT+")
	)
	(segment
		(start 84.288595 117.2536)
		(end 123.931395 117.2536)
		(width 0.2032)
		(layer "In2.Cu")
		(net "MAC_PPS_OUT+")
	)
	(segment
		(start 124.480595 102.38902)
		(end 124.651595 102.56002)
		(width 0.2032)
		(layer "In3.Cu")
		(net "MAC_PPS_OUT+")
	)
	(segment
		(start 124.480595 102.38902)
		(end 124.480595 100.69083)
		(width 0.2032)
		(layer "In3.Cu")
		(net "MAC_PPS_OUT+")
	)
	(segment
		(start 124.651595 100.51982)
		(end 124.651595 98.82163)
		(width 0.2032)
		(layer "In3.Cu")
		(net "MAC_PPS_OUT+")
	)
	(segment
		(start 124.480595 100.69083)
		(end 124.651595 100.51982)
		(width 0.2032)
		(layer "In3.Cu")
		(net "MAC_PPS_OUT+")
	)
	(segment
		(start 124.651595 116.5334)
		(end 124.651595 102.56002)
		(width 0.2032)
		(layer "In3.Cu")
		(net "MAC_PPS_OUT+")
	)
	(segment
		(start 163.538995 119.9116)
		(end 164.656595 119.9116)
		(width 0.2032)
		(layer "F.Cu")
		(net "MAC_PPS_IN1-")
	)
	(segment
		(start 163.067565 119.44017)
		(end 163.538995 119.9116)
		(width 0.2032)
		(layer "F.Cu")
		(net "MAC_PPS_IN1-")
	)
	(segment
		(start 127.698075 102.22749)
		(end 127.750395 102.27981)
		(width 0.2032)
		(layer "F.Cu")
		(net "MAC_PPS_IN1-")
	)
	(segment
		(start 127.750395 102.3348)
		(end 127.750395 102.27981)
		(width 0.2032)
		(layer "F.Cu")
		(net "MAC_PPS_IN1-")
	)
	(segment
		(start 164.656595 119.9116)
		(end 164.656595 119.9116)
		(width 0.2032)
		(layer "F.Cu")
		(net "MAC_PPS_IN1-")
	)
	(segment
		(start 127.698075 102.22749)
		(end 127.698075 100.66475)
		(width 0.2032)
		(layer "F.Cu")
		(net "MAC_PPS_IN1-")
	)
	(segment
		(start 161.838695 119.44017)
		(end 163.067565 119.44017)
		(width 0.2032)
		(layer "F.Cu")
		(net "MAC_PPS_IN1-")
	)
	(via
		(at 127.572595 120.1656)
		(size 0.4064)
		(drill 0.2032)
		(layers "F.Cu" "B.Cu")
		(net "MAC_PPS_IN1-")
	)
	(via
		(at 164.656595 119.9116)
		(size 0.4064)
		(drill 0.2032)
		(layers "F.Cu" "B.Cu")
		(net "MAC_PPS_IN1-")
	)
	(via
		(at 127.750395 102.3348)
		(size 0.4064)
		(drill 0.2032)
		(layers "F.Cu" "B.Cu")
		(net "MAC_PPS_IN1-")
	)
	(segment
		(start 152.603705 119.7846)
		(end 158.893805 119.7846)
		(width 0.2032)
		(layer "In2.Cu")
		(net "MAC_PPS_IN1-")
	)
	(segment
		(start 127.572595 120.1656)
		(end 136.780095 120.1656)
		(width 0.2032)
		(layer "In2.Cu")
		(net "MAC_PPS_IN1-")
	)
	(segment
		(start 152.451305 119.937)
		(end 152.603705 119.7846)
		(width 0.2032)
		(layer "In2.Cu")
		(net "MAC_PPS_IN1-")
	)
	(segment
		(start 137.008695 119.937)
		(end 152.451305 119.937)
		(width 0.2032)
		(layer "In2.Cu")
		(net "MAC_PPS_IN1-")
	)
	(segment
		(start 159.057375 119.94817)
		(end 164.620025 119.94817)
		(width 0.2032)
		(layer "In2.Cu")
		(net "MAC_PPS_IN1-")
	)
	(segment
		(start 158.893805 119.7846)
		(end 159.057375 119.94817)
		(width 0.2032)
		(layer "In2.Cu")
		(net "MAC_PPS_IN1-")
	)
	(segment
		(start 164.620025 119.94817)
		(end 164.656595 119.9116)
		(width 0.2032)
		(layer "In2.Cu")
		(net "MAC_PPS_IN1-")
	)
	(segment
		(start 136.780095 120.1656)
		(end 137.008695 119.937)
		(width 0.2032)
		(layer "In2.Cu")
		(net "MAC_PPS_IN1-")
	)
	(segment
		(start 127.750395 119.94497)
		(end 127.750395 102.3348)
		(width 0.2032)
		(layer "In3.Cu")
		(net "MAC_PPS_IN1-")
	)
	(segment
		(start 127.572595 120.1656)
		(end 127.572595 120.12277)
		(width 0.2032)
		(layer "In3.Cu")
		(net "MAC_PPS_IN1-")
	)
	(segment
		(start 127.572595 120.12277)
		(end 127.750395 119.94497)
		(width 0.2032)
		(layer "In3.Cu")
		(net "MAC_PPS_IN1-")
	)
	(segment
		(start 161.758995 119.94817)
		(end 161.838695 119.94817)
		(width 0.2032)
		(layer "F.Cu")
		(net "MAC_PPS_IN1+")
	)
	(segment
		(start 127.216995 102.20361)
		(end 127.216995 101.66718)
		(width 0.2032)
		(layer "F.Cu")
		(net "MAC_PPS_IN1+")
	)
	(segment
		(start 161.735595 119.97157)
		(end 161.758995 119.94817)
		(width 0.2032)
		(layer "F.Cu")
		(net "MAC_PPS_IN1+")
	)
	(segment
		(start 127.198195 101.64838)
		(end 127.216995 101.66718)
		(width 0.2032)
		(layer "F.Cu")
		(net "MAC_PPS_IN1+")
	)
	(segment
		(start 161.735595 122.1976)
		(end 161.735595 119.97157)
		(width 0.2032)
		(layer "F.Cu")
		(net "MAC_PPS_IN1+")
	)
	(segment
		(start 127.198195 101.64838)
		(end 127.198195 100.66475)
		(width 0.2032)
		(layer "F.Cu")
		(net "MAC_PPS_IN1+")
	)
	(segment
		(start 127.140795 102.3348)
		(end 127.140795 102.27981)
		(width 0.2032)
		(layer "F.Cu")
		(net "MAC_PPS_IN1+")
	)
	(segment
		(start 127.140795 102.27981)
		(end 127.216995 102.20361)
		(width 0.2032)
		(layer "F.Cu")
		(net "MAC_PPS_IN1+")
	)
	(via
		(at 127.140795 102.4364)
		(size 0.4064)
		(drill 0.2032)
		(layers "F.Cu" "B.Cu")
		(net "MAC_PPS_IN1+")
	)
	(via
		(at 161.735595 122.1976)
		(size 0.4064)
		(drill 0.2032)
		(layers "F.Cu" "B.Cu")
		(net "MAC_PPS_IN1+")
	)
	(via
		(at 126.937595 122.9596)
		(size 0.4064)
		(drill 0.2032)
		(layers "F.Cu" "B.Cu")
		(net "MAC_PPS_IN1+")
	)
	(segment
		(start 149.542095 124.001)
		(end 159.932195 124.001)
		(width 0.2032)
		(layer "In2.Cu")
		(net "MAC_PPS_IN1+")
	)
	(segment
		(start 159.932195 124.001)
		(end 161.735595 122.1976)
		(width 0.2032)
		(layer "In2.Cu")
		(net "MAC_PPS_IN1+")
	)
	(segment
		(start 148.500695 122.9596)
		(end 149.542095 124.001)
		(width 0.2032)
		(layer "In2.Cu")
		(net "MAC_PPS_IN1+")
	)
	(segment
		(start 126.937595 122.9596)
		(end 148.500695 122.9596)
		(width 0.2032)
		(layer "In2.Cu")
		(net "MAC_PPS_IN1+")
	)
	(segment
		(start 126.937595 102.55543)
		(end 127.140795 102.35223)
		(width 0.2032)
		(layer "In3.Cu")
		(net "MAC_PPS_IN1+")
	)
	(segment
		(start 126.937595 122.9596)
		(end 126.937595 102.55543)
		(width 0.2032)
		(layer "In3.Cu")
		(net "MAC_PPS_IN1+")
	)
	(segment
		(start 127.140795 102.35223)
		(end 127.140795 102.3348)
		(width 0.2032)
		(layer "In3.Cu")
		(net "MAC_PPS_IN1+")
	)
	(segment
		(start 126.198205 102.19402)
		(end 126.198205 100.66475)
		(width 0.2032)
		(layer "F.Cu")
		(net "MAC_PPS_IN0-")
	)
	(segment
		(start 126.334795 102.3856)
		(end 126.334795 102.33061)
		(width 0.2032)
		(layer "F.Cu")
		(net "MAC_PPS_IN0-")
	)
	(segment
		(start 163.292965 118.42417)
		(end 163.510395 118.6416)
		(width 0.2032)
		(layer "F.Cu")
		(net "MAC_PPS_IN0-")
	)
	(segment
		(start 161.838695 118.42417)
		(end 163.292965 118.42417)
		(width 0.2032)
		(layer "F.Cu")
		(net "MAC_PPS_IN0-")
	)
	(segment
		(start 163.510395 118.6416)
		(end 163.513595 118.6416)
		(width 0.2032)
		(layer "F.Cu")
		(net "MAC_PPS_IN0-")
	)
	(segment
		(start 126.198205 102.19402)
		(end 126.334795 102.33061)
		(width 0.2032)
		(layer "F.Cu")
		(net "MAC_PPS_IN0-")
	)
	(via
		(at 126.334795 102.3856)
		(size 0.4064)
		(drill 0.2032)
		(layers "F.Cu" "B.Cu")
		(net "MAC_PPS_IN0-")
	)
	(via
		(at 126.226395 118.921)
		(size 0.4064)
		(drill 0.2032)
		(layers "F.Cu" "B.Cu")
		(net "MAC_PPS_IN0-")
	)
	(via
		(at 163.513595 118.6416)
		(size 0.4064)
		(drill 0.2032)
		(layers "F.Cu" "B.Cu")
		(net "MAC_PPS_IN0-")
	)
	(segment
		(start 126.251795 118.8956)
		(end 154.570835 118.8956)
		(width 0.2032)
		(layer "In2.Cu")
		(net "MAC_PPS_IN0-")
	)
	(segment
		(start 126.226395 118.921)
		(end 126.251795 118.8956)
		(width 0.2032)
		(layer "In2.Cu")
		(net "MAC_PPS_IN0-")
	)
	(segment
		(start 154.824835 118.6416)
		(end 163.513595 118.6416)
		(width 0.2032)
		(layer "In2.Cu")
		(net "MAC_PPS_IN0-")
	)
	(segment
		(start 154.570835 118.8956)
		(end 154.824835 118.6416)
		(width 0.2032)
		(layer "In2.Cu")
		(net "MAC_PPS_IN0-")
	)
	(segment
		(start 126.334795 102.44059)
		(end 126.334795 102.3856)
		(width 0.2032)
		(layer "In3.Cu")
		(net "MAC_PPS_IN0-")
	)
	(segment
		(start 126.226395 102.54898)
		(end 126.334795 102.44059)
		(width 0.2032)
		(layer "In3.Cu")
		(net "MAC_PPS_IN0-")
	)
	(segment
		(start 126.226395 118.921)
		(end 126.226395 102.54898)
		(width 0.2032)
		(layer "In3.Cu")
		(net "MAC_PPS_IN0-")
	)
	(segment
		(start 125.692995 102.17518)
		(end 125.698075 102.1701)
		(width 0.2032)
		(layer "F.Cu")
		(net "MAC_PPS_IN0+")
	)
	(segment
		(start 166.283625 119.33857)
		(end 183.653595 101.9686)
		(width 0.2032)
		(layer "F.Cu")
		(net "MAC_PPS_IN0+")
	)
	(segment
		(start 183.653595 101.9686)
		(end 183.653595 101.9686)
		(width 0.2032)
		(layer "F.Cu")
		(net "MAC_PPS_IN0+")
	)
	(segment
		(start 163.085745 118.93217)
		(end 163.303175 119.1496)
		(width 0.2032)
		(layer "F.Cu")
		(net "MAC_PPS_IN0+")
	)
	(segment
		(start 161.838695 118.93217)
		(end 163.085745 118.93217)
		(width 0.2032)
		(layer "F.Cu")
		(net "MAC_PPS_IN0+")
	)
	(segment
		(start 83.646395 103.23641)
		(end 83.769345 103.23641)
		(width 0.2032)
		(layer "F.Cu")
		(net "MAC_PPS_IN0+")
	)
	(segment
		(start 118.913595 87.1536)
		(end 119.138595 86.9286)
		(width 0.2032)
		(layer "F.Cu")
		(net "MAC_PPS_IN0+")
	)
	(segment
		(start 163.303175 119.1496)
		(end 163.711145 119.1496)
		(width 0.2032)
		(layer "F.Cu")
		(net "MAC_PPS_IN0+")
	)
	(segment
		(start 83.063595 102.6536)
		(end 83.646395 103.23641)
		(width 0.2032)
		(layer "F.Cu")
		(net "MAC_PPS_IN0+")
	)
	(segment
		(start 118.913595 89.7286)
		(end 120.704075 91.51909)
		(width 0.2032)
		(layer "F.Cu")
		(net "MAC_PPS_IN0+")
	)
	(segment
		(start 125.698075 102.1701)
		(end 125.698075 100.66475)
		(width 0.2032)
		(layer "F.Cu")
		(net "MAC_PPS_IN0+")
	)
	(segment
		(start 120.847765 91.5786)
		(end 126.679425 91.5786)
		(width 0.2032)
		(layer "F.Cu")
		(net "MAC_PPS_IN0+")
	)
	(segment
		(start 163.900115 119.33857)
		(end 166.283625 119.33857)
		(width 0.2032)
		(layer "F.Cu")
		(net "MAC_PPS_IN0+")
	)
	(segment
		(start 125.692995 102.91104)
		(end 125.692995 102.17518)
		(width 0.2032)
		(layer "F.Cu")
		(net "MAC_PPS_IN0+")
	)
	(segment
		(start 118.913595 89.7286)
		(end 118.913595 87.1536)
		(width 0.2032)
		(layer "F.Cu")
		(net "MAC_PPS_IN0+")
	)
	(segment
		(start 83.063595 102.6536)
		(end 83.063595 102.5536)
		(width 0.2032)
		(layer "F.Cu")
		(net "MAC_PPS_IN0+")
	)
	(segment
		(start 163.711145 119.1496)
		(end 163.900115 119.33857)
		(width 0.2032)
		(layer "F.Cu")
		(net "MAC_PPS_IN0+")
	)
	(segment
		(start 126.823115 91.51909)
		(end 126.888595 91.4536)
		(width 0.2032)
		(layer "F.Cu")
		(net "MAC_PPS_IN0+")
	)
	(segment
		(start 83.769345 103.23641)
		(end 83.808225 103.27529)
		(width 0.2032)
		(layer "F.Cu")
		(net "MAC_PPS_IN0+")
	)
	(via
		(at 126.888595 91.4536)
		(size 0.4064)
		(drill 0.2032)
		(layers "F.Cu" "B.Cu")
		(net "MAC_PPS_IN0+")
	)
	(via
		(at 83.808225 103.27529)
		(size 0.4064)
		(drill 0.2032)
		(layers "F.Cu" "B.Cu")
		(net "MAC_PPS_IN0+")
	)
	(via
		(at 125.692995 102.91104)
		(size 0.4064)
		(drill 0.2032)
		(layers "F.Cu" "B.Cu")
		(net "MAC_PPS_IN0+")
	)
	(via
		(at 163.931775 119.33857)
		(size 0.4064)
		(drill 0.2032)
		(layers "F.Cu" "B.Cu")
		(net "MAC_PPS_IN0+")
	)
	(via
		(at 125.642195 119.5306)
		(size 0.4064)
		(drill 0.2032)
		(layers "F.Cu" "B.Cu")
		(net "MAC_PPS_IN0+")
	)
	(arc
		(start 120.847765 91.5786)
		(mid 120.770004 91.563132)
		(end 120.704081 91.519084)
		(width 0.2032)
		(layer "F.Cu")
		(net "MAC_PPS_IN0+")
	)
	(arc
		(start 126.823112 91.519085)
		(mid 126.757188 91.563132)
		(end 126.679427 91.5786)
		(width 0.2032)
		(layer "F.Cu")
		(net "MAC_PPS_IN0+")
	)
	(segment
		(start 124.738595 103.4036)
		(end 125.285915 102.85628)
		(width 0.2032)
		(layer "In2.Cu")
		(net "MAC_PPS_IN0+")
	)
	(segment
		(start 122.738595 102.9036)
		(end 123.238595 103.4036)
		(width 0.2032)
		(layer "In2.Cu")
		(net "MAC_PPS_IN0+")
	)
	(segment
		(start 83.808225 103.27529)
		(end 102.487945 103.27529)
		(width 0.2032)
		(layer "In2.Cu")
		(net "MAC_PPS_IN0+")
	)
	(segment
		(start 102.665065 103.4524)
		(end 121.289795 103.4524)
		(width 0.2032)
		(layer "In2.Cu")
		(net "MAC_PPS_IN0+")
	)
	(segment
		(start 102.487945 103.27529)
		(end 102.665065 103.4524)
		(width 0.2032)
		(layer "In2.Cu")
		(net "MAC_PPS_IN0+")
	)
	(segment
		(start 146.617185 119.5306)
		(end 146.809215 119.33857)
		(width 0.2032)
		(layer "In2.Cu")
		(net "MAC_PPS_IN0+")
	)
	(segment
		(start 125.301795 102.87216)
		(end 125.654115 102.87216)
		(width 0.2032)
		(layer "In2.Cu")
		(net "MAC_PPS_IN0+")
	)
	(segment
		(start 125.654115 102.87216)
		(end 125.692995 102.91104)
		(width 0.2032)
		(layer "In2.Cu")
		(net "MAC_PPS_IN0+")
	)
	(segment
		(start 125.285915 102.85628)
		(end 125.301795 102.87216)
		(width 0.2032)
		(layer "In2.Cu")
		(net "MAC_PPS_IN0+")
	)
	(segment
		(start 146.809215 119.33857)
		(end 163.931775 119.33857)
		(width 0.2032)
		(layer "In2.Cu")
		(net "MAC_PPS_IN0+")
	)
	(segment
		(start 123.238595 103.4036)
		(end 124.738595 103.4036)
		(width 0.2032)
		(layer "In2.Cu")
		(net "MAC_PPS_IN0+")
	)
	(segment
		(start 121.838595 102.9036)
		(end 122.738595 102.9036)
		(width 0.2032)
		(layer "In2.Cu")
		(net "MAC_PPS_IN0+")
	)
	(segment
		(start 121.289795 103.4524)
		(end 121.838595 102.9036)
		(width 0.2032)
		(layer "In2.Cu")
		(net "MAC_PPS_IN0+")
	)
	(segment
		(start 125.642195 119.5306)
		(end 146.617185 119.5306)
		(width 0.2032)
		(layer "In2.Cu")
		(net "MAC_PPS_IN0+")
	)
	(segment
		(start 125.731875 102.99996)
		(end 125.731875 102.85628)
		(width 0.2032)
		(layer "In3.Cu")
		(net "MAC_PPS_IN0+")
	)
	(segment
		(start 125.513595 96.3036)
		(end 125.513595 92.8286)
		(width 0.2032)
		(layer "In3.Cu")
		(net "MAC_PPS_IN0+")
	)
	(segment
		(start 125.731875 102.62071)
		(end 125.826795 102.52579)
		(width 0.2032)
		(layer "In3.Cu")
		(net "MAC_PPS_IN0+")
	)
	(segment
		(start 125.642195 117.1176)
		(end 125.769195 116.9906)
		(width 0.2032)
		(layer "In3.Cu")
		(net "MAC_PPS_IN0+")
	)
	(segment
		(start 125.826795 100.0154)
		(end 126.188595 99.6536)
		(width 0.2032)
		(layer "In3.Cu")
		(net "MAC_PPS_IN0+")
	)
	(segment
		(start 125.731875 102.99996)
		(end 125.769195 103.03728)
		(width 0.2032)
		(layer "In3.Cu")
		(net "MAC_PPS_IN0+")
	)
	(segment
		(start 125.692995 102.91104)
		(end 125.731875 102.87216)
		(width 0.2032)
		(layer "In3.Cu")
		(net "MAC_PPS_IN0+")
	)
	(segment
		(start 125.513595 92.8286)
		(end 126.888595 91.4536)
		(width 0.2032)
		(layer "In3.Cu")
		(net "MAC_PPS_IN0+")
	)
	(segment
		(start 125.513595 96.3036)
		(end 126.188595 96.9786)
		(width 0.2032)
		(layer "In3.Cu")
		(net "MAC_PPS_IN0+")
	)
	(segment
		(start 125.642195 119.5306)
		(end 125.642195 117.1176)
		(width 0.2032)
		(layer "In3.Cu")
		(net "MAC_PPS_IN0+")
	)
	(segment
		(start 125.769195 116.9906)
		(end 125.769195 103.03728)
		(width 0.2032)
		(layer "In3.Cu")
		(net "MAC_PPS_IN0+")
	)
	(segment
		(start 125.731875 102.87216)
		(end 125.731875 102.62071)
		(width 0.2032)
		(layer "In3.Cu")
		(net "MAC_PPS_IN0+")
	)
	(segment
		(start 125.826795 102.52579)
		(end 125.826795 100.0154)
		(width 0.2032)
		(layer "In3.Cu")
		(net "MAC_PPS_IN0+")
	)
	(segment
		(start 126.188595 99.6536)
		(end 126.188595 96.9786)
		(width 0.2032)
		(layer "In3.Cu")
		(net "MAC_PPS_IN0+")
	)
	(segment
		(start 137.513595 79.6236)
		(end 137.516095 79.6261)
		(width 0.2032)
		(layer "F.Cu")
		(net "NetBT1_2")
	)
	(segment
		(start 183.188595 89.2536)
		(end 183.188595 89.2536)
		(width 0.2032)
		(layer "F.Cu")
		(net "NetBT1_2")
	)
	(segment
		(start 182.563605 89.7286)
		(end 182.638595 89.8036)
		(width 0.2032)
		(layer "F.Cu")
		(net "NetBT1_2")
	)
	(segment
		(start 180.263595 89.2536)
		(end 183.188595 89.2536)
		(width 0.2032)
		(layer "F.Cu")
		(net "NetBT1_2")
	)
	(segment
		(start 137.516095 79.6261)
		(end 139.486095 79.6261)
		(width 0.2032)
		(layer "F.Cu")
		(net "NetBT1_2")
	)
	(segment
		(start 180.263595 89.2536)
		(end 180.288595 89.2286)
		(width 0.2032)
		(layer "F.Cu")
		(net "NetBT1_2")
	)
	(segment
		(start 139.486095 79.6261)
		(end 139.488595 79.6286)
		(width 0.2032)
		(layer "F.Cu")
		(net "NetBT1_2")
	)
	(via
		(at 180.263595 89.2536)
		(size 0.4064)
		(drill 0.2032)
		(layers "F.Cu" "B.Cu")
		(net "NetBT1_2")
	)
	(via
		(at 139.488595 79.6286)
		(size 0.4064)
		(drill 0.2032)
		(layers "F.Cu" "B.Cu")
		(net "NetBT1_2")
	)
	(segment
		(start 146.588595 78.9036)
		(end 152.138595 84.4536)
		(width 0.2032)
		(layer "In2.Cu")
		(net "NetBT1_2")
	)
	(segment
		(start 141.313595 78.9036)
		(end 146.588595 78.9036)
		(width 0.2032)
		(layer "In2.Cu")
		(net "NetBT1_2")
	)
	(segment
		(start 152.138595 84.4536)
		(end 175.463595 84.4536)
		(width 0.2032)
		(layer "In2.Cu")
		(net "NetBT1_2")
	)
	(segment
		(start 139.488595 79.6286)
		(end 140.588595 79.6286)
		(width 0.2032)
		(layer "In2.Cu")
		(net "NetBT1_2")
	)
	(segment
		(start 140.588595 79.6286)
		(end 141.313595 78.9036)
		(width 0.2032)
		(layer "In2.Cu")
		(net "NetBT1_2")
	)
	(segment
		(start 175.463595 84.4536)
		(end 180.263595 89.2536)
		(width 0.2032)
		(layer "In2.Cu")
		(net "NetBT1_2")
	)
	(segment
		(start 183.253925 97.84393)
		(end 185.288595 99.8786)
		(width 0.2032)
		(layer "F.Cu")
		(net "MAC_BITE")
	)
	(segment
		(start 123.698075 99.52912)
		(end 123.914995 99.3122)
		(width 0.2032)
		(layer "F.Cu")
		(net "MAC_BITE")
	)
	(segment
		(start 183.653595 134.9886)
		(end 185.288595 133.3536)
		(width 0.2032)
		(layer "F.Cu")
		(net "MAC_BITE")
	)
	(segment
		(start 164.860705 97.84393)
		(end 183.253925 97.84393)
		(width 0.2032)
		(layer "F.Cu")
		(net "MAC_BITE")
	)
	(segment
		(start 185.288595 133.3536)
		(end 185.288595 99.8786)
		(width 0.2032)
		(layer "F.Cu")
		(net "MAC_BITE")
	)
	(segment
		(start 161.673665 94.65689)
		(end 164.860705 97.84393)
		(width 0.2032)
		(layer "F.Cu")
		(net "MAC_BITE")
	)
	(segment
		(start 123.698075 100.66475)
		(end 123.698075 99.52912)
		(width 0.2032)
		(layer "F.Cu")
		(net "MAC_BITE")
	)
	(via
		(at 161.100595 99.4646)
		(size 0.4064)
		(drill 0.2032)
		(layers "F.Cu" "B.Cu")
		(net "MAC_BITE")
	)
	(via
		(at 123.914995 99.3122)
		(size 0.4064)
		(drill 0.2032)
		(layers "F.Cu" "B.Cu")
		(net "MAC_BITE")
	)
	(segment
		(start 123.914995 99.3122)
		(end 124.024965 99.3122)
		(width 0.2032)
		(layer "In2.Cu")
		(net "MAC_BITE")
	)
	(segment
		(start 124.024965 99.3122)
		(end 124.177365 99.4646)
		(width 0.2032)
		(layer "In2.Cu")
		(net "MAC_BITE")
	)
	(segment
		(start 124.177365 99.4646)
		(end 161.100595 99.4646)
		(width 0.2032)
		(layer "In2.Cu")
		(net "MAC_BITE")
	)
	(segment
		(start 161.100595 99.4646)
		(end 161.673665 98.89153)
		(width 0.2032)
		(layer "In3.Cu")
		(net "MAC_BITE")
	)
	(segment
		(start 161.673665 98.89153)
		(end 161.673665 94.65689)
		(width 0.2032)
		(layer "In3.Cu")
		(net "MAC_BITE")
	)
	(segment
		(start 123.198205 101.82121)
		(end 124.016595 102.6396)
		(width 0.2032)
		(layer "F.Cu")
		(net "MAC_ALARM")
	)
	(segment
		(start 158.072795 115.0654)
		(end 158.687595 114.4506)
		(width 0.2032)
		(layer "F.Cu")
		(net "MAC_ALARM")
	)
	(segment
		(start 158.049395 115.37617)
		(end 158.072795 115.35277)
		(width 0.2032)
		(layer "F.Cu")
		(net "MAC_ALARM")
	)
	(segment
		(start 123.198205 101.82121)
		(end 123.198205 100.66475)
		(width 0.2032)
		(layer "F.Cu")
		(net "MAC_ALARM")
	)
	(segment
		(start 157.838695 115.37617)
		(end 158.049395 115.37617)
		(width 0.2032)
		(layer "F.Cu")
		(net "MAC_ALARM")
	)
	(segment
		(start 158.072795 115.35277)
		(end 158.072795 115.0654)
		(width 0.2032)
		(layer "F.Cu")
		(net "MAC_ALARM")
	)
	(via
		(at 124.016595 115.111)
		(size 0.4064)
		(drill 0.2032)
		(layers "F.Cu" "B.Cu")
		(net "MAC_ALARM")
	)
	(via
		(at 158.687595 114.4506)
		(size 0.4064)
		(drill 0.2032)
		(layers "F.Cu" "B.Cu")
		(net "MAC_ALARM")
	)
	(via
		(at 124.016595 102.6396)
		(size 0.4064)
		(drill 0.2032)
		(layers "F.Cu" "B.Cu")
		(net "MAC_ALARM")
	)
	(segment
		(start 124.016595 115.111)
		(end 125.420815 115.111)
		(width 0.2032)
		(layer "In2.Cu")
		(net "MAC_ALARM")
	)
	(segment
		(start 151.245935 114.4506)
		(end 158.687595 114.4506)
		(width 0.2032)
		(layer "In2.Cu")
		(net "MAC_ALARM")
	)
	(segment
		(start 125.700215 115.3904)
		(end 146.520995 115.3904)
		(width 0.2032)
		(layer "In2.Cu")
		(net "MAC_ALARM")
	)
	(segment
		(start 146.520995 115.3904)
		(end 147.054395 114.857)
		(width 0.2032)
		(layer "In2.Cu")
		(net "MAC_ALARM")
	)
	(segment
		(start 125.420815 115.111)
		(end 125.700215 115.3904)
		(width 0.2032)
		(layer "In2.Cu")
		(net "MAC_ALARM")
	)
	(segment
		(start 147.054395 114.857)
		(end 150.839535 114.857)
		(width 0.2032)
		(layer "In2.Cu")
		(net "MAC_ALARM")
	)
	(segment
		(start 150.839535 114.857)
		(end 151.245935 114.4506)
		(width 0.2032)
		(layer "In2.Cu")
		(net "MAC_ALARM")
	)
	(segment
		(start 124.016595 115.111)
		(end 124.016595 102.6396)
		(width 0.2032)
		(layer "In3.Cu")
		(net "MAC_ALARM")
	)
	(segment
		(start 221.313595 81.3036)
		(end 221.564595 81.0526)
		(width 0.2032)
		(layer "F.Cu")
		(net "IMU_PS1")
	)
	(segment
		(start 154.904345 121.5626)
		(end 158.179595 121.5626)
		(width 0.2032)
		(layer "F.Cu")
		(net "IMU_PS1")
	)
	(segment
		(start 218.631595 81.3036)
		(end 221.313595 81.3036)
		(width 0.2032)
		(layer "F.Cu")
		(net "IMU_PS1")
	)
	(segment
		(start 151.235745 121.05993)
		(end 154.401675 121.05993)
		(width 0.2032)
		(layer "F.Cu")
		(net "IMU_PS1")
	)
	(segment
		(start 158.179595 121.5626)
		(end 158.179595 121.5626)
		(width 0.2032)
		(layer "F.Cu")
		(net "IMU_PS1")
	)
	(segment
		(start 221.564595 81.0526)
		(end 221.564595 80.5681)
		(width 0.2032)
		(layer "F.Cu")
		(net "IMU_PS1")
	)
	(segment
		(start 154.401675 121.05993)
		(end 154.904345 121.5626)
		(width 0.2032)
		(layer "F.Cu")
		(net "IMU_PS1")
	)
	(via
		(at 158.560595 81.3036)
		(size 0.4064)
		(drill 0.2032)
		(layers "F.Cu" "B.Cu")
		(net "IMU_PS1")
	)
	(via
		(at 218.631595 81.3036)
		(size 0.4064)
		(drill 0.2032)
		(layers "F.Cu" "B.Cu")
		(net "IMU_PS1")
	)
	(via
		(at 158.179595 121.5626)
		(size 0.4064)
		(drill 0.2032)
		(layers "F.Cu" "B.Cu")
		(net "IMU_PS1")
	)
	(segment
		(start 218.424205 81.456)
		(end 218.576605 81.3036)
		(width 0.2032)
		(layer "In2.Cu")
		(net "IMU_PS1")
	)
	(segment
		(start 158.767975 81.456)
		(end 160.407795 81.456)
		(width 0.2032)
		(layer "In2.Cu")
		(net "IMU_PS1")
	)
	(segment
		(start 160.407795 81.456)
		(end 218.424205 81.456)
		(width 0.2032)
		(layer "In2.Cu")
		(net "IMU_PS1")
	)
	(segment
		(start 218.576605 81.3036)
		(end 218.631595 81.3036)
		(width 0.2032)
		(layer "In2.Cu")
		(net "IMU_PS1")
	)
	(segment
		(start 158.615585 81.3036)
		(end 158.767975 81.456)
		(width 0.2032)
		(layer "In2.Cu")
		(net "IMU_PS1")
	)
	(segment
		(start 158.560595 81.3036)
		(end 158.615585 81.3036)
		(width 0.2032)
		(layer "In2.Cu")
		(net "IMU_PS1")
	)
	(segment
		(start 160.407795 81.456)
		(end 160.407795 81.456)
		(width 0.2032)
		(layer "In2.Cu")
		(net "IMU_PS1")
	)
	(segment
		(start 158.077995 117.77456)
		(end 158.077995 81.7862)
		(width 0.2032)
		(layer "In3.Cu")
		(net "IMU_PS1")
	)
	(segment
		(start 158.077995 117.77456)
		(end 158.179595 117.87616)
		(width 0.2032)
		(layer "In3.Cu")
		(net "IMU_PS1")
	)
	(segment
		(start 158.179595 121.5626)
		(end 158.179595 117.87616)
		(width 0.2032)
		(layer "In3.Cu")
		(net "IMU_PS1")
	)
	(segment
		(start 158.077995 81.7862)
		(end 158.560595 81.3036)
		(width 0.2032)
		(layer "In3.Cu")
		(net "IMU_PS1")
	)
	(segment
		(start 154.717075 120.8006)
		(end 157.417595 120.8006)
		(width 0.2032)
		(layer "F.Cu")
		(net "IMU_PS0")
	)
	(segment
		(start 220.028725 80.5056)
		(end 220.752095 80.5056)
		(width 0.2032)
		(layer "F.Cu")
		(net "IMU_PS0")
	)
	(segment
		(start 154.476285 120.55981)
		(end 154.717075 120.8006)
		(width 0.2032)
		(layer "F.Cu")
		(net "IMU_PS0")
	)
	(segment
		(start 219.454985 80.60721)
		(end 219.927125 80.60721)
		(width 0.2032)
		(layer "F.Cu")
		(net "IMU_PS0")
	)
	(segment
		(start 219.419125 80.64307)
		(end 219.454985 80.60721)
		(width 0.2032)
		(layer "F.Cu")
		(net "IMU_PS0")
	)
	(segment
		(start 151.235745 120.55981)
		(end 154.476285 120.55981)
		(width 0.2032)
		(layer "F.Cu")
		(net "IMU_PS0")
	)
	(segment
		(start 219.927125 80.60721)
		(end 220.028725 80.5056)
		(width 0.2032)
		(layer "F.Cu")
		(net "IMU_PS0")
	)
	(via
		(at 157.417595 120.8006)
		(size 0.4064)
		(drill 0.2032)
		(layers "F.Cu" "B.Cu")
		(net "IMU_PS0")
	)
	(via
		(at 156.401595 80.5416)
		(size 0.4064)
		(drill 0.2032)
		(layers "F.Cu" "B.Cu")
		(net "IMU_PS0")
	)
	(via
		(at 219.419125 80.64307)
		(size 0.4064)
		(drill 0.2032)
		(layers "F.Cu" "B.Cu")
		(net "IMU_PS0")
	)
	(segment
		(start 219.380245 80.60419)
		(end 219.380245 80.45623)
		(width 0.2032)
		(layer "In2.Cu")
		(net "IMU_PS0")
	)
	(segment
		(start 161.626775 80.44)
		(end 161.626775 80.44)
		(width 0.2032)
		(layer "In2.Cu")
		(net "IMU_PS0")
	)
	(segment
		(start 219.380245 80.60419)
		(end 219.419125 80.64307)
		(width 0.2032)
		(layer "In2.Cu")
		(net "IMU_PS0")
	)
	(segment
		(start 156.558175 80.44)
		(end 161.626775 80.44)
		(width 0.2032)
		(layer "In2.Cu")
		(net "IMU_PS0")
	)
	(segment
		(start 156.401595 80.5416)
		(end 156.456585 80.5416)
		(width 0.2032)
		(layer "In2.Cu")
		(net "IMU_PS0")
	)
	(segment
		(start 156.456585 80.5416)
		(end 156.558175 80.44)
		(width 0.2032)
		(layer "In2.Cu")
		(net "IMU_PS0")
	)
	(segment
		(start 219.364005 80.44)
		(end 219.380245 80.45623)
		(width 0.2032)
		(layer "In2.Cu")
		(net "IMU_PS0")
	)
	(segment
		(start 161.626775 80.44)
		(end 219.364005 80.44)
		(width 0.2032)
		(layer "In2.Cu")
		(net "IMU_PS0")
	)
	(segment
		(start 157.417595 120.8006)
		(end 157.417595 101.80235)
		(width 0.2032)
		(layer "In3.Cu")
		(net "IMU_PS0")
	)
	(segment
		(start 156.033295 100.41805)
		(end 157.417595 101.80235)
		(width 0.2032)
		(layer "In3.Cu")
		(net "IMU_PS0")
	)
	(segment
		(start 156.401595 87.53083)
		(end 156.401595 80.5416)
		(width 0.2032)
		(layer "In3.Cu")
		(net "IMU_PS0")
	)
	(segment
		(start 156.033295 87.89913)
		(end 156.401595 87.53083)
		(width 0.2032)
		(layer "In3.Cu")
		(net "IMU_PS0")
	)
	(segment
		(start 156.033295 100.41805)
		(end 156.033295 87.89913)
		(width 0.2032)
		(layer "In3.Cu")
		(net "IMU_PS0")
	)
	(segment
		(start 217.565045 78.789)
		(end 217.620035 78.789)
		(width 0.2032)
		(layer "F.Cu")
		(net "IMU_NRST")
	)
	(segment
		(start 152.373565 119.05994)
		(end 152.615625 119.302)
		(width 0.2032)
		(layer "F.Cu")
		(net "IMU_NRST")
	)
	(segment
		(start 217.620035 78.789)
		(end 217.878835 78.5302)
		(width 0.2032)
		(layer "F.Cu")
		(net "IMU_NRST")
	)
	(segment
		(start 154.262145 119.302)
		(end 155.131595 118.43254)
		(width 0.2032)
		(layer "F.Cu")
		(net "IMU_NRST")
	)
	(segment
		(start 219.604015 78.1286)
		(end 219.727015 78.0056)
		(width 0.2032)
		(layer "F.Cu")
		(net "IMU_NRST")
	)
	(segment
		(start 151.235745 119.05994)
		(end 152.373565 119.05994)
		(width 0.2032)
		(layer "F.Cu")
		(net "IMU_NRST")
	)
	(segment
		(start 155.106195 117.6256)
		(end 155.131595 117.651)
		(width 0.2032)
		(layer "F.Cu")
		(net "IMU_NRST")
	)
	(segment
		(start 217.878835 78.5302)
		(end 218.168365 78.5302)
		(width 0.2032)
		(layer "F.Cu")
		(net "IMU_NRST")
	)
	(segment
		(start 218.569965 78.1286)
		(end 219.604015 78.1286)
		(width 0.2032)
		(layer "F.Cu")
		(net "IMU_NRST")
	)
	(segment
		(start 152.615625 119.302)
		(end 154.262145 119.302)
		(width 0.2032)
		(layer "F.Cu")
		(net "IMU_NRST")
	)
	(segment
		(start 155.131595 118.43254)
		(end 155.131595 117.651)
		(width 0.2032)
		(layer "F.Cu")
		(net "IMU_NRST")
	)
	(segment
		(start 218.168365 78.5302)
		(end 218.569965 78.1286)
		(width 0.2032)
		(layer "F.Cu")
		(net "IMU_NRST")
	)
	(segment
		(start 219.727015 78.0056)
		(end 220.752095 78.0056)
		(width 0.2032)
		(layer "F.Cu")
		(net "IMU_NRST")
	)
	(via
		(at 155.106195 117.6256)
		(size 0.4064)
		(drill 0.2032)
		(layers "F.Cu" "B.Cu")
		(net "IMU_NRST")
	)
	(via
		(at 217.565045 78.789)
		(size 0.4064)
		(drill 0.2032)
		(layers "F.Cu" "B.Cu")
		(net "IMU_NRST")
	)
	(via
		(at 155.182395 78.408)
		(size 0.4064)
		(drill 0.2032)
		(layers "F.Cu" "B.Cu")
		(net "IMU_NRST")
	)
	(segment
		(start 155.182395 78.408)
		(end 217.184045 78.408)
		(width 0.2032)
		(layer "In2.Cu")
		(net "IMU_NRST")
	)
	(segment
		(start 217.184045 78.408)
		(end 217.565045 78.789)
		(width 0.2032)
		(layer "In2.Cu")
		(net "IMU_NRST")
	)
	(segment
		(start 154.242595 78.916)
		(end 154.750595 78.408)
		(width 0.2032)
		(layer "In3.Cu")
		(net "IMU_NRST")
	)
	(segment
		(start 155.106195 117.6256)
		(end 155.106195 117.6002)
		(width 0.2032)
		(layer "In3.Cu")
		(net "IMU_NRST")
	)
	(segment
		(start 154.750595 78.408)
		(end 155.182395 78.408)
		(width 0.2032)
		(layer "In3.Cu")
		(net "IMU_NRST")
	)
	(segment
		(start 154.242595 116.7366)
		(end 154.242595 78.916)
		(width 0.2032)
		(layer "In3.Cu")
		(net "IMU_NRST")
	)
	(segment
		(start 154.242595 116.7366)
		(end 155.106195 117.6002)
		(width 0.2032)
		(layer "In3.Cu")
		(net "IMU_NRST")
	)
	(segment
		(start 151.235745 118.55981)
		(end 152.448175 118.55981)
		(width 0.2032)
		(layer "F.Cu")
		(net "IMU_INT")
	)
	(segment
		(start 219.432475 77.08472)
		(end 220.019275 76.49792)
		(width 0.2032)
		(layer "F.Cu")
		(net "IMU_INT")
	)
	(segment
		(start 220.744415 76.49792)
		(end 220.752095 76.5056)
		(width 0.2032)
		(layer "F.Cu")
		(net "IMU_INT")
	)
	(segment
		(start 219.432475 77.58172)
		(end 219.432475 77.08472)
		(width 0.2032)
		(layer "F.Cu")
		(net "IMU_INT")
	)
	(segment
		(start 152.783965 118.8956)
		(end 153.734595 118.8956)
		(width 0.2032)
		(layer "F.Cu")
		(net "IMU_INT")
	)
	(segment
		(start 219.393595 77.6206)
		(end 219.393595 77.52627)
		(width 0.2032)
		(layer "F.Cu")
		(net "IMU_INT")
	)
	(segment
		(start 152.448175 118.55981)
		(end 152.783965 118.8956)
		(width 0.2032)
		(layer "F.Cu")
		(net "IMU_INT")
	)
	(segment
		(start 153.734595 118.8956)
		(end 154.344725 118.28547)
		(width 0.2032)
		(layer "F.Cu")
		(net "IMU_INT")
	)
	(segment
		(start 219.393595 77.6206)
		(end 219.432475 77.58172)
		(width 0.2032)
		(layer "F.Cu")
		(net "IMU_INT")
	)
	(segment
		(start 154.344725 118.28547)
		(end 154.344725 118.25961)
		(width 0.2032)
		(layer "F.Cu")
		(net "IMU_INT")
	)
	(segment
		(start 220.019275 76.49792)
		(end 220.744415 76.49792)
		(width 0.2032)
		(layer "F.Cu")
		(net "IMU_INT")
	)
	(segment
		(start 220.539595 76.5056)
		(end 220.752095 76.5056)
		(width 0.2032)
		(layer "F.Cu")
		(net "IMU_INT")
	)
	(via
		(at 154.344725 118.25961)
		(size 0.4064)
		(drill 0.2032)
		(layers "F.Cu" "B.Cu")
		(net "IMU_INT")
	)
	(via
		(at 153.607595 77.7476)
		(size 0.4064)
		(drill 0.2032)
		(layers "F.Cu" "B.Cu")
		(net "IMU_INT")
	)
	(via
		(at 219.393595 77.6206)
		(size 0.4064)
		(drill 0.2032)
		(layers "F.Cu" "B.Cu")
		(net "IMU_INT")
	)
	(segment
		(start 153.662585 77.7476)
		(end 153.756585 77.6536)
		(width 0.2032)
		(layer "In2.Cu")
		(net "IMU_INT")
	)
	(segment
		(start 186.779995 77.6206)
		(end 219.393595 77.6206)
		(width 0.2032)
		(layer "In2.Cu")
		(net "IMU_INT")
	)
	(segment
		(start 153.756585 77.6536)
		(end 186.746995 77.6536)
		(width 0.2032)
		(layer "In2.Cu")
		(net "IMU_INT")
	)
	(segment
		(start 186.746995 77.6536)
		(end 186.779995 77.6206)
		(width 0.2032)
		(layer "In2.Cu")
		(net "IMU_INT")
	)
	(segment
		(start 153.607595 77.7476)
		(end 153.662585 77.7476)
		(width 0.2032)
		(layer "In2.Cu")
		(net "IMU_INT")
	)
	(segment
		(start 154.369595 118.23473)
		(end 154.369595 117.8796)
		(width 0.2032)
		(layer "In3.Cu")
		(net "IMU_INT")
	)
	(segment
		(start 154.344725 118.25961)
		(end 154.369595 118.23473)
		(width 0.2032)
		(layer "In3.Cu")
		(net "IMU_INT")
	)
	(segment
		(start 153.607595 117.1176)
		(end 154.369595 117.8796)
		(width 0.2032)
		(layer "In3.Cu")
		(net "IMU_INT")
	)
	(segment
		(start 153.607595 117.1176)
		(end 153.607595 77.7476)
		(width 0.2032)
		(layer "In3.Cu")
		(net "IMU_INT")
	)
	(segment
		(start 221.587995 76.386)
		(end 222.187595 76.9856)
		(width 0.2032)
		(layer "F.Cu")
		(net "IMU_ENV_SDA")
	)
	(segment
		(start 221.587995 76.386)
		(end 221.587995 75.9665)
		(width 0.2032)
		(layer "F.Cu")
		(net "IMU_ENV_SDA")
	)
	(segment
		(start 221.564595 75.9431)
		(end 221.587995 75.9665)
		(width 0.2032)
		(layer "F.Cu")
		(net "IMU_ENV_SDA")
	)
	(segment
		(start 103.613025 118.05892)
		(end 104.787275 118.05892)
		(width 0.2032)
		(layer "F.Cu")
		(net "IMU_ENV_SDA")
	)
	(via
		(at 104.787275 118.05892)
		(size 0.4064)
		(drill 0.2032)
		(layers "F.Cu" "B.Cu")
		(net "IMU_ENV_SDA")
	)
	(via
		(at 222.187595 76.9856)
		(size 0.4064)
		(drill 0.2032)
		(layers "F.Cu" "B.Cu")
		(net "IMU_ENV_SDA")
	)
	(via
		(at 153.678595 117.90702)
		(size 0.4064)
		(drill 0.2032)
		(layers "F.Cu" "B.Cu")
		(net "IMU_ENV_SDA")
	)
	(via
		(at 151.396595 76.84931)
		(size 0.4064)
		(drill 0.2032)
		(layers "F.Cu" "B.Cu")
		(net "IMU_ENV_SDA")
	)
	(segment
		(start 106.381775 118.2696)
		(end 139.656275 118.2696)
		(width 0.2032)
		(layer "In2.Cu")
		(net "IMU_ENV_SDA")
	)
	(segment
		(start 153.287195 117.5706)
		(end 153.623615 117.90702)
		(width 0.2032)
		(layer "In2.Cu")
		(net "IMU_ENV_SDA")
	)
	(segment
		(start 142.497645 117.89007)
		(end 145.601115 117.89007)
		(width 0.2032)
		(layer "In2.Cu")
		(net "IMU_ENV_SDA")
	)
	(segment
		(start 104.787275 118.05892)
		(end 106.171105 118.05892)
		(width 0.2032)
		(layer "In2.Cu")
		(net "IMU_ENV_SDA")
	)
	(segment
		(start 142.479955 117.87238)
		(end 142.497645 117.89007)
		(width 0.2032)
		(layer "In2.Cu")
		(net "IMU_ENV_SDA")
	)
	(segment
		(start 139.656275 118.2696)
		(end 140.053495 117.87238)
		(width 0.2032)
		(layer "In2.Cu")
		(net "IMU_ENV_SDA")
	)
	(segment
		(start 151.405885 76.8586)
		(end 221.895635 76.8586)
		(width 0.2032)
		(layer "In2.Cu")
		(net "IMU_ENV_SDA")
	)
	(segment
		(start 153.623615 117.90702)
		(end 153.678595 117.90702)
		(width 0.2032)
		(layer "In2.Cu")
		(net "IMU_ENV_SDA")
	)
	(segment
		(start 150.190015 117.5706)
		(end 153.287195 117.5706)
		(width 0.2032)
		(layer "In2.Cu")
		(net "IMU_ENV_SDA")
	)
	(segment
		(start 145.601115 117.89007)
		(end 145.636975 117.8542)
		(width 0.2032)
		(layer "In2.Cu")
		(net "IMU_ENV_SDA")
	)
	(segment
		(start 151.396595 76.84931)
		(end 151.405885 76.8586)
		(width 0.2032)
		(layer "In2.Cu")
		(net "IMU_ENV_SDA")
	)
	(segment
		(start 145.636975 117.8542)
		(end 149.906415 117.8542)
		(width 0.2032)
		(layer "In2.Cu")
		(net "IMU_ENV_SDA")
	)
	(segment
		(start 140.053495 117.87238)
		(end 142.479955 117.87238)
		(width 0.2032)
		(layer "In2.Cu")
		(net "IMU_ENV_SDA")
	)
	(segment
		(start 221.895635 76.8586)
		(end 222.022635 76.9856)
		(width 0.2032)
		(layer "In2.Cu")
		(net "IMU_ENV_SDA")
	)
	(segment
		(start 222.022635 76.9856)
		(end 222.187595 76.9856)
		(width 0.2032)
		(layer "In2.Cu")
		(net "IMU_ENV_SDA")
	)
	(segment
		(start 106.171105 118.05892)
		(end 106.381775 118.2696)
		(width 0.2032)
		(layer "In2.Cu")
		(net "IMU_ENV_SDA")
	)
	(segment
		(start 149.906415 117.8542)
		(end 150.190015 117.5706)
		(width 0.2032)
		(layer "In2.Cu")
		(net "IMU_ENV_SDA")
	)
	(segment
		(start 153.623615 117.90702)
		(end 153.678595 117.90702)
		(width 0.2032)
		(layer "In3.Cu")
		(net "IMU_ENV_SDA")
	)
	(segment
		(start 151.396595 76.84931)
		(end 152.363595 77.81631)
		(width 0.2032)
		(layer "In3.Cu")
		(net "IMU_ENV_SDA")
	)
	(segment
		(start 152.363595 117.19742)
		(end 152.736775 117.5706)
		(width 0.2032)
		(layer "In3.Cu")
		(net "IMU_ENV_SDA")
	)
	(segment
		(start 152.363595 117.19742)
		(end 152.363595 77.81631)
		(width 0.2032)
		(layer "In3.Cu")
		(net "IMU_ENV_SDA")
	)
	(segment
		(start 152.736775 117.5706)
		(end 153.287195 117.5706)
		(width 0.2032)
		(layer "In3.Cu")
		(net "IMU_ENV_SDA")
	)
	(segment
		(start 153.287195 117.5706)
		(end 153.623615 117.90702)
		(width 0.2032)
		(layer "In3.Cu")
		(net "IMU_ENV_SDA")
	)
	(segment
		(start 104.608205 119.55879)
		(end 106.067745 118.09925)
		(width 0.2032)
		(layer "F.Cu")
		(net "IMU_ENV_SCL")
	)
	(segment
		(start 106.549085 117.7616)
		(end 106.592195 117.7616)
		(width 0.2032)
		(layer "F.Cu")
		(net "IMU_ENV_SCL")
	)
	(segment
		(start 149.670595 117.1176)
		(end 149.713775 117.1176)
		(width 0.2032)
		(layer "F.Cu")
		(net "IMU_ENV_SCL")
	)
	(segment
		(start 219.937115 76.0056)
		(end 220.752095 76.0056)
		(width 0.2032)
		(layer "F.Cu")
		(net "IMU_ENV_SCL")
	)
	(segment
		(start 219.899205 75.96768)
		(end 219.937115 76.0056)
		(width 0.2032)
		(layer "F.Cu")
		(net "IMU_ENV_SCL")
	)
	(segment
		(start 106.211435 118.09925)
		(end 106.549085 117.7616)
		(width 0.2032)
		(layer "F.Cu")
		(net "IMU_ENV_SCL")
	)
	(segment
		(start 103.613025 119.55879)
		(end 104.608205 119.55879)
		(width 0.2032)
		(layer "F.Cu")
		(net "IMU_ENV_SCL")
	)
	(segment
		(start 106.067745 118.09925)
		(end 106.211435 118.09925)
		(width 0.2032)
		(layer "F.Cu")
		(net "IMU_ENV_SCL")
	)
	(via
		(at 149.670595 117.1176)
		(size 0.4064)
		(drill 0.2032)
		(layers "F.Cu" "B.Cu")
		(net "IMU_ENV_SCL")
	)
	(via
		(at 219.899205 75.96768)
		(size 0.4064)
		(drill 0.2032)
		(layers "F.Cu" "B.Cu")
		(net "IMU_ENV_SCL")
	)
	(via
		(at 106.592195 117.7616)
		(size 0.4064)
		(drill 0.2032)
		(layers "F.Cu" "B.Cu")
		(net "IMU_ENV_SCL")
	)
	(via
		(at 148.477365 76.2866)
		(size 0.4064)
		(drill 0.2032)
		(layers "F.Cu" "B.Cu")
		(net "IMU_ENV_SCL")
	)
	(segment
		(start 139.916725 117.54218)
		(end 142.616725 117.54218)
		(width 0.2032)
		(layer "In2.Cu")
		(net "IMU_ENV_SCL")
	)
	(segment
		(start 148.488995 76.27497)
		(end 219.591915 76.27497)
		(width 0.2032)
		(layer "In2.Cu")
		(net "IMU_ENV_SCL")
	)
	(segment
		(start 145.334415 117.55987)
		(end 145.776685 117.1176)
		(width 0.2032)
		(layer "In2.Cu")
		(net "IMU_ENV_SCL")
	)
	(segment
		(start 219.591915 76.27497)
		(end 219.899205 75.96768)
		(width 0.2032)
		(layer "In2.Cu")
		(net "IMU_ENV_SCL")
	)
	(segment
		(start 148.477365 76.2866)
		(end 148.488995 76.27497)
		(width 0.2032)
		(layer "In2.Cu")
		(net "IMU_ENV_SCL")
	)
	(segment
		(start 106.592195 117.7616)
		(end 139.697305 117.7616)
		(width 0.2032)
		(layer "In2.Cu")
		(net "IMU_ENV_SCL")
	)
	(segment
		(start 142.616725 117.54218)
		(end 142.634415 117.55987)
		(width 0.2032)
		(layer "In2.Cu")
		(net "IMU_ENV_SCL")
	)
	(segment
		(start 142.634415 117.55987)
		(end 145.334415 117.55987)
		(width 0.2032)
		(layer "In2.Cu")
		(net "IMU_ENV_SCL")
	)
	(segment
		(start 145.776685 117.1176)
		(end 149.670595 117.1176)
		(width 0.2032)
		(layer "In2.Cu")
		(net "IMU_ENV_SCL")
	)
	(segment
		(start 139.697305 117.7616)
		(end 139.916725 117.54218)
		(width 0.2032)
		(layer "In2.Cu")
		(net "IMU_ENV_SCL")
	)
	(segment
		(start 148.477365 99.21737)
		(end 150.051595 100.7916)
		(width 0.2032)
		(layer "In3.Cu")
		(net "IMU_ENV_SCL")
	)
	(segment
		(start 150.051595 107.4925)
		(end 150.051595 100.7916)
		(width 0.2032)
		(layer "In3.Cu")
		(net "IMU_ENV_SCL")
	)
	(segment
		(start 148.477365 99.21737)
		(end 148.477365 76.2866)
		(width 0.2032)
		(layer "In3.Cu")
		(net "IMU_ENV_SCL")
	)
	(segment
		(start 150.280195 116.508)
		(end 150.280195 107.7211)
		(width 0.2032)
		(layer "In3.Cu")
		(net "IMU_ENV_SCL")
	)
	(segment
		(start 149.670595 117.1176)
		(end 150.280195 116.508)
		(width 0.2032)
		(layer "In3.Cu")
		(net "IMU_ENV_SCL")
	)
	(segment
		(start 150.051595 107.4925)
		(end 150.280195 107.7211)
		(width 0.2032)
		(layer "In3.Cu")
		(net "IMU_ENV_SCL")
	)
	(segment
		(start 151.235745 123.05993)
		(end 151.259115 123.03656)
		(width 0.2032)
		(layer "F.Cu")
		(net "IMU_CLKSEL0")
	)
	(segment
		(start 218.696135 79.38512)
		(end 218.809655 79.2716)
		(width 0.2032)
		(layer "F.Cu")
		(net "IMU_CLKSEL0")
	)
	(segment
		(start 151.259115 123.03656)
		(end 155.816635 123.03656)
		(width 0.2032)
		(layer "F.Cu")
		(net "IMU_CLKSEL0")
	)
	(segment
		(start 218.809655 79.2716)
		(end 219.317895 79.2716)
		(width 0.2032)
		(layer "F.Cu")
		(net "IMU_CLKSEL0")
	)
	(segment
		(start 218.238925 79.38512)
		(end 218.696135 79.38512)
		(width 0.2032)
		(layer "F.Cu")
		(net "IMU_CLKSEL0")
	)
	(segment
		(start 220.083895 78.5056)
		(end 220.752095 78.5056)
		(width 0.2032)
		(layer "F.Cu")
		(net "IMU_CLKSEL0")
	)
	(segment
		(start 155.816635 123.03656)
		(end 155.893595 122.9596)
		(width 0.2032)
		(layer "F.Cu")
		(net "IMU_CLKSEL0")
	)
	(segment
		(start 218.200045 79.424)
		(end 218.238925 79.38512)
		(width 0.2032)
		(layer "F.Cu")
		(net "IMU_CLKSEL0")
	)
	(segment
		(start 219.317895 79.2716)
		(end 220.083895 78.5056)
		(width 0.2032)
		(layer "F.Cu")
		(net "IMU_CLKSEL0")
	)
	(via
		(at 155.004595 79.2716)
		(size 0.4064)
		(drill 0.2032)
		(layers "F.Cu" "B.Cu")
		(net "IMU_CLKSEL0")
	)
	(via
		(at 218.200045 79.424)
		(size 0.4064)
		(drill 0.2032)
		(layers "F.Cu" "B.Cu")
		(net "IMU_CLKSEL0")
	)
	(via
		(at 155.893595 122.9596)
		(size 0.4064)
		(drill 0.2032)
		(layers "F.Cu" "B.Cu")
		(net "IMU_CLKSEL0")
	)
	(segment
		(start 218.145065 79.424)
		(end 218.200045 79.424)
		(width 0.2032)
		(layer "In2.Cu")
		(net "IMU_CLKSEL0")
	)
	(segment
		(start 155.029995 79.297)
		(end 218.018065 79.297)
		(width 0.2032)
		(layer "In2.Cu")
		(net "IMU_CLKSEL0")
	)
	(segment
		(start 218.018065 79.297)
		(end 218.145065 79.424)
		(width 0.2032)
		(layer "In2.Cu")
		(net "IMU_CLKSEL0")
	)
	(segment
		(start 155.004595 79.2716)
		(end 155.029995 79.297)
		(width 0.2032)
		(layer "In2.Cu")
		(net "IMU_CLKSEL0")
	)
	(segment
		(start 155.893595 122.9596)
		(end 155.893595 101.61509)
		(width 0.2032)
		(layer "In3.Cu")
		(net "IMU_CLKSEL0")
	)
	(segment
		(start 155.004595 100.72609)
		(end 155.893595 101.61509)
		(width 0.2032)
		(layer "In3.Cu")
		(net "IMU_CLKSEL0")
	)
	(segment
		(start 155.004595 100.72609)
		(end 155.004595 79.2716)
		(width 0.2032)
		(layer "In3.Cu")
		(net "IMU_CLKSEL0")
	)
	(segment
		(start 151.235745 122.5598)
		(end 154.034575 122.5598)
		(width 0.2032)
		(layer "F.Cu")
		(net "IMU_BOOT")
	)
	(segment
		(start 222.060595 79.5256)
		(end 222.064595 79.5296)
		(width 0.2032)
		(layer "F.Cu")
		(net "IMU_BOOT")
	)
	(segment
		(start 154.396775 122.1976)
		(end 156.655595 122.1976)
		(width 0.2032)
		(layer "F.Cu")
		(net "IMU_BOOT")
	)
	(segment
		(start 222.064595 80.5681)
		(end 222.064595 79.5296)
		(width 0.2032)
		(layer "F.Cu")
		(net "IMU_BOOT")
	)
	(segment
		(start 154.034575 122.5598)
		(end 154.396775 122.1976)
		(width 0.2032)
		(layer "F.Cu")
		(net "IMU_BOOT")
	)
	(via
		(at 222.060595 79.5256)
		(size 0.4064)
		(drill 0.2032)
		(layers "F.Cu" "B.Cu")
		(net "IMU_BOOT")
	)
	(via
		(at 155.766595 79.9066)
		(size 0.4064)
		(drill 0.2032)
		(layers "F.Cu" "B.Cu")
		(net "IMU_BOOT")
	)
	(via
		(at 156.655595 122.1976)
		(size 0.4064)
		(drill 0.2032)
		(layers "F.Cu" "B.Cu")
		(net "IMU_BOOT")
	)
	(segment
		(start 155.766595 79.9066)
		(end 217.869595 79.9066)
		(width 0.2032)
		(layer "In2.Cu")
		(net "IMU_BOOT")
	)
	(segment
		(start 220.078135 79.932)
		(end 220.484535 79.5256)
		(width 0.2032)
		(layer "In2.Cu")
		(net "IMU_BOOT")
	)
	(segment
		(start 217.869595 79.9066)
		(end 217.894995 79.932)
		(width 0.2032)
		(layer "In2.Cu")
		(net "IMU_BOOT")
	)
	(segment
		(start 217.894995 79.932)
		(end 220.078135 79.932)
		(width 0.2032)
		(layer "In2.Cu")
		(net "IMU_BOOT")
	)
	(segment
		(start 220.484535 79.5256)
		(end 222.060595 79.5256)
		(width 0.2032)
		(layer "In2.Cu")
		(net "IMU_BOOT")
	)
	(segment
		(start 155.626895 87.7308)
		(end 155.766595 87.5911)
		(width 0.2032)
		(layer "In3.Cu")
		(net "IMU_BOOT")
	)
	(segment
		(start 156.655595 122.1976)
		(end 156.655595 101.61509)
		(width 0.2032)
		(layer "In3.Cu")
		(net "IMU_BOOT")
	)
	(segment
		(start 155.626895 100.58639)
		(end 156.655595 101.61509)
		(width 0.2032)
		(layer "In3.Cu")
		(net "IMU_BOOT")
	)
	(segment
		(start 155.766595 87.5911)
		(end 155.766595 79.9066)
		(width 0.2032)
		(layer "In3.Cu")
		(net "IMU_BOOT")
	)
	(segment
		(start 155.626895 100.58639)
		(end 155.626895 87.7308)
		(width 0.2032)
		(layer "In3.Cu")
		(net "IMU_BOOT")
	)
	(segment
		(start 92.688595 58.0286)
		(end 92.936995 57.7802)
		(width 0.2032)
		(layer "F.Cu")
		(net "NetJP1_3")
	)
	(segment
		(start 92.936995 57.7802)
		(end 95.341995 57.7802)
		(width 0.2032)
		(layer "F.Cu")
		(net "NetJP1_3")
	)
	(segment
		(start 95.341995 57.7802)
		(end 95.513595 57.6086)
		(width 0.2032)
		(layer "F.Cu")
		(net "NetJP1_3")
	)
	(segment
		(start 92.688595 58.0286)
		(end 92.688595 56.8786)
		(width 0.2032)
		(layer "F.Cu")
		(net "NetJP1_3")
	)
	(segment
		(start 152.853565 115.55982)
		(end 152.972595 115.67885)
		(width 0.2032)
		(layer "F.Cu")
		(net "GPS1_TP2")
	)
	(segment
		(start 122.111595 74.0646)
		(end 125.413595 74.0646)
		(width 0.2032)
		(layer "F.Cu")
		(net "GPS1_TP2")
	)
	(segment
		(start 152.972595 115.7206)
		(end 152.972595 115.67885)
		(width 0.2032)
		(layer "F.Cu")
		(net "GPS1_TP2")
	)
	(segment
		(start 151.235745 115.55982)
		(end 152.853565 115.55982)
		(width 0.2032)
		(layer "F.Cu")
		(net "GPS1_TP2")
	)
	(via
		(at 152.972595 115.7206)
		(size 0.4064)
		(drill 0.2032)
		(layers "F.Cu" "B.Cu")
		(net "GPS1_TP2")
	)
	(via
		(at 123.254595 116)
		(size 0.4064)
		(drill 0.2032)
		(layers "F.Cu" "B.Cu")
		(net "GPS1_TP2")
	)
	(via
		(at 125.413595 74.0646)
		(size 0.4064)
		(drill 0.2032)
		(layers "F.Cu" "B.Cu")
		(net "GPS1_TP2")
	)
	(segment
		(start 147.385135 115.7206)
		(end 152.972595 115.7206)
		(width 0.2032)
		(layer "In2.Cu")
		(net "GPS1_TP2")
	)
	(segment
		(start 123.254595 116)
		(end 124.836615 116)
		(width 0.2032)
		(layer "In2.Cu")
		(net "GPS1_TP2")
	)
	(segment
		(start 124.836615 116)
		(end 124.963615 116.127)
		(width 0.2032)
		(layer "In2.Cu")
		(net "GPS1_TP2")
	)
	(segment
		(start 146.978735 116.127)
		(end 147.385135 115.7206)
		(width 0.2032)
		(layer "In2.Cu")
		(net "GPS1_TP2")
	)
	(segment
		(start 124.963615 116.127)
		(end 146.978735 116.127)
		(width 0.2032)
		(layer "In2.Cu")
		(net "GPS1_TP2")
	)
	(segment
		(start 125.413595 74.0646)
		(end 126.738595 75.3896)
		(width 0.2032)
		(layer "In3.Cu")
		(net "GPS1_TP2")
	)
	(segment
		(start 123.254595 116)
		(end 123.254595 94.29677)
		(width 0.2032)
		(layer "In3.Cu")
		(net "GPS1_TP2")
	)
	(segment
		(start 126.738595 90.64443)
		(end 126.738595 75.3896)
		(width 0.2032)
		(layer "In3.Cu")
		(net "GPS1_TP2")
	)
	(segment
		(start 123.254595 94.29677)
		(end 123.254595 94.29677)
		(width 0.2032)
		(layer "In3.Cu")
		(net "GPS1_TP2")
	)
	(segment
		(start 123.314105 94.15308)
		(end 126.679085 90.78812)
		(width 0.2032)
		(layer "In3.Cu")
		(net "GPS1_TP2")
	)
	(arc
		(start 123.254595 94.29677)
		(mid 123.270062 94.219009)
		(end 123.31411 94.153087)
		(width 0.2032)
		(layer "In3.Cu")
		(net "GPS1_TP2")
	)
	(arc
		(start 126.738595 90.64443)
		(mid 126.723127 90.722192)
		(end 126.679078 90.788115)
		(width 0.2032)
		(layer "In3.Cu")
		(net "GPS1_TP2")
	)
	(segment
		(start 111.483595 58.6036)
		(end 113.138595 58.6036)
		(width 0.2032)
		(layer "F.Cu")
		(net "NetJP2_3")
	)
	(segment
		(start 113.138595 58.6036)
		(end 114.638595 58.6036)
		(width 0.2032)
		(layer "F.Cu")
		(net "NetJP2_3")
	)
	(segment
		(start 110.388595 57.5086)
		(end 111.483595 58.6036)
		(width 0.2032)
		(layer "F.Cu")
		(net "NetJP2_3")
	)
	(segment
		(start 136.478985 74.38821)
		(end 136.488595 74.3786)
		(width 0.2032)
		(layer "F.Cu")
		(net "RTC_MFP")
	)
	(segment
		(start 103.613025 114.5588)
		(end 106.239015 114.5588)
		(width 0.2032)
		(layer "F.Cu")
		(net "RTC_MFP")
	)
	(segment
		(start 130.643595 79.6236)
		(end 135.878985 74.38821)
		(width 0.2032)
		(layer "F.Cu")
		(net "RTC_MFP")
	)
	(segment
		(start 106.239015 114.5588)
		(end 106.308605 114.6284)
		(width 0.2032)
		(layer "F.Cu")
		(net "RTC_MFP")
	)
	(segment
		(start 128.513595 79.6236)
		(end 130.643595 79.6236)
		(width 0.2032)
		(layer "F.Cu")
		(net "RTC_MFP")
	)
	(segment
		(start 135.878985 74.38821)
		(end 136.478985 74.38821)
		(width 0.2032)
		(layer "F.Cu")
		(net "RTC_MFP")
	)
	(via
		(at 136.133395 114.5588)
		(size 0.4064)
		(drill 0.2032)
		(layers "F.Cu" "B.Cu")
		(net "RTC_MFP")
	)
	(via
		(at 136.488595 74.3786)
		(size 0.4064)
		(drill 0.2032)
		(layers "F.Cu" "B.Cu")
		(net "RTC_MFP")
	)
	(via
		(at 106.239015 114.5588)
		(size 0.4064)
		(drill 0.2032)
		(layers "F.Cu" "B.Cu")
		(net "RTC_MFP")
	)
	(segment
		(start 106.239015 114.5588)
		(end 136.133395 114.5588)
		(width 0.2032)
		(layer "In2.Cu")
		(net "RTC_MFP")
	)
	(segment
		(start 136.488595 74.3786)
		(end 136.527475 74.41748)
		(width 0.2032)
		(layer "In3.Cu")
		(net "RTC_MFP")
	)
	(segment
		(start 136.133395 104.0338)
		(end 136.538595 103.6286)
		(width 0.2032)
		(layer "In3.Cu")
		(net "RTC_MFP")
	)
	(segment
		(start 136.538595 103.6286)
		(end 136.538595 74.57228)
		(width 0.2032)
		(layer "In3.Cu")
		(net "RTC_MFP")
	)
	(segment
		(start 136.527475 74.56116)
		(end 136.538595 74.57228)
		(width 0.2032)
		(layer "In3.Cu")
		(net "RTC_MFP")
	)
	(segment
		(start 136.527475 74.56116)
		(end 136.527475 74.41748)
		(width 0.2032)
		(layer "In3.Cu")
		(net "RTC_MFP")
	)
	(segment
		(start 136.133395 114.5588)
		(end 136.133395 104.0338)
		(width 0.2032)
		(layer "In3.Cu")
		(net "RTC_MFP")
	)
	(segment
		(start 151.228635 112.55271)
		(end 151.235745 112.55982)
		(width 0.2032)
		(layer "F.Cu")
		(net "GPS1_RST")
	)
	(segment
		(start 116.001195 70.523)
		(end 117.208195 70.523)
		(width 0.2032)
		(layer "F.Cu")
		(net "GPS1_RST")
	)
	(segment
		(start 148.788705 112.55271)
		(end 151.228635 112.55271)
		(width 0.2032)
		(layer "F.Cu")
		(net "GPS1_RST")
	)
	(segment
		(start 117.208195 70.523)
		(end 117.666595 70.0646)
		(width 0.2032)
		(layer "F.Cu")
		(net "GPS1_RST")
	)
	(segment
		(start 148.781595 112.5456)
		(end 148.788705 112.55271)
		(width 0.2032)
		(layer "F.Cu")
		(net "GPS1_RST")
	)
	(segment
		(start 115.761595 70.7626)
		(end 116.001195 70.523)
		(width 0.2032)
		(layer "F.Cu")
		(net "GPS1_RST")
	)
	(via
		(at 148.781595 112.5456)
		(size 0.4064)
		(drill 0.2032)
		(layers "F.Cu" "B.Cu")
		(net "GPS1_RST")
	)
	(via
		(at 115.761595 70.7626)
		(size 0.4064)
		(drill 0.2032)
		(layers "F.Cu" "B.Cu")
		(net "GPS1_RST")
	)
	(via
		(at 116.904595 111.9106)
		(size 0.4064)
		(drill 0.2032)
		(layers "F.Cu" "B.Cu")
		(net "GPS1_RST")
	)
	(segment
		(start 145.967895 112.317)
		(end 146.196495 112.5456)
		(width 0.2032)
		(layer "In2.Cu")
		(net "GPS1_RST")
	)
	(segment
		(start 116.904595 111.9106)
		(end 143.184875 111.9106)
		(width 0.2032)
		(layer "In2.Cu")
		(net "GPS1_RST")
	)
	(segment
		(start 146.196495 112.5456)
		(end 148.781595 112.5456)
		(width 0.2032)
		(layer "In2.Cu")
		(net "GPS1_RST")
	)
	(segment
		(start 143.184875 111.9106)
		(end 143.591275 112.317)
		(width 0.2032)
		(layer "In2.Cu")
		(net "GPS1_RST")
	)
	(segment
		(start 143.591275 112.317)
		(end 145.967895 112.317)
		(width 0.2032)
		(layer "In2.Cu")
		(net "GPS1_RST")
	)
	(segment
		(start 116.904595 111.9106)
		(end 116.904595 71.9056)
		(width 0.2032)
		(layer "In3.Cu")
		(net "GPS1_RST")
	)
	(segment
		(start 115.761595 70.7626)
		(end 116.904595 71.9056)
		(width 0.2032)
		(layer "In3.Cu")
		(net "GPS1_RST")
	)
	(segment
		(start 92.663595 55.3536)
		(end 92.663595 54.5286)
		(width 0.2032)
		(layer "F.Cu")
		(net "GPS2_TX")
	)
	(segment
		(start 98.313595 127.3036)
		(end 98.558285 127.05891)
		(width 0.2032)
		(layer "F.Cu")
		(net "GPS2_TX")
	)
	(segment
		(start 98.558285 127.05891)
		(end 99.563255 127.05891)
		(width 0.2032)
		(layer "F.Cu")
		(net "GPS2_TX")
	)
	(segment
		(start 92.663595 55.3536)
		(end 92.688595 55.3786)
		(width 0.2032)
		(layer "F.Cu")
		(net "GPS2_TX")
	)
	(segment
		(start 98.313595 127.9286)
		(end 98.313595 127.3036)
		(width 0.2032)
		(layer "F.Cu")
		(net "GPS2_TX")
	)
	(via
		(at 114.542395 127.6078)
		(size 0.4064)
		(drill 0.2032)
		(layers "F.Cu" "B.Cu")
		(net "GPS2_TX")
	)
	(via
		(at 98.313595 127.9286)
		(size 0.4064)
		(drill 0.2032)
		(layers "F.Cu" "B.Cu")
		(net "GPS2_TX")
	)
	(via
		(at 114.516995 79.297)
		(size 0.4064)
		(drill 0.2032)
		(layers "F.Cu" "B.Cu")
		(net "GPS2_TX")
	)
	(via
		(at 92.663595 54.5286)
		(size 0.4064)
		(drill 0.2032)
		(layers "F.Cu" "B.Cu")
		(net "GPS2_TX")
	)
	(via
		(at 124.321395 79.6486)
		(size 0.4064)
		(drill 0.2032)
		(layers "F.Cu" "B.Cu")
		(net "GPS2_TX")
	)
	(segment
		(start 122.238595 81.2904)
		(end 122.731095 81.2904)
		(width 0.2032)
		(layer "B.Cu")
		(net "GPS2_TX")
	)
	(segment
		(start 124.282515 79.60972)
		(end 124.321395 79.6486)
		(width 0.2032)
		(layer "B.Cu")
		(net "GPS2_TX")
	)
	(segment
		(start 124.321395 79.7001)
		(end 124.321395 79.6486)
		(width 0.2032)
		(layer "B.Cu")
		(net "GPS2_TX")
	)
	(segment
		(start 122.731095 81.2904)
		(end 124.321395 79.7001)
		(width 0.2032)
		(layer "B.Cu")
		(net "GPS2_TX")
	)
	(segment
		(start 98.421595 128.0366)
		(end 114.113595 128.0366)
		(width 0.2032)
		(layer "In2.Cu")
		(net "GPS2_TX")
	)
	(segment
		(start 119.742175 79.9574)
		(end 120.163015 79.9574)
		(width 0.2032)
		(layer "In2.Cu")
		(net "GPS2_TX")
	)
	(segment
		(start 120.823415 79.297)
		(end 123.954575 79.297)
		(width 0.2032)
		(layer "In2.Cu")
		(net "GPS2_TX")
	)
	(segment
		(start 98.313595 127.9286)
		(end 98.421595 128.0366)
		(width 0.2032)
		(layer "In2.Cu")
		(net "GPS2_TX")
	)
	(segment
		(start 114.516995 79.297)
		(end 119.081775 79.297)
		(width 0.2032)
		(layer "In2.Cu")
		(net "GPS2_TX")
	)
	(segment
		(start 120.163015 79.9574)
		(end 120.823415 79.297)
		(width 0.2032)
		(layer "In2.Cu")
		(net "GPS2_TX")
	)
	(segment
		(start 124.306175 79.6486)
		(end 124.321395 79.6486)
		(width 0.2032)
		(layer "In2.Cu")
		(net "GPS2_TX")
	)
	(segment
		(start 114.113595 128.0366)
		(end 114.542395 127.6078)
		(width 0.2032)
		(layer "In2.Cu")
		(net "GPS2_TX")
	)
	(segment
		(start 119.081775 79.297)
		(end 119.742175 79.9574)
		(width 0.2032)
		(layer "In2.Cu")
		(net "GPS2_TX")
	)
	(segment
		(start 123.954575 79.297)
		(end 124.306175 79.6486)
		(width 0.2032)
		(layer "In2.Cu")
		(net "GPS2_TX")
	)
	(segment
		(start 114.575775 99.59142)
		(end 114.991375 99.17582)
		(width 0.2032)
		(layer "In3.Cu")
		(net "GPS2_TX")
	)
	(segment
		(start 114.516995 79.297)
		(end 114.516995 55.307)
		(width 0.2032)
		(layer "In3.Cu")
		(net "GPS2_TX")
	)
	(segment
		(start 108.063595 53.7286)
		(end 112.938595 53.7286)
		(width 0.2032)
		(layer "In3.Cu")
		(net "GPS2_TX")
	)
	(segment
		(start 114.576165 97.92969)
		(end 114.951075 98.30459)
		(width 0.2032)
		(layer "In3.Cu")
		(net "GPS2_TX")
	)
	(segment
		(start 98.788595 50.9786)
		(end 99.763595 51.9536)
		(width 0.2032)
		(layer "In3.Cu")
		(net "GPS2_TX")
	)
	(segment
		(start 99.763595 51.9536)
		(end 106.288595 51.9536)
		(width 0.2032)
		(layer "In3.Cu")
		(net "GPS2_TX")
	)
	(segment
		(start 114.516995 97.78634)
		(end 114.516995 79.297)
		(width 0.2032)
		(layer "In3.Cu")
		(net "GPS2_TX")
	)
	(segment
		(start 115.050885 99.03214)
		(end 115.050895 98.48857)
		(width 0.2032)
		(layer "In3.Cu")
		(net "GPS2_TX")
	)
	(segment
		(start 106.288595 51.9536)
		(end 108.063595 53.7286)
		(width 0.2032)
		(layer "In3.Cu")
		(net "GPS2_TX")
	)
	(segment
		(start 112.938595 53.7286)
		(end 114.516995 55.307)
		(width 0.2032)
		(layer "In3.Cu")
		(net "GPS2_TX")
	)
	(segment
		(start 114.951075 98.30459)
		(end 114.991545 98.34507)
		(width 0.2032)
		(layer "In3.Cu")
		(net "GPS2_TX")
	)
	(segment
		(start 93.888595 50.9786)
		(end 98.788595 50.9786)
		(width 0.2032)
		(layer "In3.Cu")
		(net "GPS2_TX")
	)
	(segment
		(start 114.516995 127.5824)
		(end 114.542395 127.6078)
		(width 0.2032)
		(layer "In3.Cu")
		(net "GPS2_TX")
	)
	(segment
		(start 92.663595 54.5286)
		(end 92.663595 52.2036)
		(width 0.2032)
		(layer "In3.Cu")
		(net "GPS2_TX")
	)
	(segment
		(start 114.516995 127.5824)
		(end 114.516995 99.73335)
		(width 0.2032)
		(layer "In3.Cu")
		(net "GPS2_TX")
	)
	(segment
		(start 92.663595 52.2036)
		(end 93.888595 50.9786)
		(width 0.2032)
		(layer "In3.Cu")
		(net "GPS2_TX")
	)
	(arc
		(start 115.050895 99.032133)
		(mid 115.035426 99.109896)
		(end 114.991377 99.17582)
		(width 0.2032)
		(layer "In3.Cu")
		(net "GPS2_TX")
	)
	(arc
		(start 114.576169 97.929685)
		(mid 114.532371 97.86388)
		(end 114.516995 97.786342)
		(width 0.2032)
		(layer "In3.Cu")
		(net "GPS2_TX")
	)
	(arc
		(start 114.516998 99.733354)
		(mid 114.532457 99.656623)
		(end 114.575773 99.591429)
		(width 0.2032)
		(layer "In3.Cu")
		(net "GPS2_TX")
	)
	(arc
		(start 114.991554 98.345061)
		(mid 115.035475 98.410923)
		(end 115.050895 98.48857)
		(width 0.2032)
		(layer "In3.Cu")
		(net "GPS2_TX")
	)
	(segment
		(start 141.613905 118.55981)
		(end 147.185965 118.55981)
		(width 0.2032)
		(layer "F.Cu")
		(net "GPS2_TP2")
	)
	(segment
		(start 141.441695 118.3876)
		(end 141.613905 118.55981)
		(width 0.2032)
		(layer "F.Cu")
		(net "GPS2_TP2")
	)
	(segment
		(start 141.110795 118.3876)
		(end 141.441695 118.3876)
		(width 0.2032)
		(layer "F.Cu")
		(net "GPS2_TP2")
	)
	(via
		(at 141.386505 76.65909)
		(size 0.4064)
		(drill 0.2032)
		(layers "F.Cu" "B.Cu")
		(net "GPS2_TP2")
	)
	(via
		(at 141.110795 118.3876)
		(size 0.4064)
		(drill 0.2032)
		(layers "F.Cu" "B.Cu")
		(net "GPS2_TP2")
	)
	(via
		(at 124.295995 77.0618)
		(size 0.4064)
		(drill 0.2032)
		(layers "F.Cu" "B.Cu")
		(net "GPS2_TP2")
	)
	(segment
		(start 122.238595 77.2904)
		(end 124.118195 77.2904)
		(width 0.2032)
		(layer "B.Cu")
		(net "GPS2_TP2")
	)
	(segment
		(start 124.270595 77.0872)
		(end 124.295995 77.0618)
		(width 0.2032)
		(layer "B.Cu")
		(net "GPS2_TP2")
	)
	(segment
		(start 124.118195 77.2904)
		(end 124.270595 77.138)
		(width 0.2032)
		(layer "B.Cu")
		(net "GPS2_TP2")
	)
	(segment
		(start 124.270595 77.138)
		(end 124.270595 77.0872)
		(width 0.2032)
		(layer "B.Cu")
		(net "GPS2_TP2")
	)
	(segment
		(start 141.110795 76.9348)
		(end 141.386505 76.65909)
		(width 0.2032)
		(layer "In2.Cu")
		(net "GPS2_TP2")
	)
	(segment
		(start 124.295995 77.0618)
		(end 124.350985 77.0618)
		(width 0.2032)
		(layer "In2.Cu")
		(net "GPS2_TP2")
	)
	(segment
		(start 124.350985 77.0618)
		(end 124.477985 76.9348)
		(width 0.2032)
		(layer "In2.Cu")
		(net "GPS2_TP2")
	)
	(segment
		(start 124.477985 76.9348)
		(end 141.110795 76.9348)
		(width 0.2032)
		(layer "In2.Cu")
		(net "GPS2_TP2")
	)
	(segment
		(start 141.110795 118.3876)
		(end 141.110795 76.9348)
		(width 0.2032)
		(layer "In3.Cu")
		(net "GPS2_TP2")
	)
	(segment
		(start 141.110795 76.9348)
		(end 141.386505 76.65909)
		(width 0.2032)
		(layer "In3.Cu")
		(net "GPS2_TP2")
	)
	(segment
		(start 140.399595 118.38038)
		(end 140.900375 117.8796)
		(width 0.2032)
		(layer "F.Cu")
		(net "GPS2_TP1")
	)
	(segment
		(start 140.900375 117.8796)
		(end 141.589595 117.8796)
		(width 0.2032)
		(layer "F.Cu")
		(net "GPS2_TP1")
	)
	(segment
		(start 141.769935 118.05994)
		(end 147.185965 118.05994)
		(width 0.2032)
		(layer "F.Cu")
		(net "GPS2_TP1")
	)
	(segment
		(start 141.589595 117.8796)
		(end 141.769935 118.05994)
		(width 0.2032)
		(layer "F.Cu")
		(net "GPS2_TP1")
	)
	(via
		(at 140.551995 78.408)
		(size 0.4064)
		(drill 0.2032)
		(layers "F.Cu" "B.Cu")
		(net "GPS2_TP1")
	)
	(via
		(at 140.399595 118.38038)
		(size 0.4064)
		(drill 0.2032)
		(layers "F.Cu" "B.Cu")
		(net "GPS2_TP1")
	)
	(via
		(at 119.805595 79.3024)
		(size 0.4064)
		(drill 0.2032)
		(layers "F.Cu" "B.Cu")
		(net "GPS2_TP1")
	)
	(segment
		(start 117.805595 79.3024)
		(end 119.805595 79.3024)
		(width 0.2032)
		(layer "B.Cu")
		(net "GPS2_TP1")
	)
	(segment
		(start 117.793595 79.2904)
		(end 117.805595 79.3024)
		(width 0.2032)
		(layer "B.Cu")
		(net "GPS2_TP1")
	)
	(segment
		(start 119.860585 79.3024)
		(end 120.187775 78.9752)
		(width 0.2032)
		(layer "In2.Cu")
		(net "GPS2_TP1")
	)
	(segment
		(start 120.993995 78.408)
		(end 126.571325 78.408)
		(width 0.2032)
		(layer "In2.Cu")
		(net "GPS2_TP1")
	)
	(segment
		(start 119.805595 79.3024)
		(end 119.860585 79.3024)
		(width 0.2032)
		(layer "In2.Cu")
		(net "GPS2_TP1")
	)
	(segment
		(start 134.615085 78.408)
		(end 140.551995 78.408)
		(width 0.2032)
		(layer "In2.Cu")
		(net "GPS2_TP1")
	)
	(segment
		(start 127.142825 77.8365)
		(end 134.043585 77.8365)
		(width 0.2032)
		(layer "In2.Cu")
		(net "GPS2_TP1")
	)
	(segment
		(start 134.043585 77.8365)
		(end 134.615085 78.408)
		(width 0.2032)
		(layer "In2.Cu")
		(net "GPS2_TP1")
	)
	(segment
		(start 120.187775 78.9752)
		(end 120.426795 78.9752)
		(width 0.2032)
		(layer "In2.Cu")
		(net "GPS2_TP1")
	)
	(segment
		(start 126.571325 78.408)
		(end 127.142825 77.8365)
		(width 0.2032)
		(layer "In2.Cu")
		(net "GPS2_TP1")
	)
	(segment
		(start 120.426795 78.9752)
		(end 120.993995 78.408)
		(width 0.2032)
		(layer "In2.Cu")
		(net "GPS2_TP1")
	)
	(segment
		(start 140.399595 118.38038)
		(end 140.399595 78.5604)
		(width 0.2032)
		(layer "In3.Cu")
		(net "GPS2_TP1")
	)
	(segment
		(start 140.399595 78.5604)
		(end 140.551995 78.408)
		(width 0.2032)
		(layer "In3.Cu")
		(net "GPS2_TP1")
	)
	(segment
		(start 113.038595 57.0786)
		(end 113.138595 57.0786)
		(width 0.2032)
		(layer "F.Cu")
		(net "GPS2_RX")
	)
	(segment
		(start 103.613025 127.05891)
		(end 104.140225 127.05891)
		(width 0.2032)
		(layer "F.Cu")
		(net "GPS2_RX")
	)
	(segment
		(start 104.163595 127.4536)
		(end 104.163595 127.08227)
		(width 0.2032)
		(layer "F.Cu")
		(net "GPS2_RX")
	)
	(segment
		(start 104.140225 127.05891)
		(end 104.163595 127.08227)
		(width 0.2032)
		(layer "F.Cu")
		(net "GPS2_RX")
	)
	(segment
		(start 112.998685 57.03868)
		(end 113.038595 57.0786)
		(width 0.2032)
		(layer "F.Cu")
		(net "GPS2_RX")
	)
	(segment
		(start 112.998685 57.03868)
		(end 112.998685 56.34231)
		(width 0.2032)
		(layer "F.Cu")
		(net "GPS2_RX")
	)
	(via
		(at 121.032895 80.0036)
		(size 0.4064)
		(drill 0.2032)
		(layers "F.Cu" "B.Cu")
		(net "GPS2_RX")
	)
	(via
		(at 95.568595 80.6432)
		(size 0.4064)
		(drill 0.2032)
		(layers "F.Cu" "B.Cu")
		(net "GPS2_RX")
	)
	(via
		(at 104.163595 127.4536)
		(size 0.4064)
		(drill 0.2032)
		(layers "F.Cu" "B.Cu")
		(net "GPS2_RX")
	)
	(via
		(at 122.060795 127.1506)
		(size 0.4064)
		(drill 0.2032)
		(layers "F.Cu" "B.Cu")
		(net "GPS2_RX")
	)
	(via
		(at 112.998685 56.34231)
		(size 0.4064)
		(drill 0.2032)
		(layers "F.Cu" "B.Cu")
		(net "GPS2_RX")
	)
	(segment
		(start 121.746095 79.2904)
		(end 122.238595 79.2904)
		(width 0.2032)
		(layer "B.Cu")
		(net "GPS2_RX")
	)
	(segment
		(start 121.032895 80.0036)
		(end 121.746095 79.2904)
		(width 0.2032)
		(layer "B.Cu")
		(net "GPS2_RX")
	)
	(segment
		(start 109.698215 127.0744)
		(end 121.984595 127.0744)
		(width 0.2032)
		(layer "In2.Cu")
		(net "GPS2_RX")
	)
	(segment
		(start 95.568595 80.6432)
		(end 120.348995 80.6432)
		(width 0.2032)
		(layer "In2.Cu")
		(net "GPS2_RX")
	)
	(segment
		(start 109.622015 127.1506)
		(end 109.698215 127.0744)
		(width 0.2032)
		(layer "In2.Cu")
		(net "GPS2_RX")
	)
	(segment
		(start 121.984595 127.0744)
		(end 122.060795 127.1506)
		(width 0.2032)
		(layer "In2.Cu")
		(net "GPS2_RX")
	)
	(segment
		(start 104.466595 127.1506)
		(end 109.622015 127.1506)
		(width 0.2032)
		(layer "In2.Cu")
		(net "GPS2_RX")
	)
	(segment
		(start 120.348995 80.6432)
		(end 120.988595 80.0036)
		(width 0.2032)
		(layer "In2.Cu")
		(net "GPS2_RX")
	)
	(segment
		(start 104.163595 127.4536)
		(end 104.466595 127.1506)
		(width 0.2032)
		(layer "In2.Cu")
		(net "GPS2_RX")
	)
	(segment
		(start 120.988595 80.0036)
		(end 121.032895 80.0036)
		(width 0.2032)
		(layer "In2.Cu")
		(net "GPS2_RX")
	)
	(segment
		(start 108.763595 56.2786)
		(end 112.934965 56.2786)
		(width 0.2032)
		(layer "In3.Cu")
		(net "GPS2_RX")
	)
	(segment
		(start 122.136995 98.53202)
		(end 122.492595 98.88762)
		(width 0.2032)
		(layer "In3.Cu")
		(net "GPS2_RX")
	)
	(segment
		(start 122.136995 98.53202)
		(end 122.136995 96.28111)
		(width 0.2032)
		(layer "In3.Cu")
		(net "GPS2_RX")
	)
	(segment
		(start 101.188595 52.6536)
		(end 105.138595 52.6536)
		(width 0.2032)
		(layer "In3.Cu")
		(net "GPS2_RX")
	)
	(segment
		(start 122.136995 96.28111)
		(end 122.196415 96.22169)
		(width 0.2032)
		(layer "In3.Cu")
		(net "GPS2_RX")
	)
	(segment
		(start 122.060795 127.1506)
		(end 122.060795 104.42482)
		(width 0.2032)
		(layer "In3.Cu")
		(net "GPS2_RX")
	)
	(segment
		(start 107.388595 54.9036)
		(end 108.763595 56.2786)
		(width 0.2032)
		(layer "In3.Cu")
		(net "GPS2_RX")
	)
	(segment
		(start 122.196415 93.97078)
		(end 125.888595 90.2786)
		(width 0.2032)
		(layer "In3.Cu")
		(net "GPS2_RX")
	)
	(segment
		(start 99.938595 57.80025)
		(end 99.938595 53.9036)
		(width 0.2032)
		(layer "In3.Cu")
		(net "GPS2_RX")
	)
	(segment
		(start 122.060795 104.42482)
		(end 122.492595 103.99302)
		(width 0.2032)
		(layer "In3.Cu")
		(net "GPS2_RX")
	)
	(segment
		(start 95.568595 72.5986)
		(end 96.038595 72.1286)
		(width 0.2032)
		(layer "In3.Cu")
		(net "GPS2_RX")
	)
	(segment
		(start 95.568595 80.6432)
		(end 95.568595 72.5986)
		(width 0.2032)
		(layer "In3.Cu")
		(net "GPS2_RX")
	)
	(segment
		(start 121.032895 80.0036)
		(end 125.888595 84.8593)
		(width 0.2032)
		(layer "In3.Cu")
		(net "GPS2_RX")
	)
	(segment
		(start 122.492595 103.99302)
		(end 122.492595 98.88762)
		(width 0.2032)
		(layer "In3.Cu")
		(net "GPS2_RX")
	)
	(segment
		(start 122.196415 96.22169)
		(end 122.196415 93.97078)
		(width 0.2032)
		(layer "In3.Cu")
		(net "GPS2_RX")
	)
	(segment
		(start 112.934965 56.2786)
		(end 112.998685 56.34231)
		(width 0.2032)
		(layer "In3.Cu")
		(net "GPS2_RX")
	)
	(segment
		(start 107.388595 54.9036)
		(end 107.388595 54.9036)
		(width 0.2032)
		(layer "In3.Cu")
		(net "GPS2_RX")
	)
	(segment
		(start 96.038595 61.70025)
		(end 99.938595 57.80025)
		(width 0.2032)
		(layer "In3.Cu")
		(net "GPS2_RX")
	)
	(segment
		(start 96.038595 72.1286)
		(end 96.038595 61.70025)
		(width 0.2032)
		(layer "In3.Cu")
		(net "GPS2_RX")
	)
	(segment
		(start 99.938595 53.9036)
		(end 101.188595 52.6536)
		(width 0.2032)
		(layer "In3.Cu")
		(net "GPS2_RX")
	)
	(segment
		(start 105.138595 52.6536)
		(end 107.388595 54.9036)
		(width 0.2032)
		(layer "In3.Cu")
		(net "GPS2_RX")
	)
	(segment
		(start 125.888595 90.2786)
		(end 125.888595 84.8593)
		(width 0.2032)
		(layer "In3.Cu")
		(net "GPS2_RX")
	)
	(segment
		(start 139.699085 117.00531)
		(end 140.644455 116.05994)
		(width 0.2032)
		(layer "F.Cu")
		(net "GPS2_RST")
	)
	(segment
		(start 140.644455 116.05994)
		(end 147.185965 116.05994)
		(width 0.2032)
		(layer "F.Cu")
		(net "GPS2_RST")
	)
	(segment
		(start 139.699085 117.0414)
		(end 139.699085 117.00531)
		(width 0.2032)
		(layer "F.Cu")
		(net "GPS2_RST")
	)
	(via
		(at 139.699085 117.0414)
		(size 0.4064)
		(drill 0.2032)
		(layers "F.Cu" "B.Cu")
		(net "GPS2_RST")
	)
	(via
		(at 139.713795 85.139)
		(size 0.4064)
		(drill 0.2032)
		(layers "F.Cu" "B.Cu")
		(net "GPS2_RST")
	)
	(via
		(at 119.924015 81.36853)
		(size 0.4064)
		(drill 0.2032)
		(layers "F.Cu" "B.Cu")
		(net "GPS2_RST")
	)
	(segment
		(start 119.845885 81.2904)
		(end 119.924015 81.36853)
		(width 0.2032)
		(layer "B.Cu")
		(net "GPS2_RST")
	)
	(segment
		(start 117.793595 81.2904)
		(end 119.845885 81.2904)
		(width 0.2032)
		(layer "B.Cu")
		(net "GPS2_RST")
	)
	(segment
		(start 120.169925 81.36853)
		(end 123.954995 85.1536)
		(width 0.2032)
		(layer "In2.Cu")
		(net "GPS2_RST")
	)
	(segment
		(start 123.954995 85.1536)
		(end 137.141015 85.1536)
		(width 0.2032)
		(layer "In2.Cu")
		(net "GPS2_RST")
	)
	(segment
		(start 119.924015 81.36853)
		(end 120.169925 81.36853)
		(width 0.2032)
		(layer "In2.Cu")
		(net "GPS2_RST")
	)
	(segment
		(start 137.155615 85.139)
		(end 139.713795 85.139)
		(width 0.2032)
		(layer "In2.Cu")
		(net "GPS2_RST")
	)
	(segment
		(start 137.141015 85.1536)
		(end 137.155615 85.139)
		(width 0.2032)
		(layer "In2.Cu")
		(net "GPS2_RST")
	)
	(segment
		(start 139.699085 85.15371)
		(end 139.713795 85.139)
		(width 0.2032)
		(layer "In3.Cu")
		(net "GPS2_RST")
	)
	(segment
		(start 139.699085 117.0414)
		(end 139.699085 85.15371)
		(width 0.2032)
		(layer "In3.Cu")
		(net "GPS2_RST")
	)
	(segment
		(start 122.698085 94.99411)
		(end 124.838595 92.8536)
		(width 0.2032)
		(layer "F.Cu")
		(net "DCXO1")
	)
	(segment
		(start 148.263885 87.19849)
		(end 149.158485 87.19849)
		(width 0.2032)
		(layer "F.Cu")
		(net "DCXO1")
	)
	(segment
		(start 149.638595 92.3536)
		(end 149.638595 87.6786)
		(width 0.2032)
		(layer "F.Cu")
		(net "DCXO1")
	)
	(segment
		(start 122.698085 96.61497)
		(end 122.698085 94.99411)
		(width 0.2032)
		(layer "F.Cu")
		(net "DCXO1")
	)
	(segment
		(start 124.838595 92.8536)
		(end 149.138595 92.8536)
		(width 0.2032)
		(layer "F.Cu")
		(net "DCXO1")
	)
	(segment
		(start 148.178595 87.1132)
		(end 148.263885 87.19849)
		(width 0.2032)
		(layer "F.Cu")
		(net "DCXO1")
	)
	(segment
		(start 149.158485 87.19849)
		(end 149.638595 87.6786)
		(width 0.2032)
		(layer "F.Cu")
		(net "DCXO1")
	)
	(segment
		(start 149.138595 92.8536)
		(end 149.638595 92.3536)
		(width 0.2032)
		(layer "F.Cu")
		(net "DCXO1")
	)
	(segment
		(start 143.149595 79.5406)
		(end 143.149595 79.1406)
		(width 0.2032)
		(layer "F.Cu")
		(net "DCXO2")
	)
	(segment
		(start 118.198215 96.61497)
		(end 118.198215 92.59398)
		(width 0.2032)
		(layer "F.Cu")
		(net "DCXO2")
	)
	(segment
		(start 118.198215 92.59398)
		(end 119.313595 91.4786)
		(width 0.2032)
		(layer "F.Cu")
		(net "DCXO2")
	)
	(segment
		(start 141.950475 80.73972)
		(end 143.149595 79.5406)
		(width 0.2032)
		(layer "F.Cu")
		(net "DCXO2")
	)
	(segment
		(start 141.727475 80.73972)
		(end 141.950475 80.73972)
		(width 0.2032)
		(layer "F.Cu")
		(net "DCXO2")
	)
	(segment
		(start 141.688595 80.7786)
		(end 141.727475 80.73972)
		(width 0.2032)
		(layer "F.Cu")
		(net "DCXO2")
	)
	(via
		(at 141.688595 80.7786)
		(size 0.4064)
		(drill 0.2032)
		(layers "F.Cu" "B.Cu")
		(net "DCXO2")
	)
	(via
		(at 119.313595 91.4786)
		(size 0.4064)
		(drill 0.2032)
		(layers "F.Cu" "B.Cu")
		(net "DCXO2")
	)
	(segment
		(start 126.346745 90.6036)
		(end 126.347765 90.6036)
		(width 0.2032)
		(layer "In2.Cu")
		(net "DCXO2")
	)
	(segment
		(start 119.497765 91.5786)
		(end 125.204425 91.5786)
		(width 0.2032)
		(layer "In2.Cu")
		(net "DCXO2")
	)
	(segment
		(start 136.963595 90.6036)
		(end 140.588595 86.9786)
		(width 0.2032)
		(layer "In2.Cu")
		(net "DCXO2")
	)
	(segment
		(start 140.588595 81.8786)
		(end 141.688595 80.7786)
		(width 0.2032)
		(layer "In2.Cu")
		(net "DCXO2")
	)
	(segment
		(start 126.347765 90.6036)
		(end 136.963595 90.6036)
		(width 0.2032)
		(layer "In2.Cu")
		(net "DCXO2")
	)
	(segment
		(start 125.348455 91.51874)
		(end 126.203735 90.66346)
		(width 0.2032)
		(layer "In2.Cu")
		(net "DCXO2")
	)
	(segment
		(start 119.313595 91.4786)
		(end 119.354075 91.51909)
		(width 0.2032)
		(layer "In2.Cu")
		(net "DCXO2")
	)
	(segment
		(start 140.588595 86.9786)
		(end 140.588595 81.8786)
		(width 0.2032)
		(layer "In2.Cu")
		(net "DCXO2")
	)
	(arc
		(start 119.497765 91.5786)
		(mid 119.420004 91.563132)
		(end 119.354081 91.519084)
		(width 0.2032)
		(layer "In2.Cu")
		(net "DCXO2")
	)
	(arc
		(start 126.203728 90.663466)
		(mid 126.269303 90.619359)
		(end 126.346744 90.603603)
		(width 0.2032)
		(layer "In2.Cu")
		(net "DCXO2")
	)
	(arc
		(start 125.348455 91.518737)
		(mid 125.282412 91.563038)
		(end 125.204425 91.5786)
		(width 0.2032)
		(layer "In2.Cu")
		(net "DCXO2")
	)
	(segment
		(start 145.133645 114.05995)
		(end 147.185965 114.05995)
		(width 0.2032)
		(layer "F.Cu")
		(net "CSN")
	)
	(segment
		(start 143.049565 114.1966)
		(end 144.996995 114.1966)
		(width 0.2032)
		(layer "F.Cu")
		(net "CSN")
	)
	(segment
		(start 222.257055 74.3186)
		(end 222.564595 74.62614)
		(width 0.2032)
		(layer "F.Cu")
		(net "CSN")
	)
	(segment
		(start 144.996995 114.1966)
		(end 145.133645 114.05995)
		(width 0.2032)
		(layer "F.Cu")
		(net "CSN")
	)
	(segment
		(start 222.564595 75.9431)
		(end 222.564595 74.62614)
		(width 0.2032)
		(layer "F.Cu")
		(net "CSN")
	)
	(via
		(at 144.717595 73.0232)
		(size 0.4064)
		(drill 0.2032)
		(layers "F.Cu" "B.Cu")
		(net "CSN")
	)
	(via
		(at 143.049565 114.1966)
		(size 0.4064)
		(drill 0.2032)
		(layers "F.Cu" "B.Cu")
		(net "CSN")
	)
	(via
		(at 222.257055 74.3186)
		(size 0.4064)
		(drill 0.2032)
		(layers "F.Cu" "B.Cu")
		(net "CSN")
	)
	(segment
		(start 222.202075 74.3186)
		(end 222.257055 74.3186)
		(width 0.2032)
		(layer "In2.Cu")
		(net "CSN")
	)
	(segment
		(start 183.643095 74.1916)
		(end 222.075075 74.1916)
		(width 0.2032)
		(layer "In2.Cu")
		(net "CSN")
	)
	(segment
		(start 222.075075 74.1916)
		(end 222.202075 74.3186)
		(width 0.2032)
		(layer "In2.Cu")
		(net "CSN")
	)
	(segment
		(start 145.897995 74.2036)
		(end 183.631095 74.2036)
		(width 0.2032)
		(layer "In2.Cu")
		(net "CSN")
	)
	(segment
		(start 144.717595 73.0232)
		(end 145.897995 74.2036)
		(width 0.2032)
		(layer "In2.Cu")
		(net "CSN")
	)
	(segment
		(start 183.631095 74.2036)
		(end 183.643095 74.1916)
		(width 0.2032)
		(layer "In2.Cu")
		(net "CSN")
	)
	(segment
		(start 143.238595 110.9766)
		(end 144.717595 109.4976)
		(width 0.2032)
		(layer "In3.Cu")
		(net "CSN")
	)
	(segment
		(start 143.049565 114.1966)
		(end 143.129075 114.11709)
		(width 0.2032)
		(layer "In3.Cu")
		(net "CSN")
	)
	(segment
		(start 143.180285 111.13328)
		(end 143.188125 111.24903)
		(width 0.2032)
		(layer "In3.Cu")
		(net "CSN")
	)
	(segment
		(start 144.717595 109.4976)
		(end 144.717595 73.0232)
		(width 0.2032)
		(layer "In3.Cu")
		(net "CSN")
	)
	(segment
		(start 143.188595 113.9734)
		(end 143.188595 111.26277)
		(width 0.2032)
		(layer "In3.Cu")
		(net "CSN")
	)
	(arc
		(start 143.18813 111.249031)
		(mid 143.188479 111.255897)
		(end 143.188595 111.26277)
		(width 0.2032)
		(layer "In3.Cu")
		(net "CSN")
	)
	(arc
		(start 143.18029 111.133284)
		(mid 143.192585 111.048666)
		(end 143.238602 110.976598)
		(width 0.2032)
		(layer "In3.Cu")
		(net "CSN")
	)
	(arc
		(start 143.188595 113.9734)
		(mid 143.173127 114.051162)
		(end 143.129078 114.117085)
		(width 0.2032)
		(layer "In3.Cu")
		(net "CSN")
	)
	(segment
		(start 121.198215 102.16497)
		(end 121.374995 102.34175)
		(width 0.2032)
		(layer "F.Cu")
		(net "ANT4")
	)
	(segment
		(start 63.564595 137.5646)
		(end 82.177595 137.5646)
		(width 0.2032)
		(layer "F.Cu")
		(net "ANT4")
	)
	(segment
		(start 82.177595 137.5646)
		(end 84.011595 137.5646)
		(width 0.2032)
		(layer "F.Cu")
		(net "ANT4")
	)
	(segment
		(start 81.388595 142.3286)
		(end 81.388595 138.3536)
		(width 0.2032)
		(layer "F.Cu")
		(net "ANT4")
	)
	(segment
		(start 121.198215 102.16497)
		(end 121.198215 100.66475)
		(width 0.2032)
		(layer "F.Cu")
		(net "ANT4")
	)
	(segment
		(start 121.374995 102.3856)
		(end 121.374995 102.34175)
		(width 0.2032)
		(layer "F.Cu")
		(net "ANT4")
	)
	(segment
		(start 81.388595 138.3536)
		(end 82.177595 137.5646)
		(width 0.2032)
		(layer "F.Cu")
		(net "ANT4")
	)
	(via
		(at 84.011595 137.5646)
		(size 0.4064)
		(drill 0.2032)
		(layers "F.Cu" "B.Cu")
		(net "ANT4")
	)
	(via
		(at 121.374995 102.3856)
		(size 0.4064)
		(drill 0.2032)
		(layers "F.Cu" "B.Cu")
		(net "ANT4")
	)
	(via
		(at 121.451195 136.7772)
		(size 0.4064)
		(drill 0.2032)
		(layers "F.Cu" "B.Cu")
		(net "ANT4")
	)
	(segment
		(start 120.790795 137.5646)
		(end 121.451195 136.9042)
		(width 0.2032)
		(layer "In2.Cu")
		(net "ANT4")
	)
	(segment
		(start 93.938595 140.0786)
		(end 103.438595 140.0786)
		(width 0.2032)
		(layer "In2.Cu")
		(net "ANT4")
	)
	(segment
		(start 84.011595 137.5646)
		(end 91.424595 137.5646)
		(width 0.2032)
		(layer "In2.Cu")
		(net "ANT4")
	)
	(segment
		(start 91.424595 137.5646)
		(end 93.938595 140.0786)
		(width 0.2032)
		(layer "In2.Cu")
		(net "ANT4")
	)
	(segment
		(start 105.952595 137.5646)
		(end 120.790795 137.5646)
		(width 0.2032)
		(layer "In2.Cu")
		(net "ANT4")
	)
	(segment
		(start 103.438595 140.0786)
		(end 105.952595 137.5646)
		(width 0.2032)
		(layer "In2.Cu")
		(net "ANT4")
	)
	(segment
		(start 121.451195 136.9042)
		(end 121.451195 136.7772)
		(width 0.2032)
		(layer "In2.Cu")
		(net "ANT4")
	)
	(segment
		(start 121.451195 136.7772)
		(end 121.451195 102.4618)
		(width 0.2032)
		(layer "In3.Cu")
		(net "ANT4")
	)
	(segment
		(start 121.374995 102.3856)
		(end 121.451195 102.4618)
		(width 0.2032)
		(layer "In3.Cu")
		(net "ANT4")
	)
	(segment
		(start 84.087795 124.2296)
		(end 84.113195 124.255)
		(width 0.2032)
		(layer "F.Cu")
		(net "ANT3")
	)
	(segment
		(start 82.177595 124.2296)
		(end 84.087795 124.2296)
		(width 0.2032)
		(layer "F.Cu")
		(net "ANT3")
	)
	(segment
		(start 120.698085 102.5173)
		(end 120.739995 102.55921)
		(width 0.2032)
		(layer "F.Cu")
		(net "ANT3")
	)
	(segment
		(start 81.463595 129.4786)
		(end 81.463595 124.9436)
		(width 0.2032)
		(layer "F.Cu")
		(net "ANT3")
	)
	(segment
		(start 120.698085 102.5173)
		(end 120.698085 100.66475)
		(width 0.2032)
		(layer "F.Cu")
		(net "ANT3")
	)
	(segment
		(start 120.739995 102.6142)
		(end 120.739995 102.55921)
		(width 0.2032)
		(layer "F.Cu")
		(net "ANT3")
	)
	(segment
		(start 81.463595 124.9436)
		(end 82.177595 124.2296)
		(width 0.2032)
		(layer "F.Cu")
		(net "ANT3")
	)
	(segment
		(start 63.564595 124.2296)
		(end 82.177595 124.2296)
		(width 0.2032)
		(layer "F.Cu")
		(net "ANT3")
	)
	(via
		(at 120.638395 124.0772)
		(size 0.4064)
		(drill 0.2032)
		(layers "F.Cu" "B.Cu")
		(net "ANT3")
	)
	(via
		(at 120.739995 102.6142)
		(size 0.4064)
		(drill 0.2032)
		(layers "F.Cu" "B.Cu")
		(net "ANT3")
	)
	(via
		(at 84.113195 124.255)
		(size 0.4064)
		(drill 0.2032)
		(layers "F.Cu" "B.Cu")
		(net "ANT3")
	)
	(segment
		(start 84.156025 124.255)
		(end 84.333825 124.0772)
		(width 0.2032)
		(layer "In2.Cu")
		(net "ANT3")
	)
	(segment
		(start 84.113195 124.255)
		(end 84.156025 124.255)
		(width 0.2032)
		(layer "In2.Cu")
		(net "ANT3")
	)
	(segment
		(start 84.333825 124.0772)
		(end 120.638395 124.0772)
		(width 0.2032)
		(layer "In2.Cu")
		(net "ANT3")
	)
	(segment
		(start 120.638395 102.77079)
		(end 120.739995 102.66919)
		(width 0.2032)
		(layer "In3.Cu")
		(net "ANT3")
	)
	(segment
		(start 120.739995 102.66919)
		(end 120.739995 102.6142)
		(width 0.2032)
		(layer "In3.Cu")
		(net "ANT3")
	)
	(segment
		(start 120.638395 124.0772)
		(end 120.638395 102.77079)
		(width 0.2032)
		(layer "In3.Cu")
		(net "ANT3")
	)
	(segment
		(start 81.363595 111.7086)
		(end 82.093595 110.9786)
		(width 0.2032)
		(layer "F.Cu")
		(net "ANT2")
	)
	(segment
		(start 120.198215 100.66475)
		(end 120.201575 100.66811)
		(width 0.2032)
		(layer "F.Cu")
		(net "ANT2")
	)
	(segment
		(start 63.564595 110.8946)
		(end 76.529595 110.8946)
		(width 0.2032)
		(layer "F.Cu")
		(net "ANT2")
	)
	(segment
		(start 81.363595 116.2036)
		(end 81.363595 111.7086)
		(width 0.2032)
		(layer "F.Cu")
		(net "ANT2")
	)
	(segment
		(start 120.201575 101.58596)
		(end 120.201575 100.66811)
		(width 0.2032)
		(layer "F.Cu")
		(net "ANT2")
	)
	(segment
		(start 119.698595 102.5888)
		(end 120.206595 102.0808)
		(width 0.2032)
		(layer "F.Cu")
		(net "ANT2")
	)
	(segment
		(start 120.206595 102.0808)
		(end 120.206595 101.59098)
		(width 0.2032)
		(layer "F.Cu")
		(net "ANT2")
	)
	(segment
		(start 76.529595 110.8946)
		(end 76.613595 110.9786)
		(width 0.2032)
		(layer "F.Cu")
		(net "ANT2")
	)
	(segment
		(start 120.201575 101.58596)
		(end 120.206595 101.59098)
		(width 0.2032)
		(layer "F.Cu")
		(net "ANT2")
	)
	(segment
		(start 82.093595 110.9786)
		(end 82.177595 110.8946)
		(width 0.2032)
		(layer "F.Cu")
		(net "ANT2")
	)
	(segment
		(start 76.613595 110.9786)
		(end 82.093595 110.9786)
		(width 0.2032)
		(layer "F.Cu")
		(net "ANT2")
	)
	(segment
		(start 82.177595 110.8946)
		(end 84.138595 110.8946)
		(width 0.2032)
		(layer "F.Cu")
		(net "ANT2")
	)
	(via
		(at 119.698595 110.6152)
		(size 0.4064)
		(drill 0.2032)
		(layers "F.Cu" "B.Cu")
		(net "ANT2")
	)
	(via
		(at 84.138595 110.8946)
		(size 0.4064)
		(drill 0.2032)
		(layers "F.Cu" "B.Cu")
		(net "ANT2")
	)
	(via
		(at 119.698595 102.5888)
		(size 0.4064)
		(drill 0.2032)
		(layers "F.Cu" "B.Cu")
		(net "ANT2")
	)
	(segment
		(start 84.138595 110.8946)
		(end 84.417995 110.6152)
		(width 0.2032)
		(layer "In2.Cu")
		(net "ANT2")
	)
	(segment
		(start 84.417995 110.6152)
		(end 119.698595 110.6152)
		(width 0.2032)
		(layer "In2.Cu")
		(net "ANT2")
	)
	(segment
		(start 119.698595 110.6152)
		(end 119.698595 102.5888)
		(width 0.2032)
		(layer "In3.Cu")
		(net "ANT2")
	)
	(segment
		(start 82.177595 97.5596)
		(end 84.417995 97.5596)
		(width 0.2032)
		(layer "F.Cu")
		(net "ANT1")
	)
	(segment
		(start 119.698085 101.80089)
		(end 119.698595 101.8014)
		(width 0.2032)
		(layer "F.Cu")
		(net "ANT1")
	)
	(segment
		(start 81.563595 98.1736)
		(end 82.177595 97.5596)
		(width 0.2032)
		(layer "F.Cu")
		(net "ANT1")
	)
	(segment
		(start 119.698085 101.80089)
		(end 119.698085 100.66475)
		(width 0.2032)
		(layer "F.Cu")
		(net "ANT1")
	)
	(segment
		(start 81.563595 102.5536)
		(end 81.563595 98.1736)
		(width 0.2032)
		(layer "F.Cu")
		(net "ANT1")
	)
	(segment
		(start 73.596595 97.5596)
		(end 82.177595 97.5596)
		(width 0.2032)
		(layer "F.Cu")
		(net "ANT1")
	)
	(segment
		(start 63.564595 97.5596)
		(end 73.596595 97.5596)
		(width 0.2032)
		(layer "F.Cu")
		(net "ANT1")
	)
	(via
		(at 119.698595 101.8014)
		(size 0.4064)
		(drill 0.2032)
		(layers "F.Cu" "B.Cu")
		(net "ANT1")
	)
	(via
		(at 84.417995 97.5596)
		(size 0.4064)
		(drill 0.2032)
		(layers "F.Cu" "B.Cu")
		(net "ANT1")
	)
	(segment
		(start 88.659795 101.8014)
		(end 119.698595 101.8014)
		(width 0.2032)
		(layer "In2.Cu")
		(net "ANT1")
	)
	(segment
		(start 84.417995 97.5596)
		(end 88.659795 101.8014)
		(width 0.2032)
		(layer "In2.Cu")
		(net "ANT1")
	)
	(segment
		(start 152.185195 77.6078)
		(end 152.248695 77.6713)
		(width 0.508)
		(layer "F.Cu")
		(net "+3.3V_CLEAN")
	)
	(segment
		(start 161.970595 88.3856)
		(end 163.894595 88.3856)
		(width 0.508)
		(layer "F.Cu")
		(net "+3.3V_CLEAN")
	)
	(segment
		(start 154.288595 80.8786)
		(end 154.288595 80.0786)
		(width 0.508)
		(layer "F.Cu")
		(net "+3.3V_CLEAN")
	)
	(segment
		(start 161.100595 83.6526)
		(end 161.100595 83.6276)
		(width 0.508)
		(layer "F.Cu")
		(net "+3.3V_CLEAN")
	)
	(segment
		(start 138.988595 90.4786)
		(end 139.388595 90.8786)
		(width 0.2032)
		(layer "F.Cu")
		(net "+3.3V_CLEAN")
	)
	(segment
		(start 140.513595 90.6536)
		(end 140.513595 89.8416)
		(width 0.2032)
		(layer "F.Cu")
		(net "+3.3V_CLEAN")
	)
	(segment
		(start 161.100595 83.6276)
		(end 161.100595 83.6026)
		(width 0.508)
		(layer "F.Cu")
		(net "+3.3V_CLEAN")
	)
	(segment
		(start 167.207595 78.1286)
		(end 171.514595 78.1286)
		(width 0.508)
		(layer "F.Cu")
		(net "+3.3V_CLEAN")
	)
	(segment
		(start 159.068595 85.6846)
		(end 161.100595 83.6526)
		(width 0.508)
		(layer "F.Cu")
		(net "+3.3V_CLEAN")
	)
	(segment
		(start 143.388595 88.5786)
		(end 143.688595 88.8786)
		(width 0.2032)
		(layer "F.Cu")
		(net "+3.3V_CLEAN")
	)
	(segment
		(start 152.312195 79.5908)
		(end 153.800795 79.5908)
		(width 0.508)
		(layer "F.Cu")
		(net "+3.3V_CLEAN")
	)
	(segment
		(start 153.800795 79.5908)
		(end 154.288595 80.0786)
		(width 0.508)
		(layer "F.Cu")
		(net "+3.3V_CLEAN")
	)
	(segment
		(start 173.988595 87.0036)
		(end 178.613595 91.6286)
		(width 0.2032)
		(layer "F.Cu")
		(net "+3.3V_CLEAN")
	)
	(segment
		(start 160.879595 83.3816)
		(end 161.100595 83.6026)
		(width 0.508)
		(layer "F.Cu")
		(net "+3.3V_CLEAN")
	)
	(segment
		(start 155.320225 76.9856)
		(end 159.322595 80.98797)
		(width 0.508)
		(layer "F.Cu")
		(net "+3.3V_CLEAN")
	)
	(segment
		(start 137.888595 89.7786)
		(end 138.688595 89.7786)
		(width 0.2032)
		(layer "F.Cu")
		(net "+3.3V_CLEAN")
	)
	(segment
		(start 161.735595 88.1506)
		(end 161.970595 88.3856)
		(width 0.508)
		(layer "F.Cu")
		(net "+3.3V_CLEAN")
	)
	(segment
		(start 173.988595 82.4786)
		(end 173.988595 80.6026)
		(width 0.2032)
		(layer "F.Cu")
		(net "+3.3V_CLEAN")
	)
	(segment
		(start 159.322595 81.87118)
		(end 159.322595 80.98797)
		(width 0.508)
		(layer "F.Cu")
		(net "+3.3V_CLEAN")
	)
	(segment
		(start 178.613595 91.6286)
		(end 183.473595 91.6286)
		(width 0.2032)
		(layer "F.Cu")
		(net "+3.3V_CLEAN")
	)
	(segment
		(start 173.988595 87.0036)
		(end 173.988595 82.4786)
		(width 0.2032)
		(layer "F.Cu")
		(net "+3.3V_CLEAN")
	)
	(segment
		(start 159.068595 88.1506)
		(end 159.068595 85.6846)
		(width 0.508)
		(layer "F.Cu")
		(net "+3.3V_CLEAN")
	)
	(segment
		(start 152.248695 79.5273)
		(end 152.248695 77.6713)
		(width 0.508)
		(layer "F.Cu")
		(net "+3.3V_CLEAN")
	)
	(segment
		(start 161.100595 83.6276)
		(end 162.528595 83.6276)
		(width 0.508)
		(layer "F.Cu")
		(net "+3.3V_CLEAN")
	)
	(segment
		(start 139.388595 90.8786)
		(end 140.288595 90.8786)
		(width 0.2032)
		(layer "F.Cu")
		(net "+3.3V_CLEAN")
	)
	(segment
		(start 160.833015 83.3816)
		(end 160.879595 83.3816)
		(width 0.508)
		(layer "F.Cu")
		(net "+3.3V_CLEAN")
	)
	(segment
		(start 152.530595 77.74697)
		(end 153.291965 76.9856)
		(width 0.508)
		(layer "F.Cu")
		(net "+3.3V_CLEAN")
	)
	(segment
		(start 141.525595 88.5786)
		(end 143.388595 88.5786)
		(width 0.2032)
		(layer "F.Cu")
		(net "+3.3V_CLEAN")
	)
	(segment
		(start 140.288595 90.8786)
		(end 140.513595 90.6536)
		(width 0.2032)
		(layer "F.Cu")
		(net "+3.3V_CLEAN")
	)
	(segment
		(start 143.688595 89.5786)
		(end 143.688595 88.8786)
		(width 0.2032)
		(layer "F.Cu")
		(net "+3.3V_CLEAN")
	)
	(segment
		(start 173.209595 83.2576)
		(end 173.988595 82.4786)
		(width 0.508)
		(layer "F.Cu")
		(net "+3.3V_CLEAN")
	)
	(segment
		(start 152.248695 79.5273)
		(end 152.312195 79.5908)
		(width 0.508)
		(layer "F.Cu")
		(net "+3.3V_CLEAN")
	)
	(segment
		(start 171.514595 78.1286)
		(end 173.988595 80.6026)
		(width 0.508)
		(layer "F.Cu")
		(net "+3.3V_CLEAN")
	)
	(segment
		(start 159.322595 81.87118)
		(end 160.833015 83.3816)
		(width 0.508)
		(layer "F.Cu")
		(net "+3.3V_CLEAN")
	)
	(segment
		(start 153.291965 76.9856)
		(end 155.320225 76.9856)
		(width 0.508)
		(layer "F.Cu")
		(net "+3.3V_CLEAN")
	)
	(segment
		(start 143.688595 89.5786)
		(end 143.788595 89.6786)
		(width 0.2032)
		(layer "F.Cu")
		(net "+3.3V_CLEAN")
	)
	(segment
		(start 162.878595 83.2576)
		(end 173.209595 83.2576)
		(width 0.508)
		(layer "F.Cu")
		(net "+3.3V_CLEAN")
	)
	(segment
		(start 159.068595 88.1506)
		(end 161.735595 88.1506)
		(width 0.508)
		(layer "F.Cu")
		(net "+3.3V_CLEAN")
	)
	(segment
		(start 138.988595 90.4786)
		(end 138.988595 90.0786)
		(width 0.2032)
		(layer "F.Cu")
		(net "+3.3V_CLEAN")
	)
	(segment
		(start 183.473595 91.6286)
		(end 193.813595 101.9686)
		(width 0.2032)
		(layer "F.Cu")
		(net "+3.3V_CLEAN")
	)
	(segment
		(start 138.688595 89.7786)
		(end 138.988595 90.0786)
		(width 0.2032)
		(layer "F.Cu")
		(net "+3.3V_CLEAN")
	)
	(segment
		(start 162.528595 83.6276)
		(end 162.878595 83.2776)
		(width 0.508)
		(layer "F.Cu")
		(net "+3.3V_CLEAN")
	)
	(segment
		(start 162.878595 83.2776)
		(end 162.878595 83.2576)
		(width 0.508)
		(layer "F.Cu")
		(net "+3.3V_CLEAN")
	)
	(segment
		(start 93.130195 61.6186)
		(end 111.443595 61.6186)
		(width 0.2032)
		(layer "F.Cu")
		(net "LED4")
	)
	(segment
		(start 145.986715 125.05993)
		(end 147.185965 125.05993)
		(width 0.1524)
		(layer "F.Cu")
		(net "LED4")
	)
	(segment
		(start 145.033565 124.731)
		(end 145.657785 124.731)
		(width 0.1524)
		(layer "F.Cu")
		(net "LED4")
	)
	(segment
		(start 145.657785 124.731)
		(end 145.986715 125.05993)
		(width 0.1524)
		(layer "F.Cu")
		(net "LED4")
	)
	(segment
		(start 90.085395 58.57379)
		(end 90.085395 57.9906)
		(width 0.2032)
		(layer "F.Cu")
		(net "LED4")
	)
	(segment
		(start 90.085395 58.57379)
		(end 93.130195 61.6186)
		(width 0.2032)
		(layer "F.Cu")
		(net "LED4")
	)
	(via
		(at 111.418195 124.72236)
		(size 0.4064)
		(drill 0.2032)
		(layers "F.Cu" "B.Cu")
		(net "LED4")
	)
	(via
		(at 111.443595 61.6186)
		(size 0.4064)
		(drill 0.2032)
		(layers "F.Cu" "B.Cu")
		(net "LED4")
	)
	(via
		(at 145.033565 124.731)
		(size 0.4064)
		(drill 0.2032)
		(layers "F.Cu" "B.Cu")
		(net "LED4")
	)
	(segment
		(start 111.418195 124.72236)
		(end 111.422515 124.72668)
		(width 0.1524)
		(layer "In2.Cu")
		(net "LED4")
	)
	(segment
		(start 145.029245 124.72668)
		(end 145.033565 124.731)
		(width 0.1524)
		(layer "In2.Cu")
		(net "LED4")
	)
	(segment
		(start 111.422515 124.72668)
		(end 145.029245 124.72668)
		(width 0.1524)
		(layer "In2.Cu")
		(net "LED4")
	)
	(segment
		(start 111.430895 61.6313)
		(end 111.443595 61.6186)
		(width 0.1524)
		(layer "In3.Cu")
		(net "LED4")
	)
	(segment
		(start 111.430895 124.70966)
		(end 111.430895 61.6313)
		(width 0.1524)
		(layer "In3.Cu")
		(net "LED4")
	)
	(segment
		(start 111.418195 124.72236)
		(end 111.430895 124.70966)
		(width 0.1524)
		(layer "In3.Cu")
		(net "LED4")
	)
	(segment
		(start 144.368595 125.3406)
		(end 145.420555 125.3406)
		(width 0.2032)
		(layer "F.Cu")
		(net "LED3")
	)
	(segment
		(start 84.963055 58.60766)
		(end 88.608995 62.2536)
		(width 0.2032)
		(layer "F.Cu")
		(net "LED3")
	)
	(segment
		(start 145.420555 125.3406)
		(end 145.639755 125.5598)
		(width 0.2032)
		(layer "F.Cu")
		(net "LED3")
	)
	(segment
		(start 88.608995 62.2536)
		(end 110.808595 62.2536)
		(width 0.2032)
		(layer "F.Cu")
		(net "LED3")
	)
	(segment
		(start 145.639755 125.5598)
		(end 147.185965 125.5598)
		(width 0.2032)
		(layer "F.Cu")
		(net "LED3")
	)
	(segment
		(start 144.336595 125.3726)
		(end 144.368595 125.3406)
		(width 0.2032)
		(layer "F.Cu")
		(net "LED3")
	)
	(segment
		(start 84.963055 58.60766)
		(end 84.963055 57.9906)
		(width 0.2032)
		(layer "F.Cu")
		(net "LED3")
	)
	(via
		(at 144.336595 125.3726)
		(size 0.4064)
		(drill 0.2032)
		(layers "F.Cu" "B.Cu")
		(net "LED3")
	)
	(via
		(at 110.808595 125.3726)
		(size 0.4064)
		(drill 0.2032)
		(layers "F.Cu" "B.Cu")
		(net "LED3")
	)
	(via
		(at 110.808595 62.2536)
		(size 0.4064)
		(drill 0.2032)
		(layers "F.Cu" "B.Cu")
		(net "LED3")
	)
	(segment
		(start 110.808595 125.3726)
		(end 144.336595 125.3726)
		(width 0.2032)
		(layer "In2.Cu")
		(net "LED3")
	)
	(segment
		(start 110.808595 125.3726)
		(end 110.808595 62.2536)
		(width 0.2032)
		(layer "In3.Cu")
		(net "LED3")
	)
	(segment
		(start 104.591375 154.05081)
		(end 105.117385 154.05081)
		(width 0.508)
		(layer "F.Cu")
		(net "+12V_PCIE")
	)
	(segment
		(start 104.158625 157.7576)
		(end 104.158625 154.48357)
		(width 0.508)
		(layer "F.Cu")
		(net "+12V_PCIE")
	)
	(segment
		(start 105.117385 154.05081)
		(end 105.392115 153.77608)
		(width 0.508)
		(layer "F.Cu")
		(net "+12V_PCIE")
	)
	(segment
		(start 105.158615 157.7576)
		(end 105.158615 154.09205)
		(width 0.508)
		(layer "F.Cu")
		(net "+12V_PCIE")
	)
	(segment
		(start 218.377595 66.5716)
		(end 219.567595 66.5716)
		(width 0.508)
		(layer "F.Cu")
		(net "+12V_PCIE")
	)
	(segment
		(start 105.392115 153.77608)
		(end 105.474595 153.77608)
		(width 0.508)
		(layer "F.Cu")
		(net "+12V_PCIE")
	)
	(segment
		(start 105.158615 154.09205)
		(end 105.474595 153.77608)
		(width 0.508)
		(layer "F.Cu")
		(net "+12V_PCIE")
	)
	(segment
		(start 106.158615 157.7576)
		(end 106.158615 154.4601)
		(width 0.508)
		(layer "F.Cu")
		(net "+12V_PCIE")
	)
	(segment
		(start 104.158625 154.48357)
		(end 104.591375 154.05081)
		(width 0.508)
		(layer "F.Cu")
		(net "+12V_PCIE")
	)
	(via
		(at 105.038595 153.2786)
		(size 0.4064)
		(drill 0.2032)
		(layers "F.Cu" "B.Cu")
		(net "+12V_PCIE")
	)
	(via
		(at 105.538595 154.0786)
		(size 0.4064)
		(drill 0.2032)
		(layers "F.Cu" "B.Cu")
		(net "+12V_PCIE")
	)
	(via
		(at 218.377595 66.5716)
		(size 0.4064)
		(drill 0.2032)
		(layers "F.Cu" "B.Cu")
		(net "+12V_PCIE")
	)
	(via
		(at 105.474595 66.5716)
		(size 0.4064)
		(drill 0.2032)
		(layers "F.Cu" "B.Cu")
		(net "+12V_PCIE")
	)
	(via
		(at 105.038595 154.0786)
		(size 0.4064)
		(drill 0.2032)
		(layers "F.Cu" "B.Cu")
		(net "+12V_PCIE")
	)
	(via
		(at 105.538595 153.2786)
		(size 0.4064)
		(drill 0.2032)
		(layers "F.Cu" "B.Cu")
		(net "+12V_PCIE")
	)
	(via
		(at 106.038595 154.0786)
		(size 0.4064)
		(drill 0.2032)
		(layers "F.Cu" "B.Cu")
		(net "+12V_PCIE")
	)
	(via
		(at 106.038595 153.2786)
		(size 0.4064)
		(drill 0.2032)
		(layers "F.Cu" "B.Cu")
		(net "+12V_PCIE")
	)
	(segment
		(start 106.158615 157.7576)
		(end 106.158615 154.40511)
		(width 0.508)
		(layer "B.Cu")
		(net "+12V_PCIE")
	)
	(segment
		(start 105.158615 157.7576)
		(end 105.158615 154.03707)
		(width 0.508)
		(layer "B.Cu")
		(net "+12V_PCIE")
	)
	(segment
		(start 105.474595 153.72109)
		(end 106.158615 154.40511)
		(width 0.508)
		(layer "B.Cu")
		(net "+12V_PCIE")
	)
	(segment
		(start 105.158615 154.03707)
		(end 105.474595 153.72109)
		(width 0.508)
		(layer "B.Cu")
		(net "+12V_PCIE")
	)
	(segment
		(start 105.474595 66.5716)
		(end 218.377595 66.5716)
		(width 0.508)
		(layer "In2.Cu")
		(net "+12V_PCIE")
	)
	(segment
		(start 105.474595 153.6936)
		(end 105.474595 66.5716)
		(width 0.508)
		(layer "In3.Cu")
		(net "+12V_PCIE")
	)
	(segment
		(start 111.138605 157.0786)
		(end 111.138605 153.97858)
		(width 0.508)
		(layer "F.Cu")
		(net "+3.3V_PCIE")
	)
	(segment
		(start 111.438595 153.6786)
		(end 112.138595 153.6786)
		(width 0.508)
		(layer "F.Cu")
		(net "+3.3V_PCIE")
	)
	(segment
		(start 111.138605 153.97858)
		(end 111.438595 153.6786)
		(width 0.508)
		(layer "F.Cu")
		(net "+3.3V_PCIE")
	)
	(segment
		(start 111.158605 157.7576)
		(end 111.236665 157.67954)
		(width 0.508)
		(layer "F.Cu")
		(net "+3.3V_PCIE")
	)
	(via
		(at 111.238595 153.2786)
		(size 0.4064)
		(drill 0.2032)
		(layers "F.Cu" "B.Cu")
		(net "+3.3V_PCIE")
	)
	(via
		(at 113.138595 154.0786)
		(size 0.4064)
		(drill 0.2032)
		(layers "F.Cu" "B.Cu")
		(net "+3.3V_PCIE")
	)
	(via
		(at 111.238595 154.0786)
		(size 0.4064)
		(drill 0.2032)
		(layers "F.Cu" "B.Cu")
		(net "+3.3V_PCIE")
	)
	(via
		(at 112.138595 154.0786)
		(size 0.4064)
		(drill 0.2032)
		(layers "F.Cu" "B.Cu")
		(net "+3.3V_PCIE")
	)
	(via
		(at 113.138595 153.2786)
		(size 0.4064)
		(drill 0.2032)
		(layers "F.Cu" "B.Cu")
		(net "+3.3V_PCIE")
	)
	(via
		(at 112.138595 153.2786)
		(size 0.4064)
		(drill 0.2032)
		(layers "F.Cu" "B.Cu")
		(net "+3.3V_PCIE")
	)
	(segment
		(start 113.127535 157.72653)
		(end 113.127535 154.16754)
		(width 0.508)
		(layer "B.Cu")
		(net "+3.3V_PCIE")
	)
	(segment
		(start 112.138605 157.0786)
		(end 112.138605 154.07861)
		(width 0.508)
		(layer "B.Cu")
		(net "+3.3V_PCIE")
	)
	(segment
		(start 112.205595 153.2456)
		(end 113.127535 154.16754)
		(width 0.508)
		(layer "B.Cu")
		(net "+3.3V_PCIE")
	)
	(segment
		(start 112.138595 154.0786)
		(end 112.138605 154.07861)
		(width 0.508)
		(layer "B.Cu")
		(net "+3.3V_PCIE")
	)
	(segment
		(start 113.127535 157.72653)
		(end 113.158605 157.7576)
		(width 0.508)
		(layer "B.Cu")
		(net "+3.3V_PCIE")
	)
	(segment
		(start 110.560195 145.1536)
		(end 122.088595 145.1536)
		(width 0.2032)
		(layer "F.Cu")
		(net "PRSNT")
	)
	(segment
		(start 122.088595 145.1536)
		(end 136.088595 145.1536)
		(width 0.2032)
		(layer "F.Cu")
		(net "PRSNT")
	)
	(segment
		(start 104.153795 151.56)
		(end 110.560195 145.1536)
		(width 0.2032)
		(layer "F.Cu")
		(net "PRSNT")
	)
	(via
		(at 104.153795 151.56)
		(size 0.4064)
		(drill 0.2032)
		(layers "F.Cu" "B.Cu")
		(net "PRSNT")
	)
	(segment
		(start 104.158625 157.2623)
		(end 104.158625 151.56)
		(width 0.2032)
		(layer "B.Cu")
		(net "PRSNT")
	)
	(segment
		(start 129.698325 135.66887)
		(end 129.698325 134.20545)
		(width 0.127)
		(layer "F.Cu")
		(net "PCIE_TX3_N")
	)
	(segment
		(start 129.698325 134.20545)
		(end 129.706195 134.21332)
		(width 0.127)
		(layer "F.Cu")
		(net "PCIE_TX3_N")
	)
	(via
		(at 135.188595 150.2786)
		(size 0.4064)
		(drill 0.2032)
		(layers "F.Cu" "B.Cu")
		(net "PCIE_TX3_N")
	)
	(via
		(at 129.588595 135.7786)
		(size 0.4064)
		(drill 0.2032)
		(layers "F.Cu" "B.Cu")
		(net "PCIE_TX3_N")
	)
	(arc
		(start 129.698325 135.66887)
		(mid 129.666186 135.746461)
		(end 129.588595 135.7786)
		(width 0.127)
		(layer "F.Cu")
		(net "PCIE_TX3_N")
	)
	(segment
		(start 135.188595 151.3546)
		(end 135.192595 151.3586)
		(width 0.127)
		(layer "B.Cu")
		(net "PCIE_TX3_N")
	)
	(segment
		(start 135.188595 151.3546)
		(end 135.188595 150.2786)
		(width 0.127)
		(layer "B.Cu")
		(net "PCIE_TX3_N")
	)
	(segment
		(start 134.293785 150.64667)
		(end 134.293785 150.64667)
		(width 0.127)
		(layer "In3.Cu")
		(net "PCIE_TX3_N")
	)
	(segment
		(start 129.972615 136.65774)
		(end 132.044645 138.72978)
		(width 0.127)
		(layer "In3.Cu")
		(net "PCIE_TX3_N")
	)
	(segment
		(start 134.275165 150.64861)
		(end 134.275165 150.64861)
		(width 0.127)
		(layer "In3.Cu")
		(net "PCIE_TX3_N")
	)
	(segment
		(start 133.507015 150.42273)
		(end 133.507015 150.42273)
		(width 0.127)
		(layer "In3.Cu")
		(net "PCIE_TX3_N")
	)
	(segment
		(start 129.588595 135.78239)
		(end 129.625185 135.81898)
		(width 0.127)
		(layer "In3.Cu")
		(net "PCIE_TX3_N")
	)
	(segment
		(start 133.510195 150.42592)
		(end 133.519825 150.43524)
		(width 0.127)
		(layer "In3.Cu")
		(net "PCIE_TX3_N")
	)
	(segment
		(start 129.588595 135.78239)
		(end 129.588595 135.7786)
		(width 0.127)
		(layer "In3.Cu")
		(net "PCIE_TX3_N")
	)
	(segment
		(start 132.788595 148.64002)
		(end 132.788595 140.52583)
		(width 0.127)
		(layer "In3.Cu")
		(net "PCIE_TX3_N")
	)
	(arc
		(start 134.030654 150.629214)
		(mid 133.772087 150.560395)
		(end 133.531788 150.44271)
		(width 0.127)
		(layer "In3.Cu")
		(net "PCIE_TX3_N")
	)
	(arc
		(start 134.030659 150.629212)
		(mid 134.039841 150.631067)
		(end 134.048861 150.633594)
		(width 0.127)
		(layer "In3.Cu")
		(net "PCIE_TX3_N")
	)
	(arc
		(start 129.625183 135.818982)
		(mid 129.753749 136.011394)
		(end 129.798895 136.23836)
		(width 0.127)
		(layer "In3.Cu")
		(net "PCIE_TX3_N")
	)
	(arc
		(start 134.275164 150.648606)
		(mid 134.28444 150.647293)
		(end 134.293787 150.646667)
		(width 0.127)
		(layer "In3.Cu")
		(net "PCIE_TX3_N")
	)
	(arc
		(start 133.510196 150.425916)
		(mid 133.50859 150.424335)
		(end 133.507013 150.422726)
		(width 0.127)
		(layer "In3.Cu")
		(net "PCIE_TX3_N")
	)
	(arc
		(start 133.507016 150.42273)
		(mid 132.974072 149.60139)
		(end 132.788599 148.640023)
		(width 0.127)
		(layer "In3.Cu")
		(net "PCIE_TX3_N")
	)
	(arc
		(start 132.044647 138.72978)
		(mid 132.595249 139.553815)
		(end 132.788595 140.52583)
		(width 0.127)
		(layer "In3.Cu")
		(net "PCIE_TX3_N")
	)
	(arc
		(start 135.18859 150.278611)
		(mid 134.774702 150.544116)
		(end 134.293788 150.646673)
		(width 0.127)
		(layer "In3.Cu")
		(net "PCIE_TX3_N")
	)
	(arc
		(start 134.275166 150.648609)
		(mid 134.161092 150.654959)
		(end 134.048857 150.633592)
		(width 0.127)
		(layer "In3.Cu")
		(net "PCIE_TX3_N")
	)
	(arc
		(start 129.97261 136.657745)
		(mid 129.844042 136.46533)
		(end 129.798895 136.23836)
		(width 0.127)
		(layer "In3.Cu")
		(net "PCIE_TX3_N")
	)
	(arc
		(start 133.531788 150.44271)
		(mid 133.525797 150.43899)
		(end 133.519825 150.43524)
		(width 0.127)
		(layer "In3.Cu")
		(net "PCIE_TX3_N")
	)
	(segment
		(start 130.198445 135.68845)
		(end 130.198445 134.20545)
		(width 0.127)
		(layer "F.Cu")
		(net "PCIE_TX3_P")
	)
	(via
		(at 130.288595 135.7786)
		(size 0.4064)
		(drill 0.2032)
		(layers "F.Cu" "B.Cu")
		(net "PCIE_TX3_P")
	)
	(via
		(at 134.192205 150.18609)
		(size 0.4064)
		(drill 0.2032)
		(layers "F.Cu" "B.Cu")
		(net "PCIE_TX3_P")
	)
	(arc
		(start 130.288595 135.7786)
		(mid 130.224849 135.752196)
		(end 130.198445 135.68845)
		(width 0.127)
		(layer "F.Cu")
		(net "PCIE_TX3_P")
	)
	(segment
		(start 134.188595 151.32962)
		(end 134.188595 150.21614)
		(width 0.127)
		(layer "B.Cu")
		(net "PCIE_TX3_P")
	)
	(segment
		(start 134.190585 150.19377)
		(end 134.191905 150.18639)
		(width 0.127)
		(layer "B.Cu")
		(net "PCIE_TX3_P")
	)
	(segment
		(start 134.191905 150.18639)
		(end 134.192205 150.18609)
		(width 0.127)
		(layer "B.Cu")
		(net "PCIE_TX3_P")
	)
	(arc
		(start 134.188605 151.32962)
		(mid 134.185486 151.345302)
		(end 134.176602 151.358597)
		(width 0.127)
		(layer "B.Cu")
		(net "PCIE_TX3_P")
	)
	(arc
		(start 134.188595 150.21614)
		(mid 134.189092 150.20491)
		(end 134.190581 150.193768)
		(width 0.127)
		(layer "B.Cu")
		(net "PCIE_TX3_P")
	)
	(segment
		(start 134.192195 150.1861)
		(end 134.192205 150.18609)
		(width 0.127)
		(layer "In3.Cu")
		(net "PCIE_TX3_P")
	)
	(segment
		(start 133.293475 148.17347)
		(end 133.548565 148.17347)
		(width 0.127)
		(layer "In3.Cu")
		(net "PCIE_TX3_P")
	)
	(segment
		(start 133.297275 148.55447)
		(end 133.548565 148.55447)
		(width 0.127)
		(layer "In3.Cu")
		(net "PCIE_TX3_P")
	)
	(segment
		(start 133.067995 147.91946)
		(end 133.067995 140.03598)
		(width 0.127)
		(layer "In3.Cu")
		(net "PCIE_TX3_P")
	)
	(segment
		(start 130.288595 135.7824)
		(end 130.288595 135.7786)
		(width 0.127)
		(layer "In3.Cu")
		(net "PCIE_TX3_P")
	)
	(segment
		(start 133.843785 149.31647)
		(end 133.843815 149.31647)
		(width 0.127)
		(layer "In3.Cu")
		(net "PCIE_TX3_P")
	)
	(segment
		(start 133.297275 148.93547)
		(end 133.843815 148.93547)
		(width 0.127)
		(layer "In3.Cu")
		(net "PCIE_TX3_P")
	)
	(segment
		(start 133.664615 149.57167)
		(end 133.664615 149.57167)
		(width 0.127)
		(layer "In3.Cu")
		(net "PCIE_TX3_P")
	)
	(segment
		(start 133.664615 149.57167)
		(end 133.746375 149.79808)
		(width 0.127)
		(layer "In3.Cu")
		(net "PCIE_TX3_P")
	)
	(segment
		(start 133.067995 147.91946)
		(end 133.090925 147.98296)
		(width 0.127)
		(layer "In3.Cu")
		(net "PCIE_TX3_P")
	)
	(segment
		(start 133.746375 149.79808)
		(end 134.069625 150.10465)
		(width 0.127)
		(layer "In3.Cu")
		(net "PCIE_TX3_P")
	)
	(segment
		(start 133.114295 148.04767)
		(end 133.114295 148.04767)
		(width 0.127)
		(layer "In3.Cu")
		(net "PCIE_TX3_P")
	)
	(segment
		(start 133.090925 147.98296)
		(end 133.114295 148.04767)
		(width 0.127)
		(layer "In3.Cu")
		(net "PCIE_TX3_P")
	)
	(segment
		(start 130.211095 135.8599)
		(end 130.288595 135.7824)
		(width 0.127)
		(layer "In3.Cu")
		(net "PCIE_TX3_P")
	)
	(segment
		(start 130.211095 136.5011)
		(end 132.588595 138.8786)
		(width 0.127)
		(layer "In3.Cu")
		(net "PCIE_TX3_P")
	)
	(arc
		(start 133.66461 149.571673)
		(mid 133.687875 149.397507)
		(end 133.843785 149.31647)
		(width 0.127)
		(layer "In3.Cu")
		(net "PCIE_TX3_P")
	)
	(arc
		(start 133.843815 148.93547)
		(mid 134.034315 149.12597)
		(end 133.843815 149.31647)
		(width 0.127)
		(layer "In3.Cu")
		(net "PCIE_TX3_P")
	)
	(arc
		(start 132.588593 138.878598)
		(mid 132.943402 139.40961)
		(end 133.067995 140.03598)
		(width 0.127)
		(layer "In3.Cu")
		(net "PCIE_TX3_P")
	)
	(arc
		(start 134.192201 150.186098)
		(mid 134.177643 150.177199)
		(end 134.163174 150.168157)
		(width 0.127)
		(layer "In3.Cu")
		(net "PCIE_TX3_P")
	)
	(arc
		(start 133.297275 148.93547)
		(mid 133.106775 148.74497)
		(end 133.297275 148.55447)
		(width 0.127)
		(layer "In3.Cu")
		(net "PCIE_TX3_P")
	)
	(arc
		(start 130.211093 136.501102)
		(mid 130.112808 136.354009)
		(end 130.078295 136.1805)
		(width 0.127)
		(layer "In3.Cu")
		(net "PCIE_TX3_P")
	)
	(arc
		(start 130.078305 136.1805)
		(mid 130.112817 136.006996)
		(end 130.211099 135.859906)
		(width 0.127)
		(layer "In3.Cu")
		(net "PCIE_TX3_P")
	)
	(arc
		(start 133.293475 148.17347)
		(mid 133.184011 148.13888)
		(end 133.114299 148.04767)
		(width 0.127)
		(layer "In3.Cu")
		(net "PCIE_TX3_P")
	)
	(arc
		(start 134.163174 150.168157)
		(mid 134.115879 150.137175)
		(end 134.069626 150.104657)
		(width 0.127)
		(layer "In3.Cu")
		(net "PCIE_TX3_P")
	)
	(arc
		(start 133.548565 148.17347)
		(mid 133.739065 148.36397)
		(end 133.548565 148.55447)
		(width 0.127)
		(layer "In3.Cu")
		(net "PCIE_TX3_P")
	)
	(segment
		(start 131.198445 140.35482)
		(end 131.198445 138.25523)
		(width 0.127)
		(layer "F.Cu")
		(net "PCIE_TX2_N")
	)
	(via
		(at 131.188595 140.3786)
		(size 0.4064)
		(drill 0.2032)
		(layers "F.Cu" "B.Cu")
		(net "PCIE_TX2_N")
	)
	(via
		(at 130.988595 150.2786)
		(size 0.4064)
		(drill 0.2032)
		(layers "F.Cu" "B.Cu")
		(net "PCIE_TX2_N")
	)
	(arc
		(start 131.198445 140.35482)
		(mid 131.195885 140.36769)
		(end 131.188595 140.3786)
		(width 0.127)
		(layer "F.Cu")
		(net "PCIE_TX2_N")
	)
	(segment
		(start 130.988595 151.32721)
		(end 130.988595 150.2786)
		(width 0.127)
		(layer "B.Cu")
		(net "PCIE_TX2_N")
	)
	(arc
		(start 131.001594 151.358591)
		(mid 130.991974 151.344193)
		(end 130.988596 151.32721)
		(width 0.127)
		(layer "B.Cu")
		(net "PCIE_TX2_N")
	)
	(segment
		(start 129.854845 150.58482)
		(end 129.855525 150.58549)
		(width 0.127)
		(layer "In3.Cu")
		(net "PCIE_TX2_N")
	)
	(segment
		(start 130.678295 150.50319)
		(end 130.678295 150.48196)
		(width 0.127)
		(layer "In3.Cu")
		(net "PCIE_TX2_N")
	)
	(segment
		(start 131.448895 148.0657)
		(end 131.448895 141.00702)
		(width 0.127)
		(layer "In3.Cu")
		(net "PCIE_TX2_N")
	)
	(segment
		(start 129.694105 150.22666)
		(end 129.694155 150.22751)
		(width 0.127)
		(layer "In3.Cu")
		(net "PCIE_TX2_N")
	)
	(segment
		(start 129.912215 149.65497)
		(end 131.411555 148.15566)
		(width 0.127)
		(layer "In3.Cu")
		(net "PCIE_TX2_N")
	)
	(segment
		(start 130.828195 150.33206)
		(end 130.859535 150.33206)
		(width 0.127)
		(layer "In3.Cu")
		(net "PCIE_TX2_N")
	)
	(segment
		(start 129.911655 149.65553)
		(end 129.912215 149.65497)
		(width 0.127)
		(layer "In3.Cu")
		(net "PCIE_TX2_N")
	)
	(arc
		(start 130.678295 150.50319)
		(mid 130.667688 150.553999)
		(end 130.63764 150.596322)
		(width 0.127)
		(layer "In3.Cu")
		(net "PCIE_TX2_N")
	)
	(arc
		(start 130.637641 150.596325)
		(mid 130.244404 150.747996)
		(end 129.85552 150.585491)
		(width 0.127)
		(layer "In3.Cu")
		(net "PCIE_TX2_N")
	)
	(arc
		(start 130.988596 150.278601)
		(mid 130.929382 150.318166)
		(end 130.859535 150.33206)
		(width 0.127)
		(layer "In3.Cu")
		(net "PCIE_TX2_N")
	)
	(arc
		(start 129.854837 150.584826)
		(mid 129.741837 150.420854)
		(end 129.694154 150.227509)
		(width 0.127)
		(layer "In3.Cu")
		(net "PCIE_TX2_N")
	)
	(arc
		(start 131.188602 140.378593)
		(mid 131.381254 140.666918)
		(end 131.448905 141.00702)
		(width 0.127)
		(layer "In3.Cu")
		(net "PCIE_TX2_N")
	)
	(arc
		(start 130.7222 150.375965)
		(mid 130.770831 150.343471)
		(end 130.828195 150.33206)
		(width 0.127)
		(layer "In3.Cu")
		(net "PCIE_TX2_N")
	)
	(arc
		(start 130.678295 150.48196)
		(mid 130.689705 150.424597)
		(end 130.722198 150.375966)
		(width 0.127)
		(layer "In3.Cu")
		(net "PCIE_TX2_N")
	)
	(arc
		(start 129.694098 150.226667)
		(mid 129.74261 149.918146)
		(end 129.911646 149.655534)
		(width 0.127)
		(layer "In3.Cu")
		(net "PCIE_TX2_N")
	)
	(arc
		(start 131.448895 148.0657)
		(mid 131.439188 148.114397)
		(end 131.41155 148.15565)
		(width 0.127)
		(layer "In3.Cu")
		(net "PCIE_TX2_N")
	)
	(segment
		(start 131.698315 139.6778)
		(end 131.698315 138.25523)
		(width 0.127)
		(layer "F.Cu")
		(net "PCIE_TX2_P")
	)
	(via
		(at 131.988595 140.3786)
		(size 0.4064)
		(drill 0.2032)
		(layers "F.Cu" "B.Cu")
		(net "PCIE_TX2_P")
	)
	(via
		(at 130.166965 150.21916)
		(size 0.4064)
		(drill 0.2032)
		(layers "F.Cu" "B.Cu")
		(net "PCIE_TX2_P")
	)
	(arc
		(start 131.988596 140.378599)
		(mid 131.773757 140.05707)
		(end 131.698316 139.6778)
		(width 0.127)
		(layer "F.Cu")
		(net "PCIE_TX2_P")
	)
	(segment
		(start 130.088595 151.30066)
		(end 130.088595 150.33546)
		(width 0.127)
		(layer "B.Cu")
		(net "PCIE_TX2_P")
	)
	(arc
		(start 130.088599 150.335451)
		(mid 130.110278 150.265506)
		(end 130.16697 150.219157)
		(width 0.127)
		(layer "B.Cu")
		(net "PCIE_TX2_P")
	)
	(arc
		(start 130.112595 151.3586)
		(mid 130.094833 151.332017)
		(end 130.088595 151.30066)
		(width 0.127)
		(layer "B.Cu")
		(net "PCIE_TX2_P")
	)
	(segment
		(start 131.728295 148.24551)
		(end 131.728295 147.64552)
		(width 0.127)
		(layer "In3.Cu")
		(net "PCIE_TX2_P")
	)
	(segment
		(start 130.159365 150.22158)
		(end 130.161785 150.21916)
		(width 0.127)
		(layer "In3.Cu")
		(net "PCIE_TX2_P")
	)
	(segment
		(start 131.623305 148.40311)
		(end 131.668205 148.35821)
		(width 0.127)
		(layer "In3.Cu")
		(net "PCIE_TX2_P")
	)
	(segment
		(start 130.023105 150.11074)
		(end 130.051615 149.97478)
		(width 0.127)
		(layer "In3.Cu")
		(net "PCIE_TX2_P")
	)
	(segment
		(start 131.623295 148.40311)
		(end 131.623305 148.40311)
		(width 0.127)
		(layer "In3.Cu")
		(net "PCIE_TX2_P")
	)
	(segment
		(start 130.161785 150.21916)
		(end 130.166965 150.21916)
		(width 0.127)
		(layer "In3.Cu")
		(net "PCIE_TX2_P")
	)
	(segment
		(start 130.078635 150.25308)
		(end 130.110135 150.22158)
		(width 0.127)
		(layer "In3.Cu")
		(net "PCIE_TX2_P")
	)
	(segment
		(start 131.728295 147.64552)
		(end 131.728295 141.00702)
		(width 0.127)
		(layer "In3.Cu")
		(net "PCIE_TX2_P")
	)
	(segment
		(start 130.110135 150.22158)
		(end 130.159365 150.22158)
		(width 0.127)
		(layer "In3.Cu")
		(net "PCIE_TX2_P")
	)
	(segment
		(start 130.023105 150.11074)
		(end 130.031145 150.13135)
		(width 0.127)
		(layer "In3.Cu")
		(net "PCIE_TX2_P")
	)
	(segment
		(start 130.051615 149.97478)
		(end 130.545665 149.48074)
		(width 0.127)
		(layer "In3.Cu")
		(net "PCIE_TX2_P")
	)
	(segment
		(start 130.815065 149.48075)
		(end 130.917215 149.5829)
		(width 0.127)
		(layer "In3.Cu")
		(net "PCIE_TX2_P")
	)
	(segment
		(start 131.668205 148.35821)
		(end 131.668205 148.35821)
		(width 0.127)
		(layer "In3.Cu")
		(net "PCIE_TX2_P")
	)
	(segment
		(start 130.031145 150.13135)
		(end 130.078635 150.25308)
		(width 0.127)
		(layer "In3.Cu")
		(net "PCIE_TX2_P")
	)
	(segment
		(start 131.668205 148.35821)
		(end 131.690545 148.33587)
		(width 0.127)
		(layer "In3.Cu")
		(net "PCIE_TX2_P")
	)
	(segment
		(start 131.988595 140.3786)
		(end 131.988595 140.3786)
		(width 0.127)
		(layer "In3.Cu")
		(net "PCIE_TX2_P")
	)
	(segment
		(start 131.034475 149.16134)
		(end 131.186625 149.31349)
		(width 0.127)
		(layer "In3.Cu")
		(net "PCIE_TX2_P")
	)
	(segment
		(start 131.303885 148.89193)
		(end 131.456035 149.04408)
		(width 0.127)
		(layer "In3.Cu")
		(net "PCIE_TX2_P")
	)
	(segment
		(start 131.623295 148.67252)
		(end 131.725445 148.77468)
		(width 0.127)
		(layer "In3.Cu")
		(net "PCIE_TX2_P")
	)
	(arc
		(start 131.728295 148.24551)
		(mid 131.718627 148.294112)
		(end 131.691095 148.335315)
		(width 0.127)
		(layer "In3.Cu")
		(net "PCIE_TX2_P")
	)
	(arc
		(start 131.186626 149.582896)
		(mid 131.051924 149.63869)
		(end 130.917222 149.582894)
		(width 0.127)
		(layer "In3.Cu")
		(net "PCIE_TX2_P")
	)
	(arc
		(start 131.725446 149.044086)
		(mid 131.590744 149.09988)
		(end 131.456042 149.044084)
		(width 0.127)
		(layer "In3.Cu")
		(net "PCIE_TX2_P")
	)
	(arc
		(start 131.623292 148.672525)
		(mid 131.567495 148.537821)
		(end 131.623291 148.403116)
		(width 0.127)
		(layer "In3.Cu")
		(net "PCIE_TX2_P")
	)
	(arc
		(start 130.545662 149.480745)
		(mid 130.680366 149.42495)
		(end 130.815069 149.480746)
		(width 0.127)
		(layer "In3.Cu")
		(net "PCIE_TX2_P")
	)
	(arc
		(start 131.728295 141.00702)
		(mid 131.795945 140.666922)
		(end 131.988594 140.378601)
		(width 0.127)
		(layer "In3.Cu")
		(net "PCIE_TX2_P")
	)
	(arc
		(start 131.690544 148.335872)
		(mid 131.690823 148.335594)
		(end 131.691102 148.335317)
		(width 0.127)
		(layer "In3.Cu")
		(net "PCIE_TX2_P")
	)
	(arc
		(start 131.034481 149.161334)
		(mid 130.978685 149.026632)
		(end 131.034478 148.891929)
		(width 0.127)
		(layer "In3.Cu")
		(net "PCIE_TX2_P")
	)
	(arc
		(start 131.725449 148.774676)
		(mid 131.781245 148.90938)
		(end 131.725449 149.044084)
		(width 0.127)
		(layer "In3.Cu")
		(net "PCIE_TX2_P")
	)
	(arc
		(start 131.034481 148.891936)
		(mid 131.169185 148.83614)
		(end 131.303889 148.891936)
		(width 0.127)
		(layer "In3.Cu")
		(net "PCIE_TX2_P")
	)
	(arc
		(start 131.186629 149.313486)
		(mid 131.242425 149.44819)
		(end 131.186629 149.582894)
		(width 0.127)
		(layer "In3.Cu")
		(net "PCIE_TX2_P")
	)
	(segment
		(start 128.198455 139.51772)
		(end 128.198455 138.25523)
		(width 0.127)
		(layer "F.Cu")
		(net "PCIE_TX1_N")
	)
	(segment
		(start 127.888595 140.26578)
		(end 127.888595 140.26658)
		(width 0.127)
		(layer "F.Cu")
		(net "PCIE_TX1_N")
	)
	(segment
		(start 127.888595 140.3786)
		(end 127.888595 140.26658)
		(width 0.127)
		(layer "F.Cu")
		(net "PCIE_TX1_N")
	)
	(via
		(at 127.188595 150.2786)
		(size 0.4064)
		(drill 0.2032)
		(layers "F.Cu" "B.Cu")
		(net "PCIE_TX1_N")
	)
	(via
		(at 127.888595 140.3786)
		(size 0.4064)
		(drill 0.2032)
		(layers "F.Cu" "B.Cu")
		(net "PCIE_TX1_N")
	)
	(arc
		(start 127.888595 140.26578)
		(mid 127.94137 140.000465)
		(end 128.091659 139.775542)
		(width 0.127)
		(layer "F.Cu")
		(net "PCIE_TX1_N")
	)
	(arc
		(start 128.198455 139.51772)
		(mid 128.170701 139.65725)
		(end 128.091663 139.775538)
		(width 0.127)
		(layer "F.Cu")
		(net "PCIE_TX1_N")
	)
	(segment
		(start 127.188595 151.3556)
		(end 127.188595 150.2786)
		(width 0.127)
		(layer "B.Cu")
		(net "PCIE_TX1_N")
	)
	(segment
		(start 127.188595 151.3556)
		(end 127.191595 151.3586)
		(width 0.127)
		(layer "B.Cu")
		(net "PCIE_TX1_N")
	)
	(segment
		(start 127.857135 147.79096)
		(end 127.933795 147.79096)
		(width 0.127)
		(layer "In3.Cu")
		(net "PCIE_TX1_N")
	)
	(segment
		(start 127.908375 148.93396)
		(end 127.933795 148.93396)
		(width 0.127)
		(layer "In3.Cu")
		(net "PCIE_TX1_N")
	)
	(segment
		(start 127.908375 149.31496)
		(end 127.908395 149.31496)
		(width 0.127)
		(layer "In3.Cu")
		(net "PCIE_TX1_N")
	)
	(segment
		(start 127.966695 150.2242)
		(end 127.967105 150.22366)
		(width 0.127)
		(layer "In3.Cu")
		(net "PCIE_TX1_N")
	)
	(segment
		(start 128.098895 146.77495)
		(end 128.098895 140.8901)
		(width 0.127)
		(layer "In3.Cu")
		(net "PCIE_TX1_N")
	)
	(segment
		(start 127.888595 140.3824)
		(end 127.888595 140.3786)
		(width 0.127)
		(layer "In3.Cu")
		(net "PCIE_TX1_N")
	)
	(segment
		(start 127.188595 150.27861)
		(end 127.188595 150.2786)
		(width 0.127)
		(layer "In3.Cu")
		(net "PCIE_TX1_N")
	)
	(segment
		(start 127.886855 148.55296)
		(end 127.933795 148.55296)
		(width 0.127)
		(layer "In3.Cu")
		(net "PCIE_TX1_N")
	)
	(segment
		(start 127.886855 148.17196)
		(end 127.933795 148.17196)
		(width 0.127)
		(layer "In3.Cu")
		(net "PCIE_TX1_N")
	)
	(segment
		(start 127.857135 147.40996)
		(end 127.908395 147.40996)
		(width 0.127)
		(layer "In3.Cu")
		(net "PCIE_TX1_N")
	)
	(segment
		(start 127.984215 150.19983)
		(end 128.098895 149.82947)
		(width 0.127)
		(layer "In3.Cu")
		(net "PCIE_TX1_N")
	)
	(segment
		(start 128.098895 149.82947)
		(end 128.098895 149.50546)
		(width 0.127)
		(layer "In3.Cu")
		(net "PCIE_TX1_N")
	)
	(segment
		(start 128.098895 147.21946)
		(end 128.098895 146.77495)
		(width 0.127)
		(layer "In3.Cu")
		(net "PCIE_TX1_N")
	)
	(arc
		(start 127.857135 147.79096)
		(mid 127.666635 147.60046)
		(end 127.857135 147.40996)
		(width 0.127)
		(layer "In3.Cu")
		(net "PCIE_TX1_N")
	)
	(arc
		(start 127.908375 149.31496)
		(mid 127.717875 149.12446)
		(end 127.908375 148.93396)
		(width 0.127)
		(layer "In3.Cu")
		(net "PCIE_TX1_N")
	)
	(arc
		(start 127.933795 148.55296)
		(mid 128.124295 148.74346)
		(end 127.933795 148.93396)
		(width 0.127)
		(layer "In3.Cu")
		(net "PCIE_TX1_N")
	)
	(arc
		(start 127.933795 147.79096)
		(mid 128.124295 147.98146)
		(end 127.933795 148.17196)
		(width 0.127)
		(layer "In3.Cu")
		(net "PCIE_TX1_N")
	)
	(arc
		(start 127.984214 150.199831)
		(mid 127.97579 150.211839)
		(end 127.967099 150.223656)
		(width 0.127)
		(layer "In3.Cu")
		(net "PCIE_TX1_N")
	)
	(arc
		(start 127.888595 140.38239)
		(mid 128.04424 140.615329)
		(end 128.098895 140.8901)
		(width 0.127)
		(layer "In3.Cu")
		(net "PCIE_TX1_N")
	)
	(arc
		(start 128.098895 147.21946)
		(mid 128.043099 147.354164)
		(end 127.908395 147.40996)
		(width 0.127)
		(layer "In3.Cu")
		(net "PCIE_TX1_N")
	)
	(arc
		(start 127.908395 149.31496)
		(mid 128.043099 149.370756)
		(end 128.098895 149.50546)
		(width 0.127)
		(layer "In3.Cu")
		(net "PCIE_TX1_N")
	)
	(arc
		(start 127.886855 148.55296)
		(mid 127.696355 148.36246)
		(end 127.886855 148.17196)
		(width 0.127)
		(layer "In3.Cu")
		(net "PCIE_TX1_N")
	)
	(arc
		(start 127.96669 150.224197)
		(mid 127.950654 150.244173)
		(end 127.933653 150.263334)
		(width 0.127)
		(layer "In3.Cu")
		(net "PCIE_TX1_N")
	)
	(arc
		(start 127.933653 150.263333)
		(mid 127.564351 150.42845)
		(end 127.188592 150.278605)
		(width 0.127)
		(layer "In3.Cu")
		(net "PCIE_TX1_N")
	)
	(segment
		(start 128.698325 140.11369)
		(end 128.698325 138.25523)
		(width 0.127)
		(layer "F.Cu")
		(net "PCIE_TX1_P")
	)
	(via
		(at 128.588595 140.3786)
		(size 0.4064)
		(drill 0.2032)
		(layers "F.Cu" "B.Cu")
		(net "PCIE_TX1_P")
	)
	(via
		(at 126.188595 150.2786)
		(size 0.4064)
		(drill 0.2032)
		(layers "F.Cu" "B.Cu")
		(net "PCIE_TX1_P")
	)
	(arc
		(start 128.698325 140.11369)
		(mid 128.669807 140.257059)
		(end 128.588595 140.3786)
		(width 0.127)
		(layer "F.Cu")
		(net "PCIE_TX1_P")
	)
	(segment
		(start 126.188595 151.32721)
		(end 126.188595 150.2786)
		(width 0.127)
		(layer "B.Cu")
		(net "PCIE_TX1_P")
	)
	(arc
		(start 126.188595 151.32721)
		(mid 126.185217 151.344193)
		(end 126.175596 151.358591)
		(width 0.127)
		(layer "B.Cu")
		(net "PCIE_TX1_P")
	)
	(segment
		(start 126.188595 150.2786)
		(end 126.344785 150.4348)
		(width 0.127)
		(layer "In3.Cu")
		(net "PCIE_TX1_P")
	)
	(segment
		(start 128.378295 149.8509)
		(end 128.378295 149.84976)
		(width 0.127)
		(layer "In3.Cu")
		(net "PCIE_TX1_P")
	)
	(segment
		(start 126.344785 150.4348)
		(end 126.344785 150.4348)
		(width 0.127)
		(layer "In3.Cu")
		(net "PCIE_TX1_P")
	)
	(segment
		(start 128.378295 149.84976)
		(end 128.378295 140.8901)
		(width 0.127)
		(layer "In3.Cu")
		(net "PCIE_TX1_P")
	)
	(segment
		(start 128.588595 140.3824)
		(end 128.588595 140.3824)
		(width 0.127)
		(layer "In3.Cu")
		(net "PCIE_TX1_P")
	)
	(segment
		(start 128.588595 140.3824)
		(end 128.588595 140.3786)
		(width 0.127)
		(layer "In3.Cu")
		(net "PCIE_TX1_P")
	)
	(arc
		(start 128.378295 140.8901)
		(mid 128.43295 140.615331)
		(end 128.588593 140.382392)
		(width 0.127)
		(layer "In3.Cu")
		(net "PCIE_TX1_P")
	)
	(arc
		(start 128.378285 149.850895)
		(mid 128.266811 150.285644)
		(end 127.959901 150.613118)
		(width 0.127)
		(layer "In3.Cu")
		(net "PCIE_TX1_P")
	)
	(arc
		(start 127.959908 150.613118)
		(mid 127.12098 150.808083)
		(end 126.344792 150.434794)
		(width 0.127)
		(layer "In3.Cu")
		(net "PCIE_TX1_P")
	)
	(segment
		(start 126.698325 135.66887)
		(end 126.698325 134.20545)
		(width 0.127)
		(layer "F.Cu")
		(net "PCIE_TX0_N")
	)
	(via
		(at 122.288595 150.2786)
		(size 0.4064)
		(drill 0.2032)
		(layers "F.Cu" "B.Cu")
		(net "PCIE_TX0_N")
	)
	(via
		(at 126.588595 135.7786)
		(size 0.4064)
		(drill 0.2032)
		(layers "F.Cu" "B.Cu")
		(net "PCIE_TX0_N")
	)
	(arc
		(start 126.698325 135.66887)
		(mid 126.666186 135.746461)
		(end 126.588595 135.7786)
		(width 0.127)
		(layer "F.Cu")
		(net "PCIE_TX0_N")
	)
	(segment
		(start 122.288595 151.3578)
		(end 122.288595 150.2786)
		(width 0.127)
		(layer "B.Cu")
		(net "PCIE_TX0_N")
	)
	(segment
		(start 122.288595 151.3578)
		(end 122.289395 151.3586)
		(width 0.127)
		(layer "B.Cu")
		(net "PCIE_TX0_N")
	)
	(segment
		(start 121.270595 150.66721)
		(end 121.435795 150.66721)
		(width 0.127)
		(layer "In3.Cu")
		(net "PCIE_TX0_N")
	)
	(segment
		(start 121.134005 142.03319)
		(end 121.134975 142.03222)
		(width 0.127)
		(layer "In3.Cu")
		(net "PCIE_TX0_N")
	)
	(segment
		(start 121.435795 150.66721)
		(end 121.436935 150.66721)
		(width 0.127)
		(layer "In3.Cu")
		(net "PCIE_TX0_N")
	)
	(segment
		(start 121.134975 142.03222)
		(end 121.388595 141.7786)
		(width 0.127)
		(layer "In3.Cu")
		(net "PCIE_TX0_N")
	)
	(segment
		(start 121.388595 141.7786)
		(end 126.666095 136.5011)
		(width 0.127)
		(layer "In3.Cu")
		(net "PCIE_TX0_N")
	)
	(segment
		(start 126.798895 136.1805)
		(end 126.798895 136.1805)
		(width 0.127)
		(layer "In3.Cu")
		(net "PCIE_TX0_N")
	)
	(segment
		(start 126.588595 135.7824)
		(end 126.588595 135.7786)
		(width 0.127)
		(layer "In3.Cu")
		(net "PCIE_TX0_N")
	)
	(segment
		(start 121.436935 150.66721)
		(end 121.899985 150.66721)
		(width 0.127)
		(layer "In3.Cu")
		(net "PCIE_TX0_N")
	)
	(segment
		(start 120.088595 144.55621)
		(end 120.088595 149.48522)
		(width 0.127)
		(layer "In3.Cu")
		(net "PCIE_TX0_N")
	)
	(segment
		(start 126.588595 135.7824)
		(end 126.666095 135.8599)
		(width 0.127)
		(layer "In3.Cu")
		(net "PCIE_TX0_N")
	)
	(arc
		(start 120.088595 144.556205)
		(mid 120.360443 143.190758)
		(end 121.133999 142.033192)
		(width 0.127)
		(layer "In3.Cu")
		(net "PCIE_TX0_N")
	)
	(arc
		(start 126.798895 136.1805)
		(mid 126.764383 136.354005)
		(end 126.6661 136.501095)
		(width 0.127)
		(layer "In3.Cu")
		(net "PCIE_TX0_N")
	)
	(arc
		(start 121.270598 150.66722)
		(mid 120.434799 150.321024)
		(end 120.088595 149.485228)
		(width 0.127)
		(layer "In3.Cu")
		(net "PCIE_TX0_N")
	)
	(arc
		(start 126.666107 135.859898)
		(mid 126.764392 136.006991)
		(end 126.798905 136.1805)
		(width 0.127)
		(layer "In3.Cu")
		(net "PCIE_TX0_N")
	)
	(arc
		(start 122.288595 150.2786)
		(mid 122.174774 150.553389)
		(end 121.899985 150.66721)
		(width 0.127)
		(layer "In3.Cu")
		(net "PCIE_TX0_N")
	)
	(segment
		(start 127.198455 135.68846)
		(end 127.198455 134.20545)
		(width 0.127)
		(layer "F.Cu")
		(net "PCIE_TX0_P")
	)
	(via
		(at 121.223615 150.1395)
		(size 0.4064)
		(drill 0.2032)
		(layers "F.Cu" "B.Cu")
		(net "PCIE_TX0_P")
	)
	(via
		(at 127.288595 135.7786)
		(size 0.4064)
		(drill 0.2032)
		(layers "F.Cu" "B.Cu")
		(net "PCIE_TX0_P")
	)
	(arc
		(start 127.288595 135.7786)
		(mid 127.224856 135.752199)
		(end 127.198455 135.68846)
		(width 0.127)
		(layer "F.Cu")
		(net "PCIE_TX0_P")
	)
	(segment
		(start 121.223315 150.1398)
		(end 121.223615 150.1395)
		(width 0.127)
		(layer "B.Cu")
		(net "PCIE_TX0_P")
	)
	(segment
		(start 121.188595 150.29143)
		(end 121.189285 150.22501)
		(width 0.127)
		(layer "B.Cu")
		(net "PCIE_TX0_P")
	)
	(segment
		(start 121.188595 151.35)
		(end 121.188595 150.29143)
		(width 0.127)
		(layer "B.Cu")
		(net "PCIE_TX0_P")
	)
	(segment
		(start 121.188595 151.35)
		(end 121.197195 151.3586)
		(width 0.127)
		(layer "B.Cu")
		(net "PCIE_TX0_P")
	)
	(segment
		(start 121.221995 150.14126)
		(end 121.223315 150.1398)
		(width 0.127)
		(layer "B.Cu")
		(net "PCIE_TX0_P")
	)
	(arc
		(start 121.189292 150.225012)
		(mid 121.197984 150.180146)
		(end 121.221995 150.141261)
		(width 0.127)
		(layer "B.Cu")
		(net "PCIE_TX0_P")
	)
	(segment
		(start 120.637315 149.92019)
		(end 120.797825 150.05714)
		(width 0.127)
		(layer "In3.Cu")
		(net "PCIE_TX0_P")
	)
	(segment
		(start 121.223315 150.13979)
		(end 121.223615 150.1395)
		(width 0.127)
		(layer "In3.Cu")
		(net "PCIE_TX0_P")
	)
	(segment
		(start 127.288595 135.7824)
		(end 127.288595 135.7786)
		(width 0.127)
		(layer "In3.Cu")
		(net "PCIE_TX0_P")
	)
	(segment
		(start 120.779095 149.06858)
		(end 120.942805 149.06858)
		(width 0.127)
		(layer "In3.Cu")
		(net "PCIE_TX0_P")
	)
	(segment
		(start 121.217365 150.1417)
		(end 121.223315 150.13979)
		(width 0.127)
		(layer "In3.Cu")
		(net "PCIE_TX0_P")
	)
	(segment
		(start 120.533095 148.30658)
		(end 120.889415 148.30658)
		(width 0.127)
		(layer "In3.Cu")
		(net "PCIE_TX0_P")
	)
	(segment
		(start 120.779095 147.92558)
		(end 120.889415 147.92558)
		(width 0.127)
		(layer "In3.Cu")
		(net "PCIE_TX0_P")
	)
	(segment
		(start 120.533095 148.68758)
		(end 120.942805 148.68758)
		(width 0.127)
		(layer "In3.Cu")
		(net "PCIE_TX0_P")
	)
	(segment
		(start 121.332545 142.22978)
		(end 121.586165 141.97617)
		(width 0.127)
		(layer "In3.Cu")
		(net "PCIE_TX0_P")
	)
	(segment
		(start 120.588595 147.73508)
		(end 120.588595 146.3036)
		(width 0.127)
		(layer "In3.Cu")
		(net "PCIE_TX0_P")
	)
	(segment
		(start 120.798565 150.05777)
		(end 120.798975 150.05813)
		(width 0.127)
		(layer "In3.Cu")
		(net "PCIE_TX0_P")
	)
	(segment
		(start 127.252005 135.81898)
		(end 127.288595 135.7824)
		(width 0.127)
		(layer "In3.Cu")
		(net "PCIE_TX0_P")
	)
	(segment
		(start 120.588595 146.3036)
		(end 120.588595 144.02583)
		(width 0.127)
		(layer "In3.Cu")
		(net "PCIE_TX0_P")
	)
	(segment
		(start 121.586165 141.97617)
		(end 126.904585 136.65774)
		(width 0.127)
		(layer "In3.Cu")
		(net "PCIE_TX0_P")
	)
	(segment
		(start 120.588595 149.8152)
		(end 120.588595 149.7036)
		(width 0.127)
		(layer "In3.Cu")
		(net "PCIE_TX0_P")
	)
	(segment
		(start 120.588595 149.7036)
		(end 120.588595 149.25908)
		(width 0.127)
		(layer "In3.Cu")
		(net "PCIE_TX0_P")
	)
	(arc
		(start 127.078295 136.23836)
		(mid 127.123441 136.011394)
		(end 127.252007 135.818982)
		(width 0.127)
		(layer "In3.Cu")
		(net "PCIE_TX0_P")
	)
	(arc
		(start 120.779095 147.92558)
		(mid 120.644391 147.869784)
		(end 120.588595 147.73508)
		(width 0.127)
		(layer "In3.Cu")
		(net "PCIE_TX0_P")
	)
	(arc
		(start 120.889415 147.92558)
		(mid 121.079915 148.11608)
		(end 120.889415 148.30658)
		(width 0.127)
		(layer "In3.Cu")
		(net "PCIE_TX0_P")
	)
	(arc
		(start 120.588595 149.25908)
		(mid 120.644391 149.124376)
		(end 120.779095 149.06858)
		(width 0.127)
		(layer "In3.Cu")
		(net "PCIE_TX0_P")
	)
	(arc
		(start 120.637315 149.920194)
		(mid 120.60114 149.873181)
		(end 120.5886 149.815202)
		(width 0.127)
		(layer "In3.Cu")
		(net "PCIE_TX0_P")
	)
	(arc
		(start 121.217369 150.141701)
		(mid 120.997298 150.154352)
		(end 120.798974 150.058129)
		(width 0.127)
		(layer "In3.Cu")
		(net "PCIE_TX0_P")
	)
	(arc
		(start 127.078295 136.23836)
		(mid 127.033148 136.46533)
		(end 126.90458 136.657745)
		(width 0.127)
		(layer "In3.Cu")
		(net "PCIE_TX0_P")
	)
	(arc
		(start 120.533095 148.68758)
		(mid 120.342595 148.49708)
		(end 120.533095 148.30658)
		(width 0.127)
		(layer "In3.Cu")
		(net "PCIE_TX0_P")
	)
	(arc
		(start 120.942805 148.68758)
		(mid 121.133305 148.87808)
		(end 120.942805 149.06858)
		(width 0.127)
		(layer "In3.Cu")
		(net "PCIE_TX0_P")
	)
	(arc
		(start 120.797822 150.057141)
		(mid 120.798193 150.057457)
		(end 120.798563 150.057774)
		(width 0.127)
		(layer "In3.Cu")
		(net "PCIE_TX0_P")
	)
	(arc
		(start 120.588595 144.02583)
		(mid 120.781941 143.053814)
		(end 121.332544 142.229779)
		(width 0.127)
		(layer "In3.Cu")
		(net "PCIE_TX0_P")
	)
	(segment
		(start 125.698325 138.78942)
		(end 125.698325 138.25523)
		(width 0.127)
		(layer "F.Cu")
		(net "PCIE_CLK_P")
	)
	(segment
		(start 125.188595 140.3786)
		(end 125.188595 140.02002)
		(width 0.127)
		(layer "F.Cu")
		(net "PCIE_CLK_P")
	)
	(via
		(at 125.188595 140.3786)
		(size 0.4064)
		(drill 0.2032)
		(layers "F.Cu" "B.Cu")
		(net "PCIE_CLK_P")
	)
	(via
		(at 118.188595 150.2786)
		(size 0.4064)
		(drill 0.2032)
		(layers "F.Cu" "B.Cu")
		(net "PCIE_CLK_P")
	)
	(arc
		(start 125.188595 140.02002)
		(mid 125.214584 139.889364)
		(end 125.288595 139.7786)
		(width 0.127)
		(layer "F.Cu")
		(net "PCIE_CLK_P")
	)
	(arc
		(start 125.698335 138.78942)
		(mid 125.591849 139.324764)
		(end 125.288601 139.778606)
		(width 0.127)
		(layer "F.Cu")
		(net "PCIE_CLK_P")
	)
	(segment
		(start 118.188595 151.3248)
		(end 118.188595 150.2786)
		(width 0.127)
		(layer "B.Cu")
		(net "PCIE_CLK_P")
	)
	(arc
		(start 118.188595 151.3248)
		(mid 118.184956 151.343092)
		(end 118.174595 151.3586)
		(width 0.127)
		(layer "B.Cu")
		(net "PCIE_CLK_P")
	)
	(segment
		(start 120.708165 151.858)
		(end 122.889815 151.858)
		(width 0.127)
		(layer "In3.Cu")
		(net "PCIE_CLK_P")
	)
	(segment
		(start 118.548895 150.48033)
		(end 118.548895 150.42247)
		(width 0.127)
		(layer "In3.Cu")
		(net "PCIE_CLK_P")
	)
	(segment
		(start 125.188595 140.3824)
		(end 125.188595 140.3824)
		(width 0.127)
		(layer "In3.Cu")
		(net "PCIE_CLK_P")
	)
	(segment
		(start 123.085295 151.77703)
		(end 124.153495 150.70883)
		(width 0.127)
		(layer "In3.Cu")
		(net "PCIE_CLK_P")
	)
	(segment
		(start 118.627005 150.66891)
		(end 119.185295 151.2272)
		(width 0.127)
		(layer "In3.Cu")
		(net "PCIE_CLK_P")
	)
	(segment
		(start 125.188595 140.3824)
		(end 125.188595 140.3824)
		(width 0.127)
		(layer "In3.Cu")
		(net "PCIE_CLK_P")
	)
	(segment
		(start 118.229315 150.29547)
		(end 118.421895 150.29547)
		(width 0.127)
		(layer "In3.Cu")
		(net "PCIE_CLK_P")
	)
	(segment
		(start 124.978295 148.71758)
		(end 124.978295 140.8901)
		(width 0.127)
		(layer "In3.Cu")
		(net "PCIE_CLK_P")
	)
	(segment
		(start 125.188595 140.3824)
		(end 125.188595 140.3786)
		(width 0.127)
		(layer "In3.Cu")
		(net "PCIE_CLK_P")
	)
	(arc
		(start 120.708165 151.858)
		(mid 119.883991 151.694062)
		(end 119.18529 151.227205)
		(width 0.127)
		(layer "In3.Cu")
		(net "PCIE_CLK_P")
	)
	(arc
		(start 118.229315 150.29547)
		(mid 118.207276 150.291086)
		(end 118.188593 150.278602)
		(width 0.127)
		(layer "In3.Cu")
		(net "PCIE_CLK_P")
	)
	(arc
		(start 124.978295 140.8901)
		(mid 125.03295 140.615331)
		(end 125.188593 140.382392)
		(width 0.127)
		(layer "In3.Cu")
		(net "PCIE_CLK_P")
	)
	(arc
		(start 118.511698 150.332667)
		(mid 118.539228 150.373869)
		(end 118.548896 150.42247)
		(width 0.127)
		(layer "In3.Cu")
		(net "PCIE_CLK_P")
	)
	(arc
		(start 124.978305 148.71758)
		(mid 124.763945 149.79524)
		(end 124.1535 150.708835)
		(width 0.127)
		(layer "In3.Cu")
		(net "PCIE_CLK_P")
	)
	(arc
		(start 118.421895 150.29547)
		(mid 118.470496 150.305137)
		(end 118.511698 150.332667)
		(width 0.127)
		(layer "In3.Cu")
		(net "PCIE_CLK_P")
	)
	(arc
		(start 118.627007 150.668908)
		(mid 118.569196 150.582388)
		(end 118.548895 150.48033)
		(width 0.127)
		(layer "In3.Cu")
		(net "PCIE_CLK_P")
	)
	(arc
		(start 123.085295 151.77703)
		(mid 122.995608 151.836957)
		(end 122.889815 151.858)
		(width 0.127)
		(layer "In3.Cu")
		(net "PCIE_CLK_P")
	)
	(segment
		(start 125.198455 139.07194)
		(end 125.198455 138.25523)
		(width 0.127)
		(layer "F.Cu")
		(net "PCIE_CLK_N")
	)
	(segment
		(start 124.700725 139.86646)
		(end 124.988595 139.5786)
		(width 0.127)
		(layer "F.Cu")
		(net "PCIE_CLK_N")
	)
	(via
		(at 124.488595 140.3786)
		(size 0.4064)
		(drill 0.2032)
		(layers "F.Cu" "B.Cu")
		(net "PCIE_CLK_N")
	)
	(via
		(at 119.188595 150.2786)
		(size 0.4064)
		(drill 0.2032)
		(layers "F.Cu" "B.Cu")
		(net "PCIE_CLK_N")
	)
	(arc
		(start 125.198465 139.07194)
		(mid 125.143923 139.34614)
		(end 124.988601 139.578596)
		(width 0.127)
		(layer "F.Cu")
		(net "PCIE_CLK_N")
	)
	(arc
		(start 124.488595 140.3786)
		(mid 124.543727 140.101434)
		(end 124.700729 139.866464)
		(width 0.127)
		(layer "F.Cu")
		(net "PCIE_CLK_N")
	)
	(segment
		(start 119.188595 151.3566)
		(end 119.190595 151.3586)
		(width 0.127)
		(layer "B.Cu")
		(net "PCIE_CLK_N")
	)
	(segment
		(start 119.188595 151.3566)
		(end 119.188595 150.2786)
		(width 0.127)
		(layer "B.Cu")
		(net "PCIE_CLK_N")
	)
	(segment
		(start 120.988595 151.5786)
		(end 121.189815 151.5786)
		(width 0.127)
		(layer "In3.Cu")
		(net "PCIE_CLK_N")
	)
	(segment
		(start 120.173805 151.18144)
		(end 120.173805 151.12411)
		(width 0.127)
		(layer "In3.Cu")
		(net "PCIE_CLK_N")
	)
	(segment
		(start 124.698895 148.71619)
		(end 124.698895 140.89011)
		(width 0.127)
		(layer "In3.Cu")
		(net "PCIE_CLK_N")
	)
	(segment
		(start 120.694975 151.5739)
		(end 120.712125 151.5786)
		(width 0.127)
		(layer "In3.Cu")
		(net "PCIE_CLK_N")
	)
	(segment
		(start 118.865495 150.51227)
		(end 119.380055 151.02684)
		(width 0.127)
		(layer "In3.Cu")
		(net "PCIE_CLK_N")
	)
	(segment
		(start 119.752095 151.31562)
		(end 119.932975 151.36517)
		(width 0.127)
		(layer "In3.Cu")
		(net "PCIE_CLK_N")
	)
	(segment
		(start 120.694975 151.5739)
		(end 120.694975 151.5739)
		(width 0.127)
		(layer "In3.Cu")
		(net "PCIE_CLK_N")
	)
	(segment
		(start 121.189815 151.5786)
		(end 122.888595 151.5786)
		(width 0.127)
		(layer "In3.Cu")
		(net "PCIE_CLK_N")
	)
	(segment
		(start 120.712125 151.5786)
		(end 120.988595 151.5786)
		(width 0.127)
		(layer "In3.Cu")
		(net "PCIE_CLK_N")
	)
	(segment
		(start 122.888595 151.5786)
		(end 123.954945 150.51224)
		(width 0.127)
		(layer "In3.Cu")
		(net "PCIE_CLK_N")
	)
	(segment
		(start 119.932975 151.36517)
		(end 119.932975 151.36517)
		(width 0.127)
		(layer "In3.Cu")
		(net "PCIE_CLK_N")
	)
	(segment
		(start 118.828295 150.42247)
		(end 118.828295 150.42247)
		(width 0.127)
		(layer "In3.Cu")
		(net "PCIE_CLK_N")
	)
	(segment
		(start 120.554805 151.39017)
		(end 120.554805 151.12411)
		(width 0.127)
		(layer "In3.Cu")
		(net "PCIE_CLK_N")
	)
	(segment
		(start 124.488595 140.38239)
		(end 124.488595 140.3786)
		(width 0.127)
		(layer "In3.Cu")
		(net "PCIE_CLK_N")
	)
	(segment
		(start 118.955305 150.29547)
		(end 119.147875 150.29547)
		(width 0.127)
		(layer "In3.Cu")
		(net "PCIE_CLK_N")
	)
	(arc
		(start 124.488602 140.382393)
		(mid 124.644249 140.615336)
		(end 124.698905 140.89011)
		(width 0.127)
		(layer "In3.Cu")
		(net "PCIE_CLK_N")
	)
	(arc
		(start 124.698895 148.71619)
		(mid 124.505549 149.688206)
		(end 123.954946 150.512241)
		(width 0.127)
		(layer "In3.Cu")
		(net "PCIE_CLK_N")
	)
	(arc
		(start 118.828295 150.42247)
		(mid 118.837962 150.373873)
		(end 118.86549 150.332675)
		(width 0.127)
		(layer "In3.Cu")
		(net "PCIE_CLK_N")
	)
	(arc
		(start 119.752094 151.31562)
		(mid 119.720149 151.296269)
		(end 119.688594 151.276288)
		(width 0.127)
		(layer "In3.Cu")
		(net "PCIE_CLK_N")
	)
	(arc
		(start 120.173805 151.12411)
		(mid 120.364305 150.93361)
		(end 120.554805 151.12411)
		(width 0.127)
		(layer "In3.Cu")
		(net "PCIE_CLK_N")
	)
	(arc
		(start 118.865482 150.512273)
		(mid 118.837952 150.471071)
		(end 118.828284 150.42247)
		(width 0.127)
		(layer "In3.Cu")
		(net "PCIE_CLK_N")
	)
	(arc
		(start 119.688593 151.276288)
		(mid 119.527739 151.159709)
		(end 119.380056 151.026839)
		(width 0.127)
		(layer "In3.Cu")
		(net "PCIE_CLK_N")
	)
	(arc
		(start 119.188597 150.278602)
		(mid 119.169914 150.291086)
		(end 119.147875 150.29547)
		(width 0.127)
		(layer "In3.Cu")
		(net "PCIE_CLK_N")
	)
	(arc
		(start 120.173805 151.18144)
		(mid 120.098852 151.332897)
		(end 119.932973 151.365171)
		(width 0.127)
		(layer "In3.Cu")
		(net "PCIE_CLK_N")
	)
	(arc
		(start 120.694975 151.573901)
		(mid 120.593848 151.505717)
		(end 120.554805 151.390169)
		(width 0.127)
		(layer "In3.Cu")
		(net "PCIE_CLK_N")
	)
	(arc
		(start 118.865495 150.33267)
		(mid 118.9067 150.305138)
		(end 118.955305 150.295469)
		(width 0.127)
		(layer "In3.Cu")
		(net "PCIE_CLK_N")
	)
	(segment
		(start 103.613025 122.05892)
		(end 106.680075 122.05892)
		(width 0.2032)
		(layer "F.Cu")
		(net "PCIE_PERST")
	)
	(segment
		(start 112.878395 93.9062)
		(end 113.018395 93.9062)
		(width 0.2032)
		(layer "F.Cu")
		(net "PCIE_PERST")
	)
	(segment
		(start 112.053195 96.061)
		(end 113.018395 95.0958)
		(width 0.2032)
		(layer "F.Cu")
		(net "PCIE_PERST")
	)
	(segment
		(start 112.053195 116.6858)
		(end 112.053195 96.061)
		(width 0.2032)
		(layer "F.Cu")
		(net "PCIE_PERST")
	)
	(segment
		(start 113.018395 95.0958)
		(end 113.018395 93.9062)
		(width 0.2032)
		(layer "F.Cu")
		(net "PCIE_PERST")
	)
	(segment
		(start 106.680075 122.05892)
		(end 112.053195 116.6858)
		(width 0.2032)
		(layer "F.Cu")
		(net "PCIE_PERST")
	)
	(via
		(at 106.680075 122.05892)
		(size 0.4064)
		(drill 0.2032)
		(layers "F.Cu" "B.Cu")
		(net "PCIE_PERST")
	)
	(segment
		(start 114.158605 157.7576)
		(end 114.158605 149.39821)
		(width 0.2032)
		(layer "B.Cu")
		(net "PCIE_PERST")
	)
	(segment
		(start 106.668395 122.0706)
		(end 106.680075 122.05892)
		(width 0.2032)
		(layer "B.Cu")
		(net "PCIE_PERST")
	)
	(segment
		(start 106.668395 141.908)
		(end 106.668395 122.0706)
		(width 0.2032)
		(layer "B.Cu")
		(net "PCIE_PERST")
	)
	(segment
		(start 114.130035 157.72903)
		(end 114.158605 157.7576)
		(width 0.508)
		(layer "B.Cu")
		(net "PCIE_PERST")
	)
	(segment
		(start 106.668395 141.908)
		(end 114.158605 149.39821)
		(width 0.2032)
		(layer "B.Cu")
		(net "PCIE_PERST")
	)
	(segment
		(start 132.957395 157.55643)
		(end 133.158565 157.7576)
		(width 0.127)
		(layer "F.Cu")
		(net "PCIE_RX3_N")
	)
	(segment
		(start 133.138565 157.0786)
		(end 133.138565 153.59923)
		(width 0.127)
		(layer "F.Cu")
		(net "PCIE_RX3_N")
	)
	(segment
		(start 128.198455 135.66874)
		(end 128.198455 134.20545)
		(width 0.127)
		(layer "F.Cu")
		(net "PCIE_RX3_N")
	)
	(via
		(at 128.088595 135.7786)
		(size 0.4064)
		(drill 0.2032)
		(layers "F.Cu" "B.Cu")
		(net "PCIE_RX3_N")
	)
	(via
		(at 133.088595 153.4786)
		(size 0.4064)
		(drill 0.2032)
		(layers "F.Cu" "B.Cu")
		(net "PCIE_RX3_N")
	)
	(arc
		(start 133.138565 157.0786)
		(mid 132.950578 156.797257)
		(end 132.884565 156.46539)
		(width 0.2032)
		(layer "F.Cu")
		(net "PCIE_RX3_N")
	)
	(arc
		(start 128.198455 135.66874)
		(mid 128.166278 135.746423)
		(end 128.088595 135.7786)
		(width 0.127)
		(layer "F.Cu")
		(net "PCIE_RX3_N")
	)
	(arc
		(start 133.088597 153.478598)
		(mid 133.125578 153.533944)
		(end 133.138564 153.59923)
		(width 0.127)
		(layer "F.Cu")
		(net "PCIE_RX3_N")
	)
	(segment
		(start 128.655315 137.54045)
		(end 129.147755 138.03289)
		(width 0.127)
		(layer "In2.Cu")
		(net "PCIE_RX3_N")
	)
	(segment
		(start 131.139745 138.858)
		(end 131.688595 138.858)
		(width 0.127)
		(layer "In2.Cu")
		(net "PCIE_RX3_N")
	)
	(segment
		(start 132.747365 153.57867)
		(end 132.747375 153.57867)
		(width 0.127)
		(layer "In2.Cu")
		(net "PCIE_RX3_N")
	)
	(segment
		(start 132.471385 150.3671)
		(end 132.471385 150.3671)
		(width 0.127)
		(layer "In2.Cu")
		(net "PCIE_RX3_N")
	)
	(segment
		(start 131.688595 138.858)
		(end 131.688595 138.858)
		(width 0.127)
		(layer "In2.Cu")
		(net "PCIE_RX3_N")
	)
	(segment
		(start 132.588595 149.93259)
		(end 132.588595 149.93083)
		(width 0.127)
		(layer "In2.Cu")
		(net "PCIE_RX3_N")
	)
	(segment
		(start 128.298895 136.67998)
		(end 128.298895 136.2901)
		(width 0.127)
		(layer "In2.Cu")
		(net "PCIE_RX3_N")
	)
	(segment
		(start 128.088595 135.7824)
		(end 128.088595 135.7786)
		(width 0.127)
		(layer "In2.Cu")
		(net "PCIE_RX3_N")
	)
	(segment
		(start 132.872285 153.4786)
		(end 133.088595 153.4786)
		(width 0.127)
		(layer "In2.Cu")
		(net "PCIE_RX3_N")
	)
	(segment
		(start 131.788595 153.56468)
		(end 131.788595 151.62382)
		(width 0.127)
		(layer "In2.Cu")
		(net "PCIE_RX3_N")
	)
	(segment
		(start 132.431465 150.40958)
		(end 132.432865 150.40863)
		(width 0.127)
		(layer "In2.Cu")
		(net "PCIE_RX3_N")
	)
	(segment
		(start 132.588595 149.93083)
		(end 132.588595 139.73544)
		(width 0.127)
		(layer "In2.Cu")
		(net "PCIE_RX3_N")
	)
	(segment
		(start 131.788595 151.62268)
		(end 131.788595 151.62382)
		(width 0.127)
		(layer "In2.Cu")
		(net "PCIE_RX3_N")
	)
	(arc
		(start 132.336273 139.126278)
		(mid 132.523018 139.405764)
		(end 132.588594 139.73544)
		(width 0.127)
		(layer "In2.Cu")
		(net "PCIE_RX3_N")
	)
	(arc
		(start 132.471391 150.3671)
		(mid 132.454472 150.390037)
		(end 132.432865 150.408623)
		(width 0.127)
		(layer "In2.Cu")
		(net "PCIE_RX3_N")
	)
	(arc
		(start 131.79255 153.596127)
		(mid 131.789588 153.580527)
		(end 131.788595 153.56468)
		(width 0.127)
		(layer "In2.Cu")
		(net "PCIE_RX3_N")
	)
	(arc
		(start 132.747362 153.578677)
		(mid 132.276863 153.965198)
		(end 131.79255 153.596132)
		(width 0.127)
		(layer "In2.Cu")
		(net "PCIE_RX3_N")
	)
	(arc
		(start 128.655314 137.540451)
		(mid 128.391525 137.145664)
		(end 128.298895 136.67998)
		(width 0.127)
		(layer "In2.Cu")
		(net "PCIE_RX3_N")
	)
	(arc
		(start 131.788586 151.622678)
		(mid 131.959608 150.936415)
		(end 132.431462 150.409576)
		(width 0.127)
		(layer "In2.Cu")
		(net "PCIE_RX3_N")
	)
	(arc
		(start 128.088595 135.78239)
		(mid 128.24424 136.015329)
		(end 128.298895 136.2901)
		(width 0.127)
		(layer "In2.Cu")
		(net "PCIE_RX3_N")
	)
	(arc
		(start 132.747372 153.578674)
		(mid 132.792081 153.506483)
		(end 132.872288 153.478602)
		(width 0.127)
		(layer "In2.Cu")
		(net "PCIE_RX3_N")
	)
	(arc
		(start 131.688595 138.858)
		(mid 132.039114 138.927723)
		(end 132.336269 139.126276)
		(width 0.127)
		(layer "In2.Cu")
		(net "PCIE_RX3_N")
	)
	(arc
		(start 131.139745 138.858)
		(mid 130.061688 138.643561)
		(end 129.147754 138.032891)
		(width 0.127)
		(layer "In2.Cu")
		(net "PCIE_RX3_N")
	)
	(arc
		(start 132.588592 149.932586)
		(mid 132.558489 150.157533)
		(end 132.471381 150.367103)
		(width 0.127)
		(layer "In2.Cu")
		(net "PCIE_RX3_N")
	)
	(segment
		(start 132.158565 157.7576)
		(end 132.347795 157.56837)
		(width 0.127)
		(layer "F.Cu")
		(net "PCIE_RX3_P")
	)
	(segment
		(start 132.138565 157.0786)
		(end 132.138565 157.0786)
		(width 0.127)
		(layer "F.Cu")
		(net "PCIE_RX3_P")
	)
	(segment
		(start 132.138565 157.0786)
		(end 132.138565 153.8408)
		(width 0.127)
		(layer "F.Cu")
		(net "PCIE_RX3_P")
	)
	(segment
		(start 128.698325 135.68833)
		(end 128.698325 134.20545)
		(width 0.127)
		(layer "F.Cu")
		(net "PCIE_RX3_P")
	)
	(segment
		(start 132.288155 153.47904)
		(end 132.288595 153.4786)
		(width 0.127)
		(layer "F.Cu")
		(net "PCIE_RX3_P")
	)
	(via
		(at 128.788595 135.7786)
		(size 0.4064)
		(drill 0.2032)
		(layers "F.Cu" "B.Cu")
		(net "PCIE_RX3_P")
	)
	(via
		(at 132.288155 153.47904)
		(size 0.4064)
		(drill 0.2032)
		(layers "F.Cu" "B.Cu")
		(net "PCIE_RX3_P")
	)
	(arc
		(start 128.788595 135.7786)
		(mid 128.724764 135.752161)
		(end 128.698325 135.68833)
		(width 0.127)
		(layer "F.Cu")
		(net "PCIE_RX3_P")
	)
	(arc
		(start 132.138565 153.8408)
		(mid 132.177438 153.645064)
		(end 132.288157 153.479036)
		(width 0.127)
		(layer "F.Cu")
		(net "PCIE_RX3_P")
	)
	(segment
		(start 132.570755 151.44886)
		(end 132.570775 151.44886)
		(width 0.127)
		(layer "In2.Cu")
		(net "PCIE_RX3_P")
	)
	(segment
		(start 132.125795 153.31667)
		(end 132.288155 153.47904)
		(width 0.127)
		(layer "In2.Cu")
		(net "PCIE_RX3_P")
	)
	(segment
		(start 128.788595 135.7824)
		(end 128.788595 135.7786)
		(width 0.127)
		(layer "In2.Cu")
		(net "PCIE_RX3_P")
	)
	(segment
		(start 131.140695 138.5786)
		(end 131.689815 138.5786)
		(width 0.127)
		(layer "In2.Cu")
		(net "PCIE_RX3_P")
	)
	(segment
		(start 132.088595 153.16337)
		(end 132.088595 153.22687)
		(width 0.127)
		(layer "In2.Cu")
		(net "PCIE_RX3_P")
	)
	(segment
		(start 132.233095 152.21086)
		(end 132.529805 152.21086)
		(width 0.127)
		(layer "In2.Cu")
		(net "PCIE_RX3_P")
	)
	(segment
		(start 132.867995 150.3044)
		(end 132.867995 139.3786)
		(width 0.127)
		(layer "In2.Cu")
		(net "PCIE_RX3_P")
	)
	(segment
		(start 132.756435 150.46857)
		(end 132.819935 150.40507)
		(width 0.127)
		(layer "In2.Cu")
		(net "PCIE_RX3_P")
	)
	(segment
		(start 132.380255 151.25836)
		(end 132.380255 150.89735)
		(width 0.127)
		(layer "In2.Cu")
		(net "PCIE_RX3_P")
	)
	(segment
		(start 132.532975 138.92785)
		(end 132.786165 139.18103)
		(width 0.127)
		(layer "In2.Cu")
		(net "PCIE_RX3_P")
	)
	(segment
		(start 132.233095 151.82986)
		(end 132.570775 151.82986)
		(width 0.127)
		(layer "In2.Cu")
		(net "PCIE_RX3_P")
	)
	(segment
		(start 132.417445 150.80755)
		(end 132.756435 150.46857)
		(width 0.127)
		(layer "In2.Cu")
		(net "PCIE_RX3_P")
	)
	(segment
		(start 132.088595 153.16337)
		(end 132.088595 152.78236)
		(width 0.127)
		(layer "In2.Cu")
		(net "PCIE_RX3_P")
	)
	(segment
		(start 132.125795 153.31667)
		(end 132.125795 153.31667)
		(width 0.127)
		(layer "In2.Cu")
		(net "PCIE_RX3_P")
	)
	(segment
		(start 132.380255 150.89735)
		(end 132.417445 150.80755)
		(width 0.127)
		(layer "In2.Cu")
		(net "PCIE_RX3_P")
	)
	(segment
		(start 132.819935 150.40507)
		(end 132.830655 150.39436)
		(width 0.127)
		(layer "In2.Cu")
		(net "PCIE_RX3_P")
	)
	(segment
		(start 128.853855 137.34386)
		(end 129.344645 137.83465)
		(width 0.127)
		(layer "In2.Cu")
		(net "PCIE_RX3_P")
	)
	(segment
		(start 132.279095 152.59186)
		(end 132.529805 152.59186)
		(width 0.127)
		(layer "In2.Cu")
		(net "PCIE_RX3_P")
	)
	(segment
		(start 128.578295 136.6786)
		(end 128.578295 136.2901)
		(width 0.127)
		(layer "In2.Cu")
		(net "PCIE_RX3_P")
	)
	(arc
		(start 132.867995 150.3044)
		(mid 132.858288 150.353097)
		(end 132.83065 150.39435)
		(width 0.127)
		(layer "In2.Cu")
		(net "PCIE_RX3_P")
	)
	(arc
		(start 132.570775 151.44886)
		(mid 132.761275 151.63936)
		(end 132.570775 151.82986)
		(width 0.127)
		(layer "In2.Cu")
		(net "PCIE_RX3_P")
	)
	(arc
		(start 128.853855 137.34386)
		(mid 128.649911 137.038636)
		(end 128.578295 136.6786)
		(width 0.127)
		(layer "In2.Cu")
		(net "PCIE_RX3_P")
	)
	(arc
		(start 132.786168 139.181027)
		(mid 132.846737 139.271674)
		(end 132.868005 139.3786)
		(width 0.127)
		(layer "In2.Cu")
		(net "PCIE_RX3_P")
	)
	(arc
		(start 131.689815 138.5786)
		(mid 132.146127 138.669366)
		(end 132.532969 138.927846)
		(width 0.127)
		(layer "In2.Cu")
		(net "PCIE_RX3_P")
	)
	(arc
		(start 128.578295 136.2901)
		(mid 128.63295 136.015331)
		(end 128.788593 135.782392)
		(width 0.127)
		(layer "In2.Cu")
		(net "PCIE_RX3_P")
	)
	(arc
		(start 132.125792 153.316673)
		(mid 132.098262 153.275471)
		(end 132.088594 153.22687)
		(width 0.127)
		(layer "In2.Cu")
		(net "PCIE_RX3_P")
	)
	(arc
		(start 131.140695 138.5786)
		(mid 130.168679 138.385254)
		(end 129.344644 137.834651)
		(width 0.127)
		(layer "In2.Cu")
		(net "PCIE_RX3_P")
	)
	(arc
		(start 132.088595 152.78236)
		(mid 132.144391 152.647656)
		(end 132.279095 152.59186)
		(width 0.127)
		(layer "In2.Cu")
		(net "PCIE_RX3_P")
	)
	(arc
		(start 132.570755 151.44886)
		(mid 132.436051 151.393064)
		(end 132.380255 151.25836)
		(width 0.127)
		(layer "In2.Cu")
		(net "PCIE_RX3_P")
	)
	(arc
		(start 132.529805 152.21086)
		(mid 132.720305 152.40136)
		(end 132.529805 152.59186)
		(width 0.127)
		(layer "In2.Cu")
		(net "PCIE_RX3_P")
	)
	(arc
		(start 132.233095 152.21086)
		(mid 132.042595 152.02036)
		(end 132.233095 151.82986)
		(width 0.127)
		(layer "In2.Cu")
		(net "PCIE_RX3_P")
	)
	(segment
		(start 129.138575 157.0786)
		(end 129.138575 153.59925)
		(width 0.127)
		(layer "F.Cu")
		(net "PCIE_RX2_N")
	)
	(segment
		(start 129.698325 140.1137)
		(end 129.698325 138.25523)
		(width 0.127)
		(layer "F.Cu")
		(net "PCIE_RX2_N")
	)
	(via
		(at 129.588595 140.3786)
		(size 0.4064)
		(drill 0.2032)
		(layers "F.Cu" "B.Cu")
		(net "PCIE_RX2_N")
	)
	(via
		(at 129.088595 153.4786)
		(size 0.4064)
		(drill 0.2032)
		(layers "F.Cu" "B.Cu")
		(net "PCIE_RX2_N")
	)
	(arc
		(start 129.158571 157.757603)
		(mid 129.150299 157.745223)
		(end 129.147395 157.73062)
		(width 0.127)
		(layer "F.Cu")
		(net "PCIE_RX2_N")
	)
	(arc
		(start 129.698325 140.1137)
		(mid 129.669808 140.257065)
		(end 129.588598 140.378603)
		(width 0.127)
		(layer "F.Cu")
		(net "PCIE_RX2_N")
	)
	(arc
		(start 129.088599 153.478596)
		(mid 129.125587 153.533953)
		(end 129.138576 153.59925)
		(width 0.127)
		(layer "F.Cu")
		(net "PCIE_RX2_N")
	)
	(arc
		(start 129.158572 157.757603)
		(mid 128.981111 157.492014)
		(end 128.918795 157.17873)
		(width 0.127)
		(layer "F.Cu")
		(net "PCIE_RX2_N")
	)
	(segment
		(start 128.018975 153.78627)
		(end 128.019665 153.78697)
		(width 0.127)
		(layer "In2.Cu")
		(net "PCIE_RX2_N")
	)
	(segment
		(start 128.031345 150.73585)
		(end 129.288595 149.47859)
		(width 0.127)
		(layer "In2.Cu")
		(net "PCIE_RX2_N")
	)
	(segment
		(start 129.798895 148.24663)
		(end 129.798895 140.89011)
		(width 0.127)
		(layer "In2.Cu")
		(net "PCIE_RX2_N")
	)
	(segment
		(start 128.872635 153.4786)
		(end 129.088595 153.4786)
		(width 0.127)
		(layer "In2.Cu")
		(net "PCIE_RX2_N")
	)
	(segment
		(start 129.588595 140.38239)
		(end 129.588595 140.3786)
		(width 0.127)
		(layer "In2.Cu")
		(net "PCIE_RX2_N")
	)
	(arc
		(start 129.798895 148.24663)
		(mid 129.666273 148.913368)
		(end 129.288596 149.478601)
		(width 0.127)
		(layer "In2.Cu")
		(net "PCIE_RX2_N")
	)
	(arc
		(start 127.399755 152.258762)
		(mid 127.564098 151.434496)
		(end 128.03134 150.735849)
		(width 0.127)
		(layer "In2.Cu")
		(net "PCIE_RX2_N")
	)
	(arc
		(start 128.747733 153.57858)
		(mid 128.792459 153.506454)
		(end 128.872628 153.478603)
		(width 0.127)
		(layer "In2.Cu")
		(net "PCIE_RX2_N")
	)
	(arc
		(start 128.018985 153.786265)
		(mid 127.560717 153.082774)
		(end 127.399766 152.258758)
		(width 0.127)
		(layer "In2.Cu")
		(net "PCIE_RX2_N")
	)
	(arc
		(start 129.588602 140.382393)
		(mid 129.744249 140.615336)
		(end 129.798905 140.89011)
		(width 0.127)
		(layer "In2.Cu")
		(net "PCIE_RX2_N")
	)
	(arc
		(start 128.747737 153.57858)
		(mid 128.445994 153.900415)
		(end 128.019664 153.786972)
		(width 0.127)
		(layer "In2.Cu")
		(net "PCIE_RX2_N")
	)
	(segment
		(start 128.305885 153.41236)
		(end 128.308325 153.40817)
		(width 0.127)
		(layer "F.Cu")
		(net "PCIE_RX2_P")
	)
	(segment
		(start 128.158575 157.7576)
		(end 128.232995 157.68318)
		(width 0.127)
		(layer "F.Cu")
		(net "PCIE_RX2_P")
	)
	(segment
		(start 128.138575 157.0786)
		(end 128.138575 153.84078)
		(width 0.127)
		(layer "F.Cu")
		(net "PCIE_RX2_P")
	)
	(segment
		(start 128.258785 153.51109)
		(end 128.259265 153.51052)
		(width 0.127)
		(layer "F.Cu")
		(net "PCIE_RX2_P")
	)
	(segment
		(start 130.198445 140.16096)
		(end 130.198445 138.25523)
		(width 0.127)
		(layer "F.Cu")
		(net "PCIE_RX2_P")
	)
	(segment
		(start 128.280195 153.47477)
		(end 128.296995 153.43091)
		(width 0.127)
		(layer "F.Cu")
		(net "PCIE_RX2_P")
	)
	(segment
		(start 128.105995 157.70502)
		(end 128.158575 157.7576)
		(width 0.127)
		(layer "F.Cu")
		(net "PCIE_RX2_P")
	)
	(segment
		(start 128.308325 153.40817)
		(end 128.308625 153.40787)
		(width 0.127)
		(layer "F.Cu")
		(net "PCIE_RX2_P")
	)
	(via
		(at 128.308625 153.40787)
		(size 0.4064)
		(drill 0.2032)
		(layers "F.Cu" "B.Cu")
		(net "PCIE_RX2_P")
	)
	(via
		(at 130.288595 140.3786)
		(size 0.4064)
		(drill 0.2032)
		(layers "F.Cu" "B.Cu")
		(net "PCIE_RX2_P")
	)
	(arc
		(start 128.138575 153.84078)
		(mid 128.169566 153.665316)
		(end 128.258789 153.511085)
		(width 0.127)
		(layer "F.Cu")
		(net "PCIE_RX2_P")
	)
	(arc
		(start 130.288595 140.3786)
		(mid 130.221875 140.278746)
		(end 130.198446 140.16096)
		(width 0.127)
		(layer "F.Cu")
		(net "PCIE_RX2_P")
	)
	(arc
		(start 128.280193 153.474767)
		(mid 128.271197 153.4935)
		(end 128.259267 153.510515)
		(width 0.127)
		(layer "F.Cu")
		(net "PCIE_RX2_P")
	)
	(arc
		(start 128.296997 153.430905)
		(mid 128.301064 153.421452)
		(end 128.305883 153.41236)
		(width 0.127)
		(layer "F.Cu")
		(net "PCIE_RX2_P")
	)
	(segment
		(start 128.288695 153.22867)
		(end 128.288715 153.16517)
		(width 0.127)
		(layer "In2.Cu")
		(net "PCIE_RX2_P")
	)
	(segment
		(start 127.930335 151.73641)
		(end 128.098855 151.73641)
		(width 0.127)
		(layer "In2.Cu")
		(net "PCIE_RX2_P")
	)
	(segment
		(start 127.930035 152.49841)
		(end 128.352485 152.49841)
		(width 0.127)
		(layer "In2.Cu")
		(net "PCIE_RX2_P")
	)
	(segment
		(start 128.288755 153.06998)
		(end 128.288755 153.06998)
		(width 0.127)
		(layer "In2.Cu")
		(net "PCIE_RX2_P")
	)
	(segment
		(start 128.288715 153.16517)
		(end 128.288755 153.06998)
		(width 0.127)
		(layer "In2.Cu")
		(net "PCIE_RX2_P")
	)
	(segment
		(start 130.078295 148.24785)
		(end 130.078295 140.8901)
		(width 0.127)
		(layer "In2.Cu")
		(net "PCIE_RX2_P")
	)
	(segment
		(start 127.930035 152.87941)
		(end 128.098255 152.87941)
		(width 0.127)
		(layer "In2.Cu")
		(net "PCIE_RX2_P")
	)
	(segment
		(start 128.289585 150.98878)
		(end 128.289605 150.92528)
		(width 0.127)
		(layer "In2.Cu")
		(net "PCIE_RX2_P")
	)
	(segment
		(start 128.288645 153.33945)
		(end 128.288645 153.33945)
		(width 0.127)
		(layer "In2.Cu")
		(net "PCIE_RX2_P")
	)
	(segment
		(start 128.289355 151.54598)
		(end 128.289585 150.98878)
		(width 0.127)
		(layer "In2.Cu")
		(net "PCIE_RX2_P")
	)
	(segment
		(start 127.930335 152.11741)
		(end 128.352485 152.11741)
		(width 0.127)
		(layer "In2.Cu")
		(net "PCIE_RX2_P")
	)
	(segment
		(start 130.288595 140.3824)
		(end 130.288595 140.3786)
		(width 0.127)
		(layer "In2.Cu")
		(net "PCIE_RX2_P")
	)
	(segment
		(start 128.288645 153.33945)
		(end 128.288695 153.22867)
		(width 0.127)
		(layer "In2.Cu")
		(net "PCIE_RX2_P")
	)
	(segment
		(start 128.289605 150.92528)
		(end 128.289605 150.92527)
		(width 0.127)
		(layer "In2.Cu")
		(net "PCIE_RX2_P")
	)
	(segment
		(start 128.326805 150.83552)
		(end 129.487025 149.6753)
		(width 0.127)
		(layer "In2.Cu")
		(net "PCIE_RX2_P")
	)
	(segment
		(start 128.289355 151.54598)
		(end 128.289355 151.54598)
		(width 0.127)
		(layer "In2.Cu")
		(net "PCIE_RX2_P")
	)
	(segment
		(start 128.308615 153.40787)
		(end 128.308625 153.40787)
		(width 0.127)
		(layer "In2.Cu")
		(net "PCIE_RX2_P")
	)
	(arc
		(start 130.078295 148.24785)
		(mid 129.92463 149.020377)
		(end 129.487029 149.675294)
		(width 0.127)
		(layer "In2.Cu")
		(net "PCIE_RX2_P")
	)
	(arc
		(start 128.098255 152.87941)
		(mid 128.232985 152.935232)
		(end 128.288755 153.069984)
		(width 0.127)
		(layer "In2.Cu")
		(net "PCIE_RX2_P")
	)
	(arc
		(start 127.930035 152.87941)
		(mid 127.739535 152.68891)
		(end 127.930035 152.49841)
		(width 0.127)
		(layer "In2.Cu")
		(net "PCIE_RX2_P")
	)
	(arc
		(start 128.352485 152.11741)
		(mid 128.542985 152.30791)
		(end 128.352485 152.49841)
		(width 0.127)
		(layer "In2.Cu")
		(net "PCIE_RX2_P")
	)
	(arc
		(start 127.930335 152.11741)
		(mid 127.739835 151.92691)
		(end 127.930335 151.73641)
		(width 0.127)
		(layer "In2.Cu")
		(net "PCIE_RX2_P")
	)
	(arc
		(start 128.308616 153.407864)
		(mid 128.293734 153.375088)
		(end 128.288646 153.339452)
		(width 0.127)
		(layer "In2.Cu")
		(net "PCIE_RX2_P")
	)
	(arc
		(start 130.078295 140.8901)
		(mid 130.13295 140.615331)
		(end 130.288593 140.382392)
		(width 0.127)
		(layer "In2.Cu")
		(net "PCIE_RX2_P")
	)
	(arc
		(start 128.289355 151.545986)
		(mid 128.233532 151.680641)
		(end 128.098855 151.73641)
		(width 0.127)
		(layer "In2.Cu")
		(net "PCIE_RX2_P")
	)
	(arc
		(start 128.289605 150.925272)
		(mid 128.299281 150.876697)
		(end 128.326802 150.835518)
		(width 0.127)
		(layer "In2.Cu")
		(net "PCIE_RX2_P")
	)
	(segment
		(start 126.698325 139.21369)
		(end 126.698325 138.25523)
		(width 0.127)
		(layer "F.Cu")
		(net "PCIE_RX1_N")
	)
	(segment
		(start 125.138575 157.0786)
		(end 125.138575 154.84069)
		(width 0.127)
		(layer "F.Cu")
		(net "PCIE_RX1_N")
	)
	(segment
		(start 126.542145 139.52505)
		(end 126.588595 139.4786)
		(width 0.127)
		(layer "F.Cu")
		(net "PCIE_RX1_N")
	)
	(segment
		(start 124.788595 153.99576)
		(end 124.788595 153.4786)
		(width 0.127)
		(layer "F.Cu")
		(net "PCIE_RX1_N")
	)
	(segment
		(start 126.541915 139.52528)
		(end 126.542145 139.52505)
		(width 0.127)
		(layer "F.Cu")
		(net "PCIE_RX1_N")
	)
	(via
		(at 124.788595 153.4786)
		(size 0.4064)
		(drill 0.2032)
		(layers "F.Cu" "B.Cu")
		(net "PCIE_RX1_N")
	)
	(via
		(at 126.188595 140.3786)
		(size 0.4064)
		(drill 0.2032)
		(layers "F.Cu" "B.Cu")
		(net "PCIE_RX1_N")
	)
	(arc
		(start 126.188585 140.3786)
		(mid 126.280408 139.916812)
		(end 126.541906 139.525278)
		(width 0.127)
		(layer "F.Cu")
		(net "PCIE_RX1_N")
	)
	(arc
		(start 124.988594 154.478601)
		(mid 124.840573 154.257072)
		(end 124.788595 153.99576)
		(width 0.127)
		(layer "F.Cu")
		(net "PCIE_RX1_N")
	)
	(arc
		(start 126.698325 139.21369)
		(mid 126.669807 139.357059)
		(end 126.588595 139.4786)
		(width 0.127)
		(layer "F.Cu")
		(net "PCIE_RX1_N")
	)
	(arc
		(start 125.158578 157.757597)
		(mid 124.933746 157.421112)
		(end 124.854795 157.0242)
		(width 0.127)
		(layer "F.Cu")
		(net "PCIE_RX1_N")
	)
	(arc
		(start 124.9886 154.478595)
		(mid 125.099605 154.644726)
		(end 125.138585 154.84069)
		(width 0.127)
		(layer "F.Cu")
		(net "PCIE_RX1_N")
	)
	(segment
		(start 125.186355 148.38084)
		(end 125.654945 147.91225)
		(width 0.127)
		(layer "In2.Cu")
		(net "PCIE_RX1_N")
	)
	(segment
		(start 124.276555 150.29604)
		(end 124.276555 150.29604)
		(width 0.127)
		(layer "In2.Cu")
		(net "PCIE_RX1_N")
	)
	(segment
		(start 124.646455 153.4786)
		(end 124.788595 153.4786)
		(width 0.127)
		(layer "In2.Cu")
		(net "PCIE_RX1_N")
	)
	(segment
		(start 126.188595 140.38239)
		(end 126.188595 140.3786)
		(width 0.127)
		(layer "In2.Cu")
		(net "PCIE_RX1_N")
	)
	(segment
		(start 124.124125 152.81799)
		(end 124.221915 152.43171)
		(width 0.127)
		(layer "In2.Cu")
		(net "PCIE_RX1_N")
	)
	(segment
		(start 126.398895 146.1162)
		(end 126.398895 140.89011)
		(width 0.127)
		(layer "In2.Cu")
		(net "PCIE_RX1_N")
	)
	(segment
		(start 124.276145 152.26971)
		(end 124.276155 150.30604)
		(width 0.127)
		(layer "In2.Cu")
		(net "PCIE_RX1_N")
	)
	(segment
		(start 124.445395 153.58878)
		(end 124.445895 153.58675)
		(width 0.127)
		(layer "In2.Cu")
		(net "PCIE_RX1_N")
	)
	(segment
		(start 124.530235 153.49702)
		(end 124.530235 153.49702)
		(width 0.127)
		(layer "In2.Cu")
		(net "PCIE_RX1_N")
	)
	(segment
		(start 123.950245 153.01027)
		(end 123.950245 153.01027)
		(width 0.127)
		(layer "In2.Cu")
		(net "PCIE_RX1_N")
	)
	(segment
		(start 124.744655 148.96642)
		(end 124.744655 148.96642)
		(width 0.127)
		(layer "In2.Cu")
		(net "PCIE_RX1_N")
	)
	(arc
		(start 124.124122 152.817986)
		(mid 124.116505 152.839899)
		(end 124.10503 152.860061)
		(width 0.127)
		(layer "In2.Cu")
		(net "PCIE_RX1_N")
	)
	(arc
		(start 124.744655 148.966421)
		(mid 124.945098 148.658238)
		(end 125.186353 148.380838)
		(width 0.127)
		(layer "In2.Cu")
		(net "PCIE_RX1_N")
	)
	(arc
		(start 124.530234 153.497017)
		(mid 124.587619 153.483233)
		(end 124.646455 153.4786)
		(width 0.127)
		(layer "In2.Cu")
		(net "PCIE_RX1_N")
	)
	(arc
		(start 126.188602 140.382393)
		(mid 126.344249 140.615336)
		(end 126.398905 140.89011)
		(width 0.127)
		(layer "In2.Cu")
		(net "PCIE_RX1_N")
	)
	(arc
		(start 124.276155 150.30604)
		(mid 124.276254 150.301035)
		(end 124.276549 150.296038)
		(width 0.127)
		(layer "In2.Cu")
		(net "PCIE_RX1_N")
	)
	(arc
		(start 124.445394 153.588785)
		(mid 123.631602 153.784152)
		(end 123.950238 153.010268)
		(width 0.127)
		(layer "In2.Cu")
		(net "PCIE_RX1_N")
	)
	(arc
		(start 124.276555 150.29604)
		(mid 124.423806 149.600674)
		(end 124.744652 148.966423)
		(width 0.127)
		(layer "In2.Cu")
		(net "PCIE_RX1_N")
	)
	(arc
		(start 124.221917 152.431703)
		(mid 124.238392 152.379394)
		(end 124.261184 152.329513)
		(width 0.127)
		(layer "In2.Cu")
		(net "PCIE_RX1_N")
	)
	(arc
		(start 124.445889 153.586754)
		(mid 124.476455 153.530982)
		(end 124.530228 153.497022)
		(width 0.127)
		(layer "In2.Cu")
		(net "PCIE_RX1_N")
	)
	(arc
		(start 124.050075 152.946824)
		(mid 124.076589 152.902833)
		(end 124.105026 152.86006)
		(width 0.127)
		(layer "In2.Cu")
		(net "PCIE_RX1_N")
	)
	(arc
		(start 124.276145 152.269713)
		(mid 124.272347 152.300537)
		(end 124.261181 152.329517)
		(width 0.127)
		(layer "In2.Cu")
		(net "PCIE_RX1_N")
	)
	(arc
		(start 124.050071 152.946823)
		(mid 124.007992 152.990877)
		(end 123.950238 153.010266)
		(width 0.127)
		(layer "In2.Cu")
		(net "PCIE_RX1_N")
	)
	(arc
		(start 126.398895 146.1162)
		(mid 126.205549 147.088216)
		(end 125.654946 147.912251)
		(width 0.127)
		(layer "In2.Cu")
		(net "PCIE_RX1_N")
	)
	(segment
		(start 127.198455 139.21338)
		(end 127.198455 138.25523)
		(width 0.127)
		(layer "F.Cu")
		(net "PCIE_RX1_P")
	)
	(segment
		(start 124.138585 157.0786)
		(end 124.138585 153.84069)
		(width 0.127)
		(layer "F.Cu")
		(net "PCIE_RX1_P")
	)
	(segment
		(start 126.888595 140.3786)
		(end 126.888595 139.96144)
		(width 0.127)
		(layer "F.Cu")
		(net "PCIE_RX1_P")
	)
	(via
		(at 126.888595 140.3786)
		(size 0.4064)
		(drill 0.2032)
		(layers "F.Cu" "B.Cu")
		(net "PCIE_RX1_P")
	)
	(via
		(at 123.988595 153.4786)
		(size 0.4064)
		(drill 0.2032)
		(layers "F.Cu" "B.Cu")
		(net "PCIE_RX1_P")
	)
	(arc
		(start 126.888595 139.96144)
		(mid 126.940573 139.700128)
		(end 127.088594 139.478599)
		(width 0.127)
		(layer "F.Cu")
		(net "PCIE_RX1_P")
	)
	(arc
		(start 124.15858 157.757595)
		(mid 123.978301 157.487788)
		(end 123.914996 157.16953)
		(width 0.127)
		(layer "F.Cu")
		(net "PCIE_RX1_P")
	)
	(arc
		(start 123.9886 153.478595)
		(mid 124.099605 153.644726)
		(end 124.138585 153.84069)
		(width 0.127)
		(layer "F.Cu")
		(net "PCIE_RX1_P")
	)
	(arc
		(start 127.198455 139.21338)
		(mid 127.169904 139.356917)
		(end 127.088597 139.478602)
		(width 0.127)
		(layer "F.Cu")
		(net "PCIE_RX1_P")
	)
	(segment
		(start 124.720665 151.96733)
		(end 125.029685 151.96733)
		(width 0.127)
		(layer "In2.Cu")
		(net "PCIE_RX1_P")
	)
	(segment
		(start 124.588595 150.6786)
		(end 124.588595 150.6786)
		(width 0.127)
		(layer "In2.Cu")
		(net "PCIE_RX1_P")
	)
	(segment
		(start 125.386165 148.57616)
		(end 125.853495 148.10884)
		(width 0.127)
		(layer "In2.Cu")
		(net "PCIE_RX1_P")
	)
	(segment
		(start 124.720665 151.58633)
		(end 124.937295 151.58633)
		(width 0.127)
		(layer "In2.Cu")
		(net "PCIE_RX1_P")
	)
	(segment
		(start 124.588595 150.6786)
		(end 124.588595 150.49941)
		(width 0.127)
		(layer "In2.Cu")
		(net "PCIE_RX1_P")
	)
	(segment
		(start 124.336235 153.0151)
		(end 124.468645 152.49208)
		(width 0.127)
		(layer "In2.Cu")
		(net "PCIE_RX1_P")
	)
	(segment
		(start 124.653315 152.34833)
		(end 125.029685 152.34833)
		(width 0.127)
		(layer "In2.Cu")
		(net "PCIE_RX1_P")
	)
	(segment
		(start 126.678295 146.11758)
		(end 126.678295 140.8901)
		(width 0.127)
		(layer "In2.Cu")
		(net "PCIE_RX1_P")
	)
	(segment
		(start 124.779085 151.20533)
		(end 124.937295 151.20533)
		(width 0.127)
		(layer "In2.Cu")
		(net "PCIE_RX1_P")
	)
	(segment
		(start 124.588585 150.7421)
		(end 124.588595 150.6786)
		(width 0.127)
		(layer "In2.Cu")
		(net "PCIE_RX1_P")
	)
	(segment
		(start 124.588585 151.01483)
		(end 124.588585 150.7421)
		(width 0.127)
		(layer "In2.Cu")
		(net "PCIE_RX1_P")
	)
	(segment
		(start 124.468635 152.49208)
		(end 124.468645 152.49208)
		(width 0.127)
		(layer "In2.Cu")
		(net "PCIE_RX1_P")
	)
	(segment
		(start 126.888595 140.3824)
		(end 126.888595 140.3786)
		(width 0.127)
		(layer "In2.Cu")
		(net "PCIE_RX1_P")
	)
	(segment
		(start 125.386165 148.57616)
		(end 125.386165 148.57616)
		(width 0.127)
		(layer "In2.Cu")
		(net "PCIE_RX1_P")
	)
	(arc
		(start 126.678295 146.11758)
		(mid 126.463935 147.19524)
		(end 125.85349 148.108835)
		(width 0.127)
		(layer "In2.Cu")
		(net "PCIE_RX1_P")
	)
	(arc
		(start 124.720665 151.96733)
		(mid 124.530165 151.77683)
		(end 124.720665 151.58633)
		(width 0.127)
		(layer "In2.Cu")
		(net "PCIE_RX1_P")
	)
	(arc
		(start 125.029685 151.96733)
		(mid 125.220185 152.15783)
		(end 125.029685 152.34833)
		(width 0.127)
		(layer "In2.Cu")
		(net "PCIE_RX1_P")
	)
	(arc
		(start 124.336231 153.015098)
		(mid 124.318358 153.04701)
		(end 124.299917 153.078598)
		(width 0.127)
		(layer "In2.Cu")
		(net "PCIE_RX1_P")
	)
	(arc
		(start 126.678295 140.8901)
		(mid 126.73295 140.615331)
		(end 126.888593 140.382392)
		(width 0.127)
		(layer "In2.Cu")
		(net "PCIE_RX1_P")
	)
	(arc
		(start 124.779085 151.20533)
		(mid 124.64438 151.149533)
		(end 124.588585 151.014827)
		(width 0.127)
		(layer "In2.Cu")
		(net "PCIE_RX1_P")
	)
	(arc
		(start 124.937295 151.20533)
		(mid 125.127795 151.39583)
		(end 124.937295 151.58633)
		(width 0.127)
		(layer "In2.Cu")
		(net "PCIE_RX1_P")
	)
	(arc
		(start 124.299917 153.078598)
		(mid 124.156675 153.288265)
		(end 123.988595 153.478599)
		(width 0.127)
		(layer "In2.Cu")
		(net "PCIE_RX1_P")
	)
	(arc
		(start 124.468641 152.492079)
		(mid 124.536302 152.388503)
		(end 124.653315 152.34833)
		(width 0.127)
		(layer "In2.Cu")
		(net "PCIE_RX1_P")
	)
	(arc
		(start 124.588596 150.499412)
		(mid 124.796304 149.458548)
		(end 125.386162 148.576159)
		(width 0.127)
		(layer "In2.Cu")
		(net "PCIE_RX1_P")
	)
	(segment
		(start 120.138585 157.0786)
		(end 120.138585 154.56501)
		(width 0.127)
		(layer "F.Cu")
		(net "PCIE_RX0_N")
	)
	(segment
		(start 125.198455 135.66874)
		(end 125.198455 134.20545)
		(width 0.127)
		(layer "F.Cu")
		(net "PCIE_RX0_N")
	)
	(via
		(at 120.588595 153.4786)
		(size 0.4064)
		(drill 0.2032)
		(layers "F.Cu" "B.Cu")
		(net "PCIE_RX0_N")
	)
	(via
		(at 125.088595 135.7786)
		(size 0.4064)
		(drill 0.2032)
		(layers "F.Cu" "B.Cu")
		(net "PCIE_RX0_N")
	)
	(arc
		(start 120.158589 157.757596)
		(mid 119.987332 157.501292)
		(end 119.927194 157.19896)
		(width 0.127)
		(layer "F.Cu")
		(net "PCIE_RX0_N")
	)
	(arc
		(start 120.138585 154.56501)
		(mid 120.255538 153.977048)
		(end 120.588592 153.478597)
		(width 0.127)
		(layer "F.Cu")
		(net "PCIE_RX0_N")
	)
	(arc
		(start 125.198455 135.66874)
		(mid 125.166278 135.746423)
		(end 125.088595 135.7786)
		(width 0.127)
		(layer "F.Cu")
		(net "PCIE_RX0_N")
	)
	(segment
		(start 122.380545 151.41725)
		(end 122.380545 151.41724)
		(width 0.127)
		(layer "In2.Cu")
		(net "PCIE_RX0_N")
	)
	(segment
		(start 125.088595 135.78239)
		(end 125.088595 135.7786)
		(width 0.127)
		(layer "In2.Cu")
		(net "PCIE_RX0_N")
	)
	(segment
		(start 123.409195 150.5786)
		(end 123.409195 150.5786)
		(width 0.127)
		(layer "In2.Cu")
		(net "PCIE_RX0_N")
	)
	(segment
		(start 121.509625 152.16277)
		(end 121.572315 152.22546)
		(width 0.127)
		(layer "In2.Cu")
		(net "PCIE_RX0_N")
	)
	(segment
		(start 120.588595 153.4786)
		(end 120.988595 153.0786)
		(width 0.127)
		(layer "In2.Cu")
		(net "PCIE_RX0_N")
	)
	(segment
		(start 123.095825 150.97137)
		(end 123.353055 150.71414)
		(width 0.127)
		(layer "In2.Cu")
		(net "PCIE_RX0_N")
	)
	(segment
		(start 120.949805 152.68058)
		(end 121.033505 152.76428)
		(width 0.127)
		(layer "In2.Cu")
		(net "PCIE_RX0_N")
	)
	(segment
		(start 121.219215 152.41117)
		(end 121.302905 152.49487)
		(width 0.127)
		(layer "In2.Cu")
		(net "PCIE_RX0_N")
	)
	(segment
		(start 120.988595 153.0786)
		(end 121.033505 153.03369)
		(width 0.127)
		(layer "In2.Cu")
		(net "PCIE_RX0_N")
	)
	(segment
		(start 122.380515 151.41722)
		(end 122.380545 151.41724)
		(width 0.127)
		(layer "In2.Cu")
		(net "PCIE_RX0_N")
	)
	(segment
		(start 122.111115 151.68663)
		(end 122.111135 151.68665)
		(width 0.127)
		(layer "In2.Cu")
		(net "PCIE_RX0_N")
	)
	(segment
		(start 125.298895 136.71619)
		(end 125.298895 136.29011)
		(width 0.127)
		(layer "In2.Cu")
		(net "PCIE_RX0_N")
	)
	(segment
		(start 123.788095 139.27909)
		(end 124.554945 138.51224)
		(width 0.127)
		(layer "In2.Cu")
		(net "PCIE_RX0_N")
	)
	(segment
		(start 122.649955 151.41724)
		(end 123.095825 150.97137)
		(width 0.127)
		(layer "In2.Cu")
		(net "PCIE_RX0_N")
	)
	(segment
		(start 123.409195 150.5786)
		(end 123.409195 140.19385)
		(width 0.127)
		(layer "In2.Cu")
		(net "PCIE_RX0_N")
	)
	(segment
		(start 121.779035 151.89337)
		(end 121.841725 151.95605)
		(width 0.127)
		(layer "In2.Cu")
		(net "PCIE_RX0_N")
	)
	(arc
		(start 123.409195 150.5786)
		(mid 123.394603 150.651957)
		(end 123.35305 150.714145)
		(width 0.127)
		(layer "In2.Cu")
		(net "PCIE_RX0_N")
	)
	(arc
		(start 121.572316 152.494866)
		(mid 121.437614 152.55066)
		(end 121.302912 152.494864)
		(width 0.127)
		(layer "In2.Cu")
		(net "PCIE_RX0_N")
	)
	(arc
		(start 121.509631 151.893366)
		(mid 121.644335 151.83757)
		(end 121.779039 151.893366)
		(width 0.127)
		(layer "In2.Cu")
		(net "PCIE_RX0_N")
	)
	(arc
		(start 123.409195 140.19385)
		(mid 123.507669 139.698788)
		(end 123.788099 139.279094)
		(width 0.127)
		(layer "In2.Cu")
		(net "PCIE_RX0_N")
	)
	(arc
		(start 122.111111 151.686624)
		(mid 122.055315 151.551922)
		(end 122.111108 151.417219)
		(width 0.127)
		(layer "In2.Cu")
		(net "PCIE_RX0_N")
	)
	(arc
		(start 121.033509 152.764286)
		(mid 121.089305 152.89899)
		(end 121.033509 153.033694)
		(width 0.127)
		(layer "In2.Cu")
		(net "PCIE_RX0_N")
	)
	(arc
		(start 122.649949 151.417244)
		(mid 122.515245 151.47304)
		(end 122.380541 151.417244)
		(width 0.127)
		(layer "In2.Cu")
		(net "PCIE_RX0_N")
	)
	(arc
		(start 125.088602 135.782393)
		(mid 125.244249 136.015336)
		(end 125.298905 136.29011)
		(width 0.127)
		(layer "In2.Cu")
		(net "PCIE_RX0_N")
	)
	(arc
		(start 120.949801 152.411176)
		(mid 121.084505 152.35538)
		(end 121.219209 152.411176)
		(width 0.127)
		(layer "In2.Cu")
		(net "PCIE_RX0_N")
	)
	(arc
		(start 122.111111 151.417216)
		(mid 122.245815 151.36142)
		(end 122.380519 151.417216)
		(width 0.127)
		(layer "In2.Cu")
		(net "PCIE_RX0_N")
	)
	(arc
		(start 125.298895 136.71619)
		(mid 125.105549 137.688206)
		(end 124.554946 138.512241)
		(width 0.127)
		(layer "In2.Cu")
		(net "PCIE_RX0_N")
	)
	(arc
		(start 122.111126 151.956056)
		(mid 121.976424 152.01185)
		(end 121.841722 151.956054)
		(width 0.127)
		(layer "In2.Cu")
		(net "PCIE_RX0_N")
	)
	(arc
		(start 121.509631 152.162774)
		(mid 121.453835 152.028072)
		(end 121.509628 151.893369)
		(width 0.127)
		(layer "In2.Cu")
		(net "PCIE_RX0_N")
	)
	(arc
		(start 121.572319 152.225466)
		(mid 121.628115 152.36017)
		(end 121.572319 152.494874)
		(width 0.127)
		(layer "In2.Cu")
		(net "PCIE_RX0_N")
	)
	(arc
		(start 120.949811 152.680584)
		(mid 120.894015 152.545882)
		(end 120.949808 152.411179)
		(width 0.127)
		(layer "In2.Cu")
		(net "PCIE_RX0_N")
	)
	(arc
		(start 122.111129 151.686646)
		(mid 122.166925 151.82135)
		(end 122.111129 151.956054)
		(width 0.127)
		(layer "In2.Cu")
		(net "PCIE_RX0_N")
	)
	(segment
		(start 119.138595 157.0786)
		(end 119.138595 155.04785)
		(width 0.127)
		(layer "F.Cu")
		(net "PCIE_RX0_P")
	)
	(segment
		(start 125.698325 135.68833)
		(end 125.698325 134.20545)
		(width 0.127)
		(layer "F.Cu")
		(net "PCIE_RX0_P")
	)
	(via
		(at 125.788595 135.7786)
		(size 0.4064)
		(drill 0.2032)
		(layers "F.Cu" "B.Cu")
		(net "PCIE_RX0_P")
	)
	(via
		(at 119.788595 153.4786)
		(size 0.4064)
		(drill 0.2032)
		(layers "F.Cu" "B.Cu")
		(net "PCIE_RX0_P")
	)
	(arc
		(start 125.788595 135.7786)
		(mid 125.724764 135.752161)
		(end 125.698325 135.68833)
		(width 0.127)
		(layer "F.Cu")
		(net "PCIE_RX0_P")
	)
	(arc
		(start 119.138595 155.04785)
		(mid 119.307525 154.19858)
		(end 119.788598 153.478603)
		(width 0.127)
		(layer "F.Cu")
		(net "PCIE_RX0_P")
	)
	(segment
		(start 123.986165 139.47616)
		(end 124.753495 138.70883)
		(width 0.127)
		(layer "In2.Cu")
		(net "PCIE_RX0_P")
	)
	(segment
		(start 125.578295 136.71758)
		(end 125.578295 136.2901)
		(width 0.127)
		(layer "In2.Cu")
		(net "PCIE_RX0_P")
	)
	(segment
		(start 123.986165 139.47616)
		(end 123.986165 139.47616)
		(width 0.127)
		(layer "In2.Cu")
		(net "PCIE_RX0_P")
	)
	(segment
		(start 123.688595 150.64871)
		(end 123.688595 140.19379)
		(width 0.127)
		(layer "In2.Cu")
		(net "PCIE_RX0_P")
	)
	(segment
		(start 125.788595 135.7824)
		(end 125.788595 135.7824)
		(width 0.127)
		(layer "In2.Cu")
		(net "PCIE_RX0_P")
	)
	(segment
		(start 125.788595 135.7824)
		(end 125.788595 135.7786)
		(width 0.127)
		(layer "In2.Cu")
		(net "PCIE_RX0_P")
	)
	(segment
		(start 121.056455 153.43491)
		(end 121.056455 153.43491)
		(width 0.127)
		(layer "In2.Cu")
		(net "PCIE_RX0_P")
	)
	(segment
		(start 121.092775 153.33362)
		(end 123.598685 150.82771)
		(width 0.127)
		(layer "In2.Cu")
		(net "PCIE_RX0_P")
	)
	(segment
		(start 120.004555 153.4786)
		(end 120.004555 153.4786)
		(width 0.127)
		(layer "In2.Cu")
		(net "PCIE_RX0_P")
	)
	(segment
		(start 119.788595 153.4786)
		(end 120.004555 153.4786)
		(width 0.127)
		(layer "In2.Cu")
		(net "PCIE_RX0_P")
	)
	(arc
		(start 120.004562 153.478603)
		(mid 120.084731 153.506454)
		(end 120.129457 153.57858)
		(width 0.127)
		(layer "In2.Cu")
		(net "PCIE_RX0_P")
	)
	(arc
		(start 125.578295 136.71758)
		(mid 125.363935 137.79524)
		(end 124.75349 138.708835)
		(width 0.127)
		(layer "In2.Cu")
		(net "PCIE_RX0_P")
	)
	(arc
		(start 123.688595 140.193796)
		(mid 123.766074 139.805415)
		(end 123.986159 139.476165)
		(width 0.127)
		(layer "In2.Cu")
		(net "PCIE_RX0_P")
	)
	(arc
		(start 123.688596 150.648709)
		(mid 123.658023 150.745434)
		(end 123.598687 150.827712)
		(width 0.127)
		(layer "In2.Cu")
		(net "PCIE_RX0_P")
	)
	(arc
		(start 121.05646 153.434914)
		(mid 120.660561 153.942957)
		(end 120.129455 153.578581)
		(width 0.127)
		(layer "In2.Cu")
		(net "PCIE_RX0_P")
	)
	(arc
		(start 121.056455 153.434911)
		(mid 121.063359 153.38023)
		(end 121.092778 153.333623)
		(width 0.127)
		(layer "In2.Cu")
		(net "PCIE_RX0_P")
	)
	(arc
		(start 125.578295 136.2901)
		(mid 125.63295 136.015331)
		(end 125.788593 135.782392)
		(width 0.127)
		(layer "In2.Cu")
		(net "PCIE_RX0_P")
	)
	(segment
		(start 144.336595 126.6426)
		(end 144.419395 126.5598)
		(width 0.2032)
		(layer "F.Cu")
		(net "LED1")
	)
	(segment
		(start 79.718995 63.6506)
		(end 109.411595 63.6506)
		(width 0.2032)
		(layer "F.Cu")
		(net "LED1")
	)
	(segment
		(start 144.419395 126.5598)
		(end 147.185965 126.5598)
		(width 0.2032)
		(layer "F.Cu")
		(net "LED1")
	)
	(segment
		(start 74.718395 58.65)
		(end 79.718995 63.6506)
		(width 0.2032)
		(layer "F.Cu")
		(net "LED1")
	)
	(segment
		(start 74.718395 58.65)
		(end 74.718395 57.9906)
		(width 0.2032)
		(layer "F.Cu")
		(net "LED1")
	)
	(via
		(at 109.411595 63.6506)
		(size 0.4064)
		(drill 0.2032)
		(layers "F.Cu" "B.Cu")
		(net "LED1")
	)
	(via
		(at 144.336595 126.6426)
		(size 0.4064)
		(drill 0.2032)
		(layers "F.Cu" "B.Cu")
		(net "LED1")
	)
	(via
		(at 109.411595 126.6426)
		(size 0.4064)
		(drill 0.2032)
		(layers "F.Cu" "B.Cu")
		(net "LED1")
	)
	(segment
		(start 109.411595 126.6426)
		(end 144.336595 126.6426)
		(width 0.2032)
		(layer "In2.Cu")
		(net "LED1")
	)
	(segment
		(start 109.411595 126.6426)
		(end 109.411595 63.6506)
		(width 0.2032)
		(layer "In3.Cu")
		(net "LED1")
	)
	(segment
		(start 145.081565 125.9502)
		(end 145.191295 126.05992)
		(width 0.2032)
		(layer "F.Cu")
		(net "LED2")
	)
	(segment
		(start 145.191295 126.05992)
		(end 147.185965 126.05992)
		(width 0.2032)
		(layer "F.Cu")
		(net "LED2")
	)
	(segment
		(start 84.341795 63.1426)
		(end 110.046595 63.1426)
		(width 0.2032)
		(layer "F.Cu")
		(net "LED2")
	)
	(segment
		(start 79.840725 58.64153)
		(end 84.341795 63.1426)
		(width 0.2032)
		(layer "F.Cu")
		(net "LED2")
	)
	(segment
		(start 144.971595 125.9502)
		(end 145.081565 125.9502)
		(width 0.2032)
		(layer "F.Cu")
		(net "LED2")
	)
	(segment
		(start 79.840725 58.64153)
		(end 79.840725 57.9906)
		(width 0.2032)
		(layer "F.Cu")
		(net "LED2")
	)
	(via
		(at 110.046595 63.1426)
		(size 0.4064)
		(drill 0.2032)
		(layers "F.Cu" "B.Cu")
		(net "LED2")
	)
	(via
		(at 144.971595 125.9502)
		(size 0.4064)
		(drill 0.2032)
		(layers "F.Cu" "B.Cu")
		(net "LED2")
	)
	(via
		(at 110.021195 125.99236)
		(size 0.4064)
		(drill 0.2032)
		(layers "F.Cu" "B.Cu")
		(net "LED2")
	)
	(segment
		(start 144.914195 126.0076)
		(end 144.971595 125.9502)
		(width 0.2032)
		(layer "In2.Cu")
		(net "LED2")
	)
	(segment
		(start 110.036435 126.0076)
		(end 144.914195 126.0076)
		(width 0.2032)
		(layer "In2.Cu")
		(net "LED2")
	)
	(segment
		(start 110.021195 125.99236)
		(end 110.036435 126.0076)
		(width 0.2032)
		(layer "In2.Cu")
		(net "LED2")
	)
	(segment
		(start 110.046595 125.96696)
		(end 110.046595 63.1426)
		(width 0.2032)
		(layer "In3.Cu")
		(net "LED2")
	)
	(segment
		(start 110.021195 125.99236)
		(end 110.046595 125.96696)
		(width 0.2032)
		(layer "In3.Cu")
		(net "LED2")
	)
	(segment
		(start 114.418595 66.3796)
		(end 114.618595 66.1796)
		(width 0.2032)
		(layer "F.Cu")
		(net "GND")
	)
	(segment
		(start 75.088595 96.1036)
		(end 75.099355 96.09284)
		(width 0.3048)
		(layer "F.Cu")
		(net "GND")
	)
	(segment
		(start 170.988595 63.5786)
		(end 171.888595 63.5786)
		(width 0.3048)
		(layer "F.Cu")
		(net "GND")
	)
	(segment
		(start 143.091995 74.3982)
		(end 143.149595 74.3406)
		(width 0.254)
		(layer "F.Cu")
		(net "GND")
	)
	(segment
		(start 126.429595 71.6516)
		(end 126.429595 71.5126)
		(width 0.508)
		(layer "F.Cu")
		(net "GND")
	)
	(segment
		(start 147.185965 109.55983)
		(end 148.335825 109.55983)
		(width 0.2032)
		(layer "F.Cu")
		(net "GND")
	)
	(segment
		(start 131.698065 96.61497)
		(end 131.698065 95.41127)
		(width 0.254)
		(layer "F.Cu")
		(net "GND")
	)
	(segment
		(start 235.751195 114.0786)
		(end 236.288595 113.5412)
		(width 0.2032)
		(layer "F.Cu")
		(net "GND")
	)
	(segment
		(start 124.288595 94.56659)
		(end 124.288595 94.5116)
		(width 0.2032)
		(layer "F.Cu")
		(net "GND")
	)
	(segment
		(start 102.147195 115.0602)
		(end 102.148465 115.05893)
		(width 0.254)
		(layer "F.Cu")
		(net "GND")
	)
	(segment
		(start 75.088595 112.4536)
		(end 75.121595 112.4866)
		(width 0.3048)
		(layer "F.Cu")
		(net "GND")
	)
	(segment
		(start 152.571605 82.19801)
		(end 152.571605 81.65021)
		(width 0.254)
		(layer "F.Cu")
		(net "GND")
	)
	(segment
		(start 75.121595 109.4706)
		(end 75.121595 107.9228)
		(width 0.3048)
		(layer "F.Cu")
		(net "GND")
	)
	(segment
		(start 150.488595 144.1786)
		(end 151.588595 144.1786)
		(width 0.2032)
		(layer "F.Cu")
		(net "GND")
	)
	(segment
		(start 132.288595 136.83358)
		(end 132.288595 136.7786)
		(width 0.2032)
		(layer "F.Cu")
		(net "GND")
	)
	(segment
		(start 144.719595 53.3616)
		(end 144.742995 53.3382)
		(width 0.254)
		(layer "F.Cu")
		(net "GND")
	)
	(segment
		(start 75.088595 109.5036)
		(end 75.121595 109.4706)
		(width 0.3048)
		(layer "F.Cu")
		(net "GND")
	)
	(segment
		(start 117.455595 74.2756)
		(end 117.666595 74.0646)
		(width 0.508)
		(layer "F.Cu")
		(net "GND")
	)
	(segment
		(start 150.182405 119.55981)
		(end 151.235745 119.55981)
		(width 0.254)
		(layer "F.Cu")
		(net "GND")
	)
	(segment
		(start 102.152785 122.55879)
		(end 103.613025 122.55879)
		(width 0.254)
		(layer "F.Cu")
		(net "GND")
	)
	(segment
		(start 162.878595 81.1766)
		(end 162.976435 81.07876)
		(width 0.254)
		(layer "F.Cu")
		(net "GND")
	)
	(segment
		(start 141.525595 90.3156)
		(end 141.525595 89.5786)
		(width 0.2032)
		(layer "F.Cu")
		(net "GND")
	)
	(segment
		(start 165.393195 80.948)
		(end 165.422355 80.97716)
		(width 0.254)
		(layer "F.Cu")
		(net "GND")
	)
	(segment
		(start 148.124245 112.05995)
		(end 148.781595 111.4026)
		(width 0.2032)
		(layer "F.Cu")
		(net "GND")
	)
	(segment
		(start 87.877595 97.5596)
		(end 90.513995 97.5596)
		(width 0.254)
		(layer "F.Cu")
		(net "GND")
	)
	(segment
		(start 162.746185 62.99919)
		(end 162.751595 63.0046)
		(width 0.254)
		(layer "F.Cu")
		(net "GND")
	)
	(segment
		(start 132.188595 134.22882)
		(end 132.188595 132.4786)
		(width 0.2032)
		(layer "F.Cu")
		(net "GND")
	)
	(segment
		(start 99.564525 115.0602)
		(end 100.953395 115.0602)
		(width 0.254)
		(layer "F.Cu")
		(net "GND")
	)
	(segment
		(start 124.688485 133.58087)
		(end 124.688485 132.61995)
		(width 0.254)
		(layer "F.Cu")
		(net "GND")
	)
	(segment
		(start 149.797595 122.1214)
		(end 149.838835 122.1214)
		(width 0.254)
		(layer "F.Cu")
		(net "GND")
	)
	(segment
		(start 146.454705 117.05187)
		(end 146.460745 117.05791)
		(width 0.254)
		(layer "F.Cu")
		(net "GND")
	)
	(segment
		(start 116.688245 100.68812)
		(end 116.688245 99.67895)
		(width 0.2032)
		(layer "F.Cu")
		(net "GND")
	)
	(segment
		(start 228.535995 114.0738)
		(end 229.365595 114.0738)
		(width 0.254)
		(layer "F.Cu")
		(net "GND")
	)
	(segment
		(start 117.288595 136.93358)
		(end 117.288595 136.8786)
		(width 0.2032)
		(layer "F.Cu")
		(net "GND")
	)
	(segment
		(start 150.026195 143.2542)
		(end 150.026195 142.691)
		(width 0.254)
		(layer "F.Cu")
		(net "GND")
	)
	(segment
		(start 147.185965 112.05995)
		(end 148.124245 112.05995)
		(width 0.2032)
		(layer "F.Cu")
		(net "GND")
	)
	(segment
		(start 127.132225 157.07224)
		(end 127.138575 157.0786)
		(width 0.508)
		(layer "F.Cu")
		(net "GND")
	)
	(segment
		(start 223.000395 78.5096)
		(end 223.004395 78.5056)
		(width 0.254)
		(layer "F.Cu")
		(net "GND")
	)
	(segment
		(start 115.216595 65.70439)
		(end 115.365385 65.5556)
		(width 0.254)
		(layer "F.Cu")
		(net "GND")
	)
	(segment
		(start 99.563255 115.05893)
		(end 99.564525 115.0602)
		(width 0.254)
		(layer "F.Cu")
		(net "GND")
	)
	(segment
		(start 170.310595 82.1846)
		(end 170.330595 82.1846)
		(width 0.254)
		(layer "F.Cu")
		(net "GND")
	)
	(segment
		(start 75.099355 96.09284)
		(end 75.099355 94.69379)
		(width 0.3048)
		(layer "F.Cu")
		(net "GND")
	)
	(segment
		(start 99.565285 122.55676)
		(end 100.288475 122.55676)
		(width 0.254)
		(layer "F.Cu")
		(net "GND")
	)
	(segment
		(start 168.568195 80.948)
		(end 168.593595 80.9734)
		(width 0.254)
		(layer "F.Cu")
		(net "GND")
	)
	(segment
		(start 102.223395 110.0564)
		(end 102.225935 110.05894)
		(width 0.254)
		(layer "F.Cu")
		(net "GND")
	)
	(segment
		(start 129.088595 94.56659)
		(end 129.188355 94.66634)
		(width 0.2032)
		(layer "F.Cu")
		(net "GND")
	)
	(segment
		(start 116.688245 96.63835)
		(end 116.688245 94.52524)
		(width 0.2032)
		(layer "F.Cu")
		(net "GND")
	)
	(segment
		(start 161.735595 91.4382)
		(end 161.735595 89.9506)
		(width 0.254)
		(layer "F.Cu")
		(net "GND")
	)
	(segment
		(start 150.026195 142.691)
		(end 150.580595 142.1366)
		(width 0.254)
		(layer "F.Cu")
		(net "GND")
	)
	(segment
		(start 149.988595 144.2786)
		(end 150.388595 144.2786)
		(width 0.2032)
		(layer "F.Cu")
		(net "GND")
	)
	(segment
		(start 124.188365 94.66682)
		(end 124.288595 94.56659)
		(width 0.2032)
		(layer "F.Cu")
		(net "GND")
	)
	(segment
		(start 119.688495 134.22882)
		(end 119.688545 134.22877)
		(width 0.2032)
		(layer "F.Cu")
		(net "GND")
	)
	(segment
		(start 119.688545 134.22877)
		(end 119.688545 132.47865)
		(width 0.2032)
		(layer "F.Cu")
		(net "GND")
	)
	(segment
		(start 102.148465 115.05893)
		(end 103.613025 115.05893)
		(width 0.254)
		(layer "F.Cu")
		(net "GND")
	)
	(segment
		(start 145.225595 87.1218)
		(end 145.819995 87.1218)
		(width 0.254)
		(layer "F.Cu")
		(net "GND")
	)
	(segment
		(start 220.088595 87.0786)
		(end 220.088595 85.5786)
		(width 0.508)
		(layer "F.Cu")
		(net "GND")
	)
	(segment
		(start 137.548595 80.9286)
		(end 139.338595 80.9286)
		(width 0.2032)
		(layer "F.Cu")
		(net "GND")
	)
	(segment
		(start 116.435795 53.7054)
		(end 116.675995 53.4652)
		(width 0.254)
		(layer "F.Cu")
		(net "GND")
	)
	(segment
		(start 125.540595 70.7736)
		(end 125.690595 70.7736)
		(width 0.508)
		(layer "F.Cu")
		(net "GND")
	)
	(segment
		(start 149.838835 122.1214)
		(end 149.900305 122.05993)
		(width 0.254)
		(layer "F.Cu")
		(net "GND")
	)
	(segment
		(start 130.888595 132.53359)
		(end 130.888595 132.4786)
		(width 0.2032)
		(layer "F.Cu")
		(net "GND")
	)
	(segment
		(start 102.045595 120.064)
		(end 102.050675 120.05892)
		(width 0.254)
		(layer "F.Cu")
		(net "GND")
	)
	(segment
		(start 110.158605 154.34359)
		(end 110.173595 154.3286)
		(width 0.508)
		(layer "F.Cu")
		(net "GND")
	)
	(segment
		(start 183.188595 59.9536)
		(end 183.188595 55.9786)
		(width 0.2032)
		(layer "F.Cu")
		(net "GND")
	)
	(segment
		(start 137.513595 80.8936)
		(end 137.548595 80.9286)
		(width 0.2032)
		(layer "F.Cu")
		(net "GND")
	)
	(segment
		(start 225.988595 119.6786)
		(end 226.927595 119.6786)
		(width 0.2032)
		(layer "F.Cu")
		(net "GND")
	)
	(segment
		(start 120.643785 154.41678)
		(end 120.955925 154.65301)
		(width 0.508)
		(layer "F.Cu")
		(net "GND")
	)
	(segment
		(start 119.188375 99.67882)
		(end 119.988595 98.8786)
		(width 0.2032)
		(layer "F.Cu")
		(net "GND")
	)
	(segment
		(start 145.098595 123.2898)
		(end 146.080815 122.30758)
		(width 0.254)
		(layer "F.Cu")
		(net "GND")
	)
	(segment
		(start 129.188475 98.77872)
		(end 129.188595 98.7786)
		(width 0.2032)
		(layer "F.Cu")
		(net "GND")
	)
	(segment
		(start 163.999955 81.12956)
		(end 164.275595 81.4052)
		(width 0.254)
		(layer "F.Cu")
		(net "GND")
	)
	(segment
		(start 107.142105 157.74109)
		(end 107.142105 154.36162)
		(width 0.508)
		(layer "F.Cu")
		(net "GND")
	)
	(segment
		(start 122.188615 138.2786)
		(end 122.188615 137.13356)
		(width 0.2032)
		(layer "F.Cu")
		(net "GND")
	)
	(segment
		(start 119.188375 100.68812)
		(end 119.188375 99.67882)
		(width 0.2032)
		(layer "F.Cu")
		(net "GND")
	)
	(segment
		(start 121.688325 95.17887)
		(end 121.688415 95.17878)
		(width 0.2032)
		(layer "F.Cu")
		(net "GND")
	)
	(segment
		(start 163.680025 69.28717)
		(end 163.680025 69.2196)
		(width 0.2032)
		(layer "F.Cu")
		(net "GND")
	)
	(segment
		(start 142.288595 91.0786)
		(end 143.788595 91.0786)
		(width 0.2032)
		(layer "F.Cu")
		(net "GND")
	)
	(segment
		(start 165.393195 80.948)
		(end 165.407595 80.9336)
		(width 0.254)
		(layer "F.Cu")
		(net "GND")
	)
	(segment
		(start 102.444065 117.58217)
		(end 102.955235 117.58217)
		(width 0.254)
		(layer "F.Cu")
		(net "GND")
	)
	(segment
		(start 163.999955 81.12956)
		(end 163.999955 80.97716)
		(width 0.254)
		(layer "F.Cu")
		(net "GND")
	)
	(segment
		(start 99.563255 120.05892)
		(end 100.922915 120.05892)
		(width 0.254)
		(layer "F.Cu")
		(net "GND")
	)
	(segment
		(start 75.121595 127.2014)
		(end 75.121595 125.6866)
		(width 0.3048)
		(layer "F.Cu")
		(net "GND")
	)
	(segment
		(start 102.264635 117.7616)
		(end 102.444065 117.58217)
		(width 0.254)
		(layer "F.Cu")
		(net "GND")
	)
	(segment
		(start 126.698075 101.86668)
		(end 126.708995 101.8776)
		(width 0.254)
		(layer "F.Cu")
		(net "GND")
	)
	(segment
		(start 148.486355 124.5598)
		(end 148.613355 124.6868)
		(width 0.254)
		(layer "F.Cu")
		(net "GND")
	)
	(segment
		(start 124.949715 102.13972)
		(end 124.988595 102.1786)
		(width 0.2032)
		(layer "F.Cu")
		(net "GND")
	)
	(segment
		(start 128.222595 65.5196)
		(end 128.222595 65.3196)
		(width 0.254)
		(layer "F.Cu")
		(net "GND")
	)
	(segment
		(start 226.831095 121.7341)
		(end 226.875595 121.6896)
		(width 0.254)
		(layer "F.Cu")
		(net "GND")
	)
	(segment
		(start 99.563255 125.05891)
		(end 100.936885 125.05891)
		(width 0.254)
		(layer "F.Cu")
		(net "GND")
	)
	(segment
		(start 100.936885 125.05891)
		(end 100.953395 125.0424)
		(width 0.254)
		(layer "F.Cu")
		(net "GND")
	)
	(segment
		(start 152.571605 82.19801)
		(end 152.921795 82.5482)
		(width 0.254)
		(layer "F.Cu")
		(net "GND")
	)
	(segment
		(start 217.869595 99.8456)
		(end 219.836595 99.8456)
		(width 0.254)
		(layer "F.Cu")
		(net "GND")
	)
	(segment
		(start 141.557595 65.3196)
		(end 141.557595 64.453)
		(width 0.254)
		(layer "F.Cu")
		(net "GND")
	)
	(segment
		(start 114.618595 66.1796)
		(end 114.768595 66.1796)
		(width 0.254)
		(layer "F.Cu")
		(net "GND")
	)
	(segment
		(start 127.158575 157.7576)
		(end 127.158575 156.0177)
		(width 0.508)
		(layer "F.Cu")
		(net "GND")
	)
	(segment
		(start 99.563255 112.55881)
		(end 101.041785 112.55881)
		(width 0.254)
		(layer "F.Cu")
		(net "GND")
	)
	(segment
		(start 129.088595 94.56659)
		(end 129.088595 94.5116)
		(width 0.2032)
		(layer "F.Cu")
		(net "GND")
	)
	(segment
		(start 155.750755 65.0222)
		(end 155.791995 65.0222)
		(width 0.254)
		(layer "F.Cu")
		(net "GND")
	)
	(segment
		(start 220.178595 98.0786)
		(end 220.229395 98.0278)
		(width 0.254)
		(layer "F.Cu")
		(net "GND")
	)
	(segment
		(start 100.288475 122.55676)
		(end 100.292035 122.5532)
		(width 0.254)
		(layer "F.Cu")
		(net "GND")
	)
	(segment
		(start 130.057215 156.99725)
		(end 130.138565 157.0786)
		(width 0.508)
		(layer "F.Cu")
		(net "GND")
	)
	(segment
		(start 127.899595 65.6426)
		(end 128.099595 65.6426)
		(width 0.254)
		(layer "F.Cu")
		(net "GND")
	)
	(segment
		(start 132.188595 136.93358)
		(end 132.288595 136.83358)
		(width 0.2032)
		(layer "F.Cu")
		(net "GND")
	)
	(segment
		(start 133.608465 154.1786)
		(end 133.919345 154.53599)
		(width 0.508)
		(layer "F.Cu")
		(net "GND")
	)
	(segment
		(start 102.235585 112.55881)
		(end 103.613025 112.55881)
		(width 0.254)
		(layer "F.Cu")
		(net "GND")
	)
	(segment
		(start 167.018795 82.3468)
		(end 167.018795 80.948)
		(width 0.254)
		(layer "F.Cu")
		(net "GND")
	)
	(segment
		(start 204.128195 75.2036)
		(end 204.128195 70.2546)
		(width 0.254)
		(layer "F.Cu")
		(net "GND")
	)
	(segment
		(start 129.588595 154.1786)
		(end 130.563595 154.1786)
		(width 0.508)
		(layer "F.Cu")
		(net "GND")
	)
	(segment
		(start 225.988595 118.0786)
		(end 226.893595 118.0786)
		(width 0.2032)
		(layer "F.Cu")
		(net "GND")
	)
	(segment
		(start 145.022395 123.4676)
		(end 145.022395 123.42636)
		(width 0.254)
		(layer "F.Cu")
		(net "GND")
	)
	(segment
		(start 168.593595 82.3976)
		(end 168.593595 80.9734)
		(width 0.254)
		(layer "F.Cu")
		(net "GND")
	)
	(segment
		(start 121.688325 96.63826)
		(end 121.688325 95.17887)
		(width 0.2032)
		(layer "F.Cu")
		(net "GND")
	)
	(segment
		(start 121.588595 98.93358)
		(end 121.588595 98.8786)
		(width 0.2032)
		(layer "F.Cu")
		(net "GND")
	)
	(segment
		(start 130.688475 132.73371)
		(end 130.888595 132.53359)
		(width 0.2032)
		(layer "F.Cu")
		(net "GND")
	)
	(segment
		(start 75.088595 125.6536)
		(end 75.121595 125.6866)
		(width 0.3048)
		(layer "F.Cu")
		(net "GND")
	)
	(segment
		(start 161.087895 64.4761)
		(end 161.100595 64.4634)
		(width 0.254)
		(layer "F.Cu")
		(net "GND")
	)
	(segment
		(start 161.100595 82.0276)
		(end 161.432005 81.69619)
		(width 0.254)
		(layer "F.Cu")
		(net "GND")
	)
	(segment
		(start 169.939795 53.7446)
		(end 171.084595 53.7446)
		(width 0.254)
		(layer "F.Cu")
		(net "GND")
	)
	(segment
		(start 163.054015 69.19477)
		(end 163.655195 69.19477)
		(width 0.2032)
		(layer "F.Cu")
		(net "GND")
	)
	(segment
		(start 117.455595 75.2076)
		(end 117.455595 74.2756)
		(width 0.508)
		(layer "F.Cu")
		(net "GND")
	)
	(segment
		(start 122.388595 136.93358)
		(end 122.388595 136.8786)
		(width 0.2032)
		(layer "F.Cu")
		(net "GND")
	)
	(segment
		(start 151.235745 124.5598)
		(end 153.302795 124.5598)
		(width 0.254)
		(layer "F.Cu")
		(net "GND")
	)
	(segment
		(start 233.909595 107.3386)
		(end 234.989195 107.3386)
		(width 0.254)
		(layer "F.Cu")
		(net "GND")
	)
	(segment
		(start 117.188625 134.22882)
		(end 117.188625 132.47863)
		(width 0.2032)
		(layer "F.Cu")
		(net "GND")
	)
	(segment
		(start 75.096195 122.696)
		(end 75.096195 121.1816)
		(width 0.3048)
		(layer "F.Cu")
		(net "GND")
	)
	(segment
		(start 165.422355 81.07876)
		(end 165.672595 81.329)
		(width 0.254)
		(layer "F.Cu")
		(net "GND")
	)
	(segment
		(start 166.053595 91.362)
		(end 166.053595 89.9506)
		(width 0.508)
		(layer "F.Cu")
		(net "GND")
	)
	(segment
		(start 162.878595 82.3976)
		(end 162.878595 81.1766)
		(width 0.254)
		(layer "F.Cu")
		(net "GND")
	)
	(segment
		(start 227.078595 112.7996)
		(end 228.664595 112.7996)
		(width 0.254)
		(layer "F.Cu")
		(net "GND")
	)
	(segment
		(start 173.388595 65.6786)
		(end 173.388595 64.2786)
		(width 0.2032)
		(layer "F.Cu")
		(net "GND")
	)
	(segment
		(start 75.121595 100.506)
		(end 75.121595 99.0866)
		(width 0.3048)
		(layer "F.Cu")
		(net "GND")
	)
	(segment
		(start 119.188375 96.63835)
		(end 119.188375 94.34333)
		(width 0.2032)
		(layer "F.Cu")
		(net "GND")
	)
	(segment
		(start 165.407595 80.9336)
		(end 165.407595 78.1286)
		(width 0.254)
		(layer "F.Cu")
		(net "GND")
	)
	(segment
		(start 147.183935 117.05791)
		(end 147.185965 117.05994)
		(width 0.254)
		(layer "F.Cu")
		(net "GND")
	)
	(segment
		(start 227.203595 116.8786)
		(end 227.218595 116.8636)
		(width 0.254)
		(layer "F.Cu")
		(net "GND")
	)
	(segment
		(start 99.930195 56.4497)
		(end 100.940695 56.4497)
		(width 0.254)
		(layer "F.Cu")
		(net "GND")
	)
	(segment
		(start 161.838695 117.91617)
		(end 163.232585 117.91617)
		(width 0.254)
		(layer "F.Cu")
		(net "GND")
	)
	(segment
		(start 149.695995 119.0734)
		(end 150.182405 119.55981)
		(width 0.254)
		(layer "F.Cu")
		(net "GND")
	)
	(segment
		(start 148.613355 124.6868)
		(end 148.654595 124.6868)
		(width 0.254)
		(layer "F.Cu")
		(net "GND")
	)
	(segment
		(start 145.022395 123.42636)
		(end 145.098595 123.35016)
		(width 0.254)
		(layer "F.Cu")
		(net "GND")
	)
	(segment
		(start 202.678595 75.1786)
		(end 202.678595 70.5104)
		(width 0.254)
		(layer "F.Cu")
		(net "GND")
	)
	(segment
		(start 75.088595 99.0536)
		(end 75.121595 99.0866)
		(width 0.3048)
		(layer "F.Cu")
		(net "GND")
	)
	(segment
		(start 140.001595 88.5786)
		(end 140.001595 87.0156)
		(width 0.2032)
		(layer "F.Cu")
		(net "GND")
	)
	(segment
		(start 110.158605 157.7576)
		(end 110.158605 154.34359)
		(width 0.508)
		(layer "F.Cu")
		(net "GND")
	)
	(segment
		(start 223.004395 78.5056)
		(end 223.877095 78.5056)
		(width 0.254)
		(layer "F.Cu")
		(net "GND")
	)
	(segment
		(start 222.049595 83.7056)
		(end 222.049595 82.5736)
		(width 0.254)
		(layer "F.Cu")
		(net "GND")
	)
	(segment
		(start 129.188475 100.688)
		(end 129.188475 98.77872)
		(width 0.2032)
		(layer "F.Cu")
		(net "GND")
	)
	(segment
		(start 102.050675 120.05892)
		(end 103.613025 120.05892)
		(width 0.254)
		(layer "F.Cu")
		(net "GND")
	)
	(segment
		(start 171.057395 81.4578)
		(end 171.057395 80.948)
		(width 0.254)
		(layer "F.Cu")
		(net "GND")
	)
	(segment
		(start 154.311595 65.1111)
		(end 155.661855 65.1111)
		(width 0.254)
		(layer "F.Cu")
		(net "GND")
	)
	(segment
		(start 146.318945 122.05993)
		(end 147.185965 122.05993)
		(width 0.254)
		(layer "F.Cu")
		(net "GND")
	)
	(segment
		(start 146.080815 122.30758)
		(end 146.080815 122.29806)
		(width 0.254)
		(layer "F.Cu")
		(net "GND")
	)
	(segment
		(start 107.142105 157.74109)
		(end 107.158615 157.7576)
		(width 0.508)
		(layer "F.Cu")
		(net "GND")
	)
	(segment
		(start 100.922915 120.05892)
		(end 100.927995 120.064)
		(width 0.254)
		(layer "F.Cu")
		(net "GND")
	)
	(segment
		(start 88.918995 123.1882)
		(end 90.056795 123.1882)
		(width 0.254)
		(layer "F.Cu")
		(net "GND")
	)
	(segment
		(start 152.696245 112.05995)
		(end 152.972595 111.7836)
		(width 0.2032)
		(layer "F.Cu")
		(net "GND")
	)
	(segment
		(start 127.688485 132.6337)
		(end 127.788595 132.53359)
		(width 0.2032)
		(layer "F.Cu")
		(net "GND")
	)
	(segment
		(start 102.223395 112.571)
		(end 102.235585 112.55881)
		(width 0.254)
		(layer "F.Cu")
		(net "GND")
	)
	(segment
		(start 165.422355 81.07876)
		(end 165.422355 80.97716)
		(width 0.254)
		(layer "F.Cu")
		(net "GND")
	)
	(segment
		(start 143.788595 91.0786)
		(end 143.788595 91.0786)
		(width 0.2032)
		(layer "F.Cu")
		(net "GND")
	)
	(segment
		(start 161.432005 81.35319)
		(end 161.837195 80.948)
		(width 0.254)
		(layer "F.Cu")
		(net "GND")
	)
	(segment
		(start 101.041785 112.55881)
		(end 101.054995 112.5456)
		(width 0.254)
		(layer "F.Cu")
		(net "GND")
	)
	(segment
		(start 127.132225 155.99134)
		(end 127.158575 156.0177)
		(width 0.508)
		(layer "F.Cu")
		(net "GND")
	)
	(segment
		(start 124.188365 100.68812)
		(end 124.211725 100.71149)
		(width 0.2032)
		(layer "F.Cu")
		(net "GND")
	)
	(segment
		(start 159.068595 91.362)
		(end 159.093995 91.3874)
		(width 0.254)
		(layer "F.Cu")
		(net "GND")
	)
	(segment
		(start 115.365385 65.5556)
		(end 115.863195 65.5556)
		(width 0.254)
		(layer "F.Cu")
		(net "GND")
	)
	(segment
		(start 100.940695 56.4497)
		(end 101.461395 56.9704)
		(width 0.254)
		(layer "F.Cu")
		(net "GND")
	)
	(segment
		(start 116.435795 54.652)
		(end 116.435795 53.7054)
		(width 0.254)
		(layer "F.Cu")
		(net "GND")
	)
	(segment
		(start 100.292035 122.5532)
		(end 100.953395 122.5532)
		(width 0.254)
		(layer "F.Cu")
		(net "GND")
	)
	(segment
		(start 125.690595 70.7736)
		(end 126.429595 71.5126)
		(width 0.508)
		(layer "F.Cu")
		(net "GND")
	)
	(segment
		(start 220.931995 106.9686)
		(end 220.942995 106.9576)
		(width 0.254)
		(layer "F.Cu")
		(net "GND")
	)
	(segment
		(start 165.037595 63.1046)
		(end 165.037595 61.9234)
		(width 0.254)
		(layer "F.Cu")
		(net "GND")
	)
	(segment
		(start 126.688225 94.66695)
		(end 126.788595 94.56659)
		(width 0.2032)
		(layer "F.Cu")
		(net "GND")
	)
	(segment
		(start 162.268995 61.7202)
		(end 162.746185 62.19739)
		(width 0.254)
		(layer "F.Cu")
		(net "GND")
	)
	(segment
		(start 160.733825 116.39217)
		(end 161.838695 116.39217)
		(width 0.254)
		(layer "F.Cu")
		(net "GND")
	)
	(segment
		(start 224.895835 81.202)
		(end 225.010235 81.0876)
		(width 0.2286)
		(layer "F.Cu")
		(net "GND")
	)
	(segment
		(start 217.863595 85.6536)
		(end 217.888595 85.6786)
		(width 0.508)
		(layer "F.Cu")
		(net "GND")
	)
	(segment
		(start 150.388595 144.2786)
		(end 150.488595 144.1786)
		(width 0.2032)
		(layer "F.Cu")
		(net "GND")
	)
	(segment
		(start 87.877595 124.2296)
		(end 88.918995 123.1882)
		(width 0.254)
		(layer "F.Cu")
		(net "GND")
	)
	(segment
		(start 150.580595 142.1366)
		(end 151.437595 142.1366)
		(width 0.254)
		(layer "F.Cu")
		(net "GND")
	)
	(segment
		(start 163.655195 69.19477)
		(end 163.680025 69.2196)
		(width 0.2032)
		(layer "F.Cu")
		(net "GND")
	)
	(segment
		(start 145.098595 123.35016)
		(end 145.098595 123.2898)
		(width 0.254)
		(layer "F.Cu")
		(net "GND")
	)
	(segment
		(start 131.044715 156.98475)
		(end 131.138565 157.0786)
		(width 0.508)
		(layer "F.Cu")
		(net "GND")
	)
	(segment
		(start 131.488595 102.34113)
		(end 131.688215 102.14151)
		(width 0.2032)
		(layer "F.Cu")
		(net "GND")
	)
	(segment
		(start 126.698075 101.86668)
		(end 126.698075 100.66475)
		(width 0.254)
		(layer "F.Cu")
		(net "GND")
	)
	(segment
		(start 183.223995 55.9432)
		(end 183.223995 53.8208)
		(width 0.2032)
		(layer "F.Cu")
		(net "GND")
	)
	(segment
		(start 229.365595 114.0738)
		(end 229.598595 114.3068)
		(width 0.254)
		(layer "F.Cu")
		(net "GND")
	)
	(segment
		(start 130.057215 156.99725)
		(end 130.057215 154.64722)
		(width 0.508)
		(layer "F.Cu")
		(net "GND")
	)
	(segment
		(start 102.096395 125.0424)
		(end 102.112905 125.05891)
		(width 0.254)
		(layer "F.Cu")
		(net "GND")
	)
	(segment
		(start 130.688475 134.22882)
		(end 130.688475 132.73371)
		(width 0.2032)
		(layer "F.Cu")
		(net "GND")
	)
	(segment
		(start 220.018595 96.1786)
		(end 222.339995 96.1786)
		(width 0.254)
		(layer "F.Cu")
		(net "GND")
	)
	(segment
		(start 99.563255 110.05894)
		(end 101.027055 110.05894)
		(width 0.254)
		(layer "F.Cu")
		(net "GND")
	)
	(segment
		(start 131.143595 65.3196)
		(end 131.143595 64.4484)
		(width 0.254)
		(layer "F.Cu")
		(net "GND")
	)
	(segment
		(start 141.542595 64.438)
		(end 141.557595 64.453)
		(width 0.254)
		(layer "F.Cu")
		(net "GND")
	)
	(segment
		(start 171.641595 81.6338)
		(end 172.196635 81.07876)
		(width 0.254)
		(layer "F.Cu")
		(net "GND")
	)
	(segment
		(start 124.688485 132.61995)
		(end 124.788595 132.51984)
		(width 0.254)
		(layer "F.Cu")
		(net "GND")
	)
	(segment
		(start 159.006625 118.42417)
		(end 159.297195 118.1336)
		(width 0.254)
		(layer "F.Cu")
		(net "GND")
	)
	(segment
		(start 226.260595 81.0786)
		(end 227.338595 81.0786)
		(width 0.2286)
		(layer "F.Cu")
		(net "GND")
	)
	(segment
		(start 129.188605 134.22882)
		(end 129.188605 132.63358)
		(width 0.2032)
		(layer "F.Cu")
		(net "GND")
	)
	(segment
		(start 145.216035 114.73)
		(end 145.386215 114.55982)
		(width 0.254)
		(layer "F.Cu")
		(net "GND")
	)
	(segment
		(start 122.188615 132.64353)
		(end 122.288595 132.54356)
		(width 0.2032)
		(layer "F.Cu")
		(net "GND")
	)
	(segment
		(start 163.970795 80.948)
		(end 163.999955 80.97716)
		(width 0.254)
		(layer "F.Cu")
		(net "GND")
	)
	(segment
		(start 124.211725 101.54259)
		(end 124.211725 100.71149)
		(width 0.2032)
		(layer "F.Cu")
		(net "GND")
	)
	(segment
		(start 223.261995 81.202)
		(end 224.895835 81.202)
		(width 0.2286)
		(layer "F.Cu")
		(net "GND")
	)
	(segment
		(start 170.330595 82.1846)
		(end 171.057395 81.4578)
		(width 0.254)
		(layer "F.Cu")
		(net "GND")
	)
	(segment
		(start 226.875595 125.7138)
		(end 226.875595 124.4836)
		(width 0.254)
		(layer "F.Cu")
		(net "GND")
	)
	(segment
		(start 220.229395 98.0278)
		(end 222.339995 98.0278)
		(width 0.254)
		(layer "F.Cu")
		(net "GND")
	)
	(segment
		(start 121.158585 155.05901)
		(end 121.158585 155.05901)
		(width 0.508)
		(layer "F.Cu")
		(net "GND")
	)
	(segment
		(start 112.840595 66.3796)
		(end 114.418595 66.3796)
		(width 0.2032)
		(layer "F.Cu")
		(net "GND")
	)
	(segment
		(start 220.018595 90.9786)
		(end 222.339995 90.9786)
		(width 0.254)
		(layer "F.Cu")
		(net "GND")
	)
	(segment
		(start 122.288595 132.54356)
		(end 122.288595 132.48857)
		(width 0.2032)
		(layer "F.Cu")
		(net "GND")
	)
	(segment
		(start 128.099595 65.6426)
		(end 128.222595 65.5196)
		(width 0.254)
		(layer "F.Cu")
		(net "GND")
	)
	(segment
		(start 151.235745 112.05995)
		(end 152.696245 112.05995)
		(width 0.2032)
		(layer "F.Cu")
		(net "GND")
	)
	(segment
		(start 127.699595 65.8604)
		(end 127.699595 65.8426)
		(width 0.254)
		(layer "F.Cu")
		(net "GND")
	)
	(segment
		(start 126.188615 134.22882)
		(end 126.188615 132.47861)
		(width 0.2032)
		(layer "F.Cu")
		(net "GND")
	)
	(segment
		(start 137.158555 157.7576)
		(end 137.163595 157.75256)
		(width 0.508)
		(layer "F.Cu")
		(net "GND")
	)
	(segment
		(start 114.768595 66.1796)
		(end 115.216595 65.7316)
		(width 0.254)
		(layer "F.Cu")
		(net "GND")
	)
	(segment
		(start 143.091995 76.7316)
		(end 143.091995 74.3982)
		(width 0.254)
		(layer "F.Cu")
		(net "GND")
	)
	(segment
		(start 217.888595 87.0786)
		(end 217.888595 85.6786)
		(width 0.508)
		(layer "F.Cu")
		(net "GND")
	)
	(segment
		(start 223.066595 81.0066)
		(end 223.261995 81.202)
		(width 0.2286)
		(layer "F.Cu")
		(net "GND")
	)
	(segment
		(start 222.049595 83.7056)
		(end 222.492395 84.1484)
		(width 0.254)
		(layer "F.Cu")
		(net "GND")
	)
	(segment
		(start 126.834635 154.2818)
		(end 127.132225 154.57938)
		(width 0.508)
		(layer "F.Cu")
		(net "GND")
	)
	(segment
		(start 87.877595 110.8946)
		(end 87.877595 110.875)
		(width 0.254)
		(layer "F.Cu")
		(net "GND")
	)
	(segment
		(start 173.015995 63.906)
		(end 173.388595 64.2786)
		(width 0.3048)
		(layer "F.Cu")
		(net "GND")
	)
	(segment
		(start 129.188605 132.63358)
		(end 129.288595 132.53359)
		(width 0.2032)
		(layer "F.Cu")
		(net "GND")
	)
	(segment
		(start 131.488595 102.39612)
		(end 131.488595 102.34113)
		(width 0.2032)
		(layer "F.Cu")
		(net "GND")
	)
	(segment
		(start 154.471195 58.3928)
		(end 154.487395 58.3766)
		(width 0.254)
		(layer "F.Cu")
		(net "GND")
	)
	(segment
		(start 162.976435 80.97716)
		(end 163.005595 80.948)
		(width 0.254)
		(layer "F.Cu")
		(net "GND")
	)
	(segment
		(start 171.641595 82.3976)
		(end 171.641595 81.6338)
		(width 0.254)
		(layer "F.Cu")
		(net "GND")
	)
	(segment
		(start 159.761595 64.4761)
		(end 161.087895 64.4761)
		(width 0.254)
		(layer "F.Cu")
		(net "GND")
	)
	(segment
		(start 116.396595 94.23359)
		(end 116.688245 94.52524)
		(width 0.2032)
		(layer "F.Cu")
		(net "GND")
	)
	(segment
		(start 127.132225 155.99134)
		(end 127.132225 154.57938)
		(width 0.508)
		(layer "F.Cu")
		(net "GND")
	)
	(segment
		(start 167.018795 82.3468)
		(end 167.069595 82.3976)
		(width 0.254)
		(layer "F.Cu")
		(net "GND")
	)
	(segment
		(start 131.687395 95.4006)
		(end 131.698065 95.41127)
		(width 0.254)
		(layer "F.Cu")
		(net "GND")
	)
	(segment
		(start 99.563255 122.55879)
		(end 99.565285 122.55676)
		(width 0.254)
		(layer "F.Cu")
		(net "GND")
	)
	(segment
		(start 127.577595 71.8106)
		(end 127.588595 71.7996)
		(width 0.508)
		(layer "F.Cu")
		(net "GND")
	)
	(segment
		(start 145.386215 114.55982)
		(end 147.185965 114.55982)
		(width 0.254)
		(layer "F.Cu")
		(net "GND")
	)
	(segment
		(start 126.688225 96.63835)
		(end 126.688225 94.66695)
		(width 0.2032)
		(layer "F.Cu")
		(net "GND")
	)
	(segment
		(start 122.188615 137.13356)
		(end 122.388595 136.93358)
		(width 0.2032)
		(layer "F.Cu")
		(net "GND")
	)
	(segment
		(start 152.502795 75.6902)
		(end 153.607595 75.6902)
		(width 0.254)
		(layer "F.Cu")
		(net "GND")
	)
	(segment
		(start 152.185195 76.0078)
		(end 152.502795 75.6902)
		(width 0.254)
		(layer "F.Cu")
		(net "GND")
	)
	(segment
		(start 131.688215 102.14151)
		(end 131.688215 100.68812)
		(width 0.2032)
		(layer "F.Cu")
		(net "GND")
	)
	(segment
		(start 170.117595 82.3976)
		(end 170.117595 82.3776)
		(width 0.254)
		(layer "F.Cu")
		(net "GND")
	)
	(segment
		(start 225.818675 121.7341)
		(end 226.831095 121.7341)
		(width 0.254)
		(layer "F.Cu")
		(net "GND")
	)
	(segment
		(start 183.188595 55.9786)
		(end 183.223995 55.9432)
		(width 0.2032)
		(layer "F.Cu")
		(net "GND")
	)
	(segment
		(start 184.343395 53.8208)
		(end 184.419595 53.7446)
		(width 0.254)
		(layer "F.Cu")
		(net "GND")
	)
	(segment
		(start 143.447595 53.3616)
		(end 144.719595 53.3616)
		(width 0.254)
		(layer "F.Cu")
		(net "GND")
	)
	(segment
		(start 226.251595 76.0586)
		(end 226.594595 75.7156)
		(width 0.254)
		(layer "F.Cu")
		(net "GND")
	)
	(segment
		(start 145.755185 119.55981)
		(end 147.185965 119.55981)
		(width 0.254)
		(layer "F.Cu")
		(net "GND")
	)
	(segment
		(start 124.808855 102.13972)
		(end 124.949715 102.13972)
		(width 0.2032)
		(layer "F.Cu")
		(net "GND")
	)
	(segment
		(start 154.445795 58.3928)
		(end 154.471195 58.3928)
		(width 0.254)
		(layer "F.Cu")
		(net "GND")
	)
	(segment
		(start 155.661855 65.1111)
		(end 155.750755 65.0222)
		(width 0.254)
		(layer "F.Cu")
		(net "GND")
	)
	(segment
		(start 119.088595 94.24356)
		(end 119.188375 94.34333)
		(width 0.2032)
		(layer "F.Cu")
		(net "GND")
	)
	(segment
		(start 226.861195 125.7282)
		(end 226.875595 125.7138)
		(width 0.254)
		(layer "F.Cu")
		(net "GND")
	)
	(segment
		(start 148.197395 67.613)
		(end 148.197395 67.5876)
		(width 0.254)
		(layer "F.Cu")
		(net "GND")
	)
	(segment
		(start 103.925195 51.622)
		(end 103.925195 50.6125)
		(width 0.254)
		(layer "F.Cu")
		(net "GND")
	)
	(segment
		(start 145.200195 120.1148)
		(end 145.755185 119.55981)
		(width 0.254)
		(layer "F.Cu")
		(net "GND")
	)
	(segment
		(start 124.698335 138.25523)
		(end 124.698335 136.90826)
		(width 0.254)
		(layer "F.Cu")
		(net "GND")
	)
	(segment
		(start 121.688235 96.63835)
		(end 121.688325 96.63826)
		(width 0.2032)
		(layer "F.Cu")
		(net "GND")
	)
	(segment
		(start 149.525815 114.55982)
		(end 151.235745 114.55982)
		(width 0.2032)
		(layer "F.Cu")
		(net "GND")
	)
	(segment
		(start 226.251595 81.0876)
		(end 226.260595 81.0786)
		(width 0.2286)
		(layer "F.Cu")
		(net "GND")
	)
	(segment
		(start 147.272595 66.6628)
		(end 147.272595 65.3196)
		(width 0.254)
		(layer "F.Cu")
		(net "GND")
	)
	(segment
		(start 127.132225 157.07224)
		(end 127.132225 155.99134)
		(width 0.508)
		(layer "F.Cu")
		(net "GND")
	)
	(segment
		(start 172.196635 80.97716)
		(end 172.225795 80.948)
		(width 0.254)
		(layer "F.Cu")
		(net "GND")
	)
	(segment
		(start 137.888595 91.1786)
		(end 137.888595 91.1786)
		(width 0.2032)
		(layer "F.Cu")
		(net "GND")
	)
	(segment
		(start 225.788595 84.2786)
		(end 227.388595 84.2786)
		(width 0.2032)
		(layer "F.Cu")
		(net "GND")
	)
	(segment
		(start 130.563595 154.1786)
		(end 131.044715 154.65972)
		(width 0.508)
		(layer "F.Cu")
		(net "GND")
	)
	(segment
		(start 162.746185 62.99919)
		(end 162.746185 62.19739)
		(width 0.254)
		(layer "F.Cu")
		(net "GND")
	)
	(segment
		(start 164.275595 82.3976)
		(end 164.275595 81.4052)
		(width 0.254)
		(layer "F.Cu")
		(net "GND")
	)
	(segment
		(start 119.688545 132.47865)
		(end 119.688595 132.4786)
		(width 0.2032)
		(layer "F.Cu")
		(net "GND")
	)
	(segment
		(start 152.653825 109.55983)
		(end 152.972595 109.8786)
		(width 0.2032)
		(layer "F.Cu")
		(net "GND")
	)
	(segment
		(start 172.196635 81.07876)
		(end 172.196635 80.97716)
		(width 0.254)
		(layer "F.Cu")
		(net "GND")
	)
	(segment
		(start 121.158585 157.7576)
		(end 121.158585 155.05901)
		(width 0.508)
		(layer "F.Cu")
		(net "GND")
	)
	(segment
		(start 168.720595 91.362)
		(end 168.720595 89.9506)
		(width 0.508)
		(layer "F.Cu")
		(net "GND")
	)
	(segment
		(start 163.396155 117.7526)
		(end 163.437395 117.7526)
		(width 0.254)
		(layer "F.Cu")
		(net "GND")
	)
	(segment
		(start 223.066595 81.0066)
		(end 223.066595 80.7286)
		(width 0.2286)
		(layer "F.Cu")
		(net "GND")
	)
	(segment
		(start 102.350395 50.6125)
		(end 102.362995 50.6251)
		(width 0.254)
		(layer "F.Cu")
		(net "GND")
	)
	(segment
		(start 118.116725 157.71574)
		(end 118.158595 157.7576)
		(width 0.508)
		(layer "F.Cu")
		(net "GND")
	)
	(segment
		(start 149.695995 119.0734)
		(end 149.695995 118.3622)
		(width 0.254)
		(layer "F.Cu")
		(net "GND")
	)
	(segment
		(start 129.288595 132.53359)
		(end 129.288595 132.4786)
		(width 0.2032)
		(layer "F.Cu")
		(net "GND")
	)
	(segment
		(start 119.788595 136.93358)
		(end 119.788595 136.8786)
		(width 0.2032)
		(layer "F.Cu")
		(net "GND")
	)
	(segment
		(start 145.200195 120.6228)
		(end 145.200195 120.1148)
		(width 0.254)
		(layer "F.Cu")
		(net "GND")
	)
	(segment
		(start 170.588595 63.9786)
		(end 170.988595 63.5786)
		(width 0.3048)
		(layer "F.Cu")
		(net "GND")
	)
	(segment
		(start 152.928515 117.08128)
		(end 152.947195 117.0626)
		(width 0.254)
		(layer "F.Cu")
		(net "GND")
	)
	(segment
		(start 117.188625 137.03355)
		(end 117.288595 136.93358)
		(width 0.2032)
		(layer "F.Cu")
		(net "GND")
	)
	(segment
		(start 141.525595 90.3156)
		(end 142.288595 91.0786)
		(width 0.2032)
		(layer "F.Cu")
		(net "GND")
	)
	(segment
		(start 127.699595 65.8426)
		(end 127.899595 65.6426)
		(width 0.254)
		(layer "F.Cu")
		(net "GND")
	)
	(segment
		(start 151.437595 142.20201)
		(end 151.437595 142.1366)
		(width 0.254)
		(layer "F.Cu")
		(net "GND")
	)
	(segment
		(start 172.215995 63.906)
		(end 173.015995 63.906)
		(width 0.3048)
		(layer "F.Cu")
		(net "GND")
	)
	(segment
		(start 236.288595 113.5412)
		(end 236.288595 112.8686)
		(width 0.2032)
		(layer "F.Cu")
		(net "GND")
	)
	(segment
		(start 141.525595 89.5786)
		(end 141.525595 89.0786)
		(width 0.2032)
		(layer "F.Cu")
		(net "GND")
	)
	(segment
		(start 126.788595 94.56659)
		(end 126.788595 94.5116)
		(width 0.2032)
		(layer "F.Cu")
		(net "GND")
	)
	(segment
		(start 163.232585 117.91617)
		(end 163.396155 117.7526)
		(width 0.254)
		(layer "F.Cu")
		(net "GND")
	)
	(segment
		(start 140.001595 87.0156)
		(end 141.588595 85.4286)
		(width 0.2032)
		(layer "F.Cu")
		(net "GND")
	)
	(segment
		(start 75.121595 113.8664)
		(end 75.121595 112.4866)
		(width 0.3048)
		(layer "F.Cu")
		(net "GND")
	)
	(segment
		(start 131.143595 64.4484)
		(end 131.153995 64.438)
		(width 0.254)
		(layer "F.Cu")
		(net "GND")
	)
	(segment
		(start 163.680025 69.28717)
		(end 163.913595 69.0536)
		(width 0.2032)
		(layer "F.Cu")
		(net "GND")
	)
	(segment
		(start 90.513995 97.5596)
		(end 90.539395 97.5342)
		(width 0.254)
		(layer "F.Cu")
		(net "GND")
	)
	(segment
		(start 157.838695 118.42417)
		(end 159.006625 118.42417)
		(width 0.254)
		(layer "F.Cu")
		(net "GND")
	)
	(segment
		(start 147.185965 124.5598)
		(end 148.486355 124.5598)
		(width 0.254)
		(layer "F.Cu")
		(net "GND")
	)
	(segment
		(start 220.018595 94.3786)
		(end 222.388595 94.3786)
		(width 0.254)
		(layer "F.Cu")
		(net "GND")
	)
	(segment
		(start 151.873855 117.08128)
		(end 152.928515 117.08128)
		(width 0.254)
		(layer "F.Cu")
		(net "GND")
	)
	(segment
		(start 124.188365 96.63835)
		(end 124.188365 94.66682)
		(width 0.2032)
		(layer "F.Cu")
		(net "GND")
	)
	(segment
		(start 160.008395 117.1176)
		(end 160.733825 116.39217)
		(width 0.254)
		(layer "F.Cu")
		(net "GND")
	)
	(segment
		(start 225.988595 116.8786)
		(end 227.203595 116.8786)
		(width 0.254)
		(layer "F.Cu")
		(net "GND")
	)
	(segment
		(start 225.010235 81.0876)
		(end 226.251595 81.0876)
		(width 0.2286)
		(layer "F.Cu")
		(net "GND")
	)
	(segment
		(start 134.044715 156.98475)
		(end 134.138565 157.0786)
		(width 0.508)
		(layer "F.Cu")
		(net "GND")
	)
	(segment
		(start 219.393595 106.9686)
		(end 220.931995 106.9686)
		(width 0.254)
		(layer "F.Cu")
		(net "GND")
	)
	(segment
		(start 147.272595 66.6628)
		(end 148.197395 67.5876)
		(width 0.254)
		(layer "F.Cu")
		(net "GND")
	)
	(segment
		(start 151.235745 109.55983)
		(end 152.653825 109.55983)
		(width 0.2032)
		(layer "F.Cu")
		(net "GND")
	)
	(segment
		(start 134.044715 154.87014)
		(end 134.044715 154.87014)
		(width 0.508)
		(layer "F.Cu")
		(net "GND")
	)
	(segment
		(start 117.888595 154.3286)
		(end 118.116725 154.55673)
		(width 0.508)
		(layer "F.Cu")
		(net "GND")
	)
	(segment
		(start 154.487395 58.3766)
		(end 155.223595 58.3766)
		(width 0.254)
		(layer "F.Cu")
		(net "GND")
	)
	(segment
		(start 210.988595 99.8886)
		(end 210.988595 98.8514)
		(width 0.254)
		(layer "F.Cu")
		(net "GND")
	)
	(segment
		(start 124.698335 136.90826)
		(end 124.753195 136.8534)
		(width 0.254)
		(layer "F.Cu")
		(net "GND")
	)
	(segment
		(start 146.460745 117.05791)
		(end 147.183935 117.05791)
		(width 0.254)
		(layer "F.Cu")
		(net "GND")
	)
	(segment
		(start 75.088595 122.7036)
		(end 75.096195 122.696)
		(width 0.3048)
		(layer "F.Cu")
		(net "GND")
	)
	(segment
		(start 100.201365 117.5842)
		(end 100.709355 117.5842)
		(width 0.254)
		(layer "F.Cu")
		(net "GND")
	)
	(segment
		(start 171.888595 63.5786)
		(end 172.215995 63.906)
		(width 0.3048)
		(layer "F.Cu")
		(net "GND")
	)
	(segment
		(start 145.819995 87.1218)
		(end 145.828595 87.1132)
		(width 0.254)
		(layer "F.Cu")
		(net "GND")
	)
	(segment
		(start 226.927595 119.6786)
		(end 226.948595 119.6576)
		(width 0.2032)
		(layer "F.Cu")
		(net "GND")
	)
	(segment
		(start 156.988595 82.3786)
		(end 156.988595 82.36722)
		(width 0.254)
		(layer "F.Cu")
		(net "GND")
	)
	(segment
		(start 183.223995 53.8208)
		(end 184.343395 53.8208)
		(width 0.254)
		(layer "F.Cu")
		(net "GND")
	)
	(segment
		(start 121.688235 100.68812)
		(end 121.688235 99.03323)
		(width 0.2032)
		(layer "F.Cu")
		(net "GND")
	)
	(segment
		(start 75.146995 136.0452)
		(end 75.146995 134.4658)
		(width 0.3048)
		(layer "F.Cu")
		(net "GND")
	)
	(segment
		(start 126.188605 132.47861)
		(end 126.188615 132.47861)
		(width 0.2032)
		(layer "F.Cu")
		(net "GND")
	)
	(segment
		(start 119.688495 137.03368)
		(end 119.788595 136.93358)
		(width 0.2032)
		(layer "F.Cu")
		(net "GND")
	)
	(segment
		(start 223.064595 80.7266)
		(end 223.066595 80.7286)
		(width 0.2286)
		(layer "F.Cu")
		(net "GND")
	)
	(segment
		(start 122.188615 134.22882)
		(end 122.188615 132.64353)
		(width 0.2032)
		(layer "F.Cu")
		(net "GND")
	)
	(segment
		(start 115.216595 65.7316)
		(end 115.216595 65.70439)
		(width 0.254)
		(layer "F.Cu")
		(net "GND")
	)
	(segment
		(start 129.188355 96.63835)
		(end 129.188355 94.66634)
		(width 0.2032)
		(layer "F.Cu")
		(net "GND")
	)
	(segment
		(start 116.688245 99.67895)
		(end 117.488595 98.8786)
		(width 0.2032)
		(layer "F.Cu")
		(net "GND")
	)
	(segment
		(start 159.068595 91.362)
		(end 159.068595 89.9506)
		(width 0.254)
		(layer "F.Cu")
		(net "GND")
	)
	(segment
		(start 143.788595 91.0786)
		(end 145.225595 91.0786)
		(width 0.2032)
		(layer "F.Cu")
		(net "GND")
	)
	(segment
		(start 117.188625 138.2786)
		(end 117.188625 137.03355)
		(width 0.2032)
		(layer "F.Cu")
		(net "GND")
	)
	(segment
		(start 124.211725 101.54259)
		(end 124.808855 102.13972)
		(width 0.2032)
		(layer "F.Cu")
		(net "GND")
	)
	(segment
		(start 226.893595 118.0786)
		(end 226.948595 118.1336)
		(width 0.2032)
		(layer "F.Cu")
		(net "GND")
	)
	(segment
		(start 124.788595 132.51984)
		(end 124.788595 132.4786)
		(width 0.254)
		(layer "F.Cu")
		(net "GND")
	)
	(segment
		(start 132.188595 138.2786)
		(end 132.188595 136.93358)
		(width 0.2032)
		(layer "F.Cu")
		(net "GND")
	)
	(segment
		(start 101.027055 110.05894)
		(end 101.029595 110.0564)
		(width 0.254)
		(layer "F.Cu")
		(net "GND")
	)
	(segment
		(start 148.335825 109.55983)
		(end 148.781595 110.0056)
		(width 0.2032)
		(layer "F.Cu")
		(net "GND")
	)
	(segment
		(start 102.112905 125.05891)
		(end 103.613025 125.05891)
		(width 0.254)
		(layer "F.Cu")
		(net "GND")
	)
	(segment
		(start 227.405595 105.3066)
		(end 227.648595 105.5496)
		(width 0.254)
		(layer "F.Cu")
		(net "GND")
	)
	(segment
		(start 154.288595 82.2786)
		(end 154.388595 82.3786)
		(width 0.3048)
		(layer "F.Cu")
		(net "GND")
	)
	(segment
		(start 87.877595 110.875)
		(end 88.975595 109.777)
		(width 0.254)
		(layer "F.Cu")
		(net "GND")
	)
	(segment
		(start 125.486995 154.3036)
		(end 125.840995 154.3036)
		(width 0.508)
		(layer "F.Cu")
		(net "GND")
	)
	(segment
		(start 88.791995 136.6502)
		(end 90.412395 136.6502)
		(width 0.254)
		(layer "F.Cu")
		(net "GND")
	)
	(segment
		(start 100.709355 117.5842)
		(end 100.886755 117.7616)
		(width 0.254)
		(layer "F.Cu")
		(net "GND")
	)
	(segment
		(start 226.594595 75.7156)
		(end 227.369195 75.7156)
		(width 0.254)
		(layer "F.Cu")
		(net "GND")
	)
	(segment
		(start 102.362995 52.0428)
		(end 102.362995 50.6251)
		(width 0.254)
		(layer "F.Cu")
		(net "GND")
	)
	(segment
		(start 129.188355 100.68812)
		(end 129.188475 100.688)
		(width 0.2032)
		(layer "F.Cu")
		(net "GND")
	)
	(segment
		(start 125.840995 154.3036)
		(end 126.138575 154.60118)
		(width 0.508)
		(layer "F.Cu")
		(net "GND")
	)
	(segment
		(start 135.988595 91.1786)
		(end 137.888595 91.1786)
		(width 0.2032)
		(layer "F.Cu")
		(net "GND")
	)
	(segment
		(start 100.886755 117.7616)
		(end 100.927995 117.7616)
		(width 0.254)
		(layer "F.Cu")
		(net "GND")
	)
	(segment
		(start 127.688485 134.22882)
		(end 127.688485 132.6337)
		(width 0.2032)
		(layer "F.Cu")
		(net "GND")
	)
	(segment
		(start 148.781595 113.8156)
		(end 149.525815 114.55982)
		(width 0.2032)
		(layer "F.Cu")
		(net "GND")
	)
	(segment
		(start 162.976435 81.07876)
		(end 162.976435 80.97716)
		(width 0.254)
		(layer "F.Cu")
		(net "GND")
	)
	(segment
		(start 149.900305 122.05993)
		(end 151.235745 122.05993)
		(width 0.254)
		(layer "F.Cu")
		(net "GND")
	)
	(segment
		(start 102.934595 56.183)
		(end 103.302895 55.8147)
		(width 0.254)
		(layer "F.Cu")
		(net "GND")
	)
	(segment
		(start 131.865195 53.3636)
		(end 131.867195 53.3616)
		(width 0.254)
		(layer "F.Cu")
		(net "GND")
	)
	(segment
		(start 121.588595 98.93358)
		(end 121.688235 99.03323)
		(width 0.2032)
		(layer "F.Cu")
		(net "GND")
	)
	(segment
		(start 123.143085 154.37508)
		(end 123.158585 154.35959)
		(width 0.508)
		(layer "F.Cu")
		(net "GND")
	)
	(segment
		(start 134.044715 156.98475)
		(end 134.044715 154.87014)
		(width 0.508)
		(layer "F.Cu")
		(net "GND")
	)
	(segment
		(start 102.225935 110.05894)
		(end 103.613025 110.05894)
		(width 0.254)
		(layer "F.Cu")
		(net "GND")
	)
	(segment
		(start 119.088595 94.24356)
		(end 119.088595 94.18857)
		(width 0.2032)
		(layer "F.Cu")
		(net "GND")
	)
	(segment
		(start 127.588595 71.7996)
		(end 127.588595 70.3086)
		(width 0.508)
		(layer "F.Cu")
		(net "GND")
	)
	(segment
		(start 212.129195 105.4336)
		(end 213.259595 105.4336)
		(width 0.254)
		(layer "F.Cu")
		(net "GND")
	)
	(segment
		(start 123.143085 157.74211)
		(end 123.143085 154.37508)
		(width 0.508)
		(layer "F.Cu")
		(net "GND")
	)
	(segment
		(start 170.588595 64.64481)
		(end 170.588595 63.9786)
		(width 0.3048)
		(layer "F.Cu")
		(net "GND")
	)
	(segment
		(start 75.088595 136.1036)
		(end 75.146995 136.0452)
		(width 0.3048)
		(layer "F.Cu")
		(net "GND")
	)
	(segment
		(start 119.688495 138.2786)
		(end 119.688495 137.03368)
		(width 0.2032)
		(layer "F.Cu")
		(net "GND")
	)
	(segment
		(start 170.117595 82.3776)
		(end 170.310595 82.1846)
		(width 0.254)
		(layer "F.Cu")
		(net "GND")
	)
	(segment
		(start 131.044715 156.98475)
		(end 131.044715 154.65972)
		(width 0.508)
		(layer "F.Cu")
		(net "GND")
	)
	(segment
		(start 126.138575 157.0786)
		(end 126.138575 154.60118)
		(width 0.508)
		(layer "F.Cu")
		(net "GND")
	)
	(segment
		(start 220.018595 92.6786)
		(end 222.364875 92.6786)
		(width 0.254)
		(layer "F.Cu")
		(net "GND")
	)
	(segment
		(start 161.432005 81.69619)
		(end 161.432005 81.35319)
		(width 0.254)
		(layer "F.Cu")
		(net "GND")
	)
	(segment
		(start 75.088595 139.0536)
		(end 75.121595 139.0866)
		(width 0.3048)
		(layer "F.Cu")
		(net "GND")
	)
	(segment
		(start 127.788595 132.53359)
		(end 127.788595 132.4786)
		(width 0.2032)
		(layer "F.Cu")
		(net "GND")
	)
	(segment
		(start 152.312195 81.3908)
		(end 152.571605 81.65021)
		(width 0.254)
		(layer "F.Cu")
		(net "GND")
	)
	(segment
		(start 116.396595 94.23359)
		(end 116.396595 94.1786)
		(width 0.2032)
		(layer "F.Cu")
		(net "GND")
	)
	(segment
		(start 75.121595 140.511)
		(end 75.121595 139.0866)
		(width 0.3048)
		(layer "F.Cu")
		(net "GND")
	)
	(segment
		(start 88.975595 109.777)
		(end 90.209195 109.777)
		(width 0.254)
		(layer "F.Cu")
		(net "GND")
	)
	(segment
		(start 226.327795 105.3066)
		(end 227.405595 105.3066)
		(width 0.254)
		(layer "F.Cu")
		(net "GND")
	)
	(segment
		(start 102.223395 117.7616)
		(end 102.264635 117.7616)
		(width 0.254)
		(layer "F.Cu")
		(net "GND")
	)
	(segment
		(start 137.163595 157.75256)
		(end 137.163595 154.1786)
		(width 0.508)
		(layer "F.Cu")
		(net "GND")
	)
	(segment
		(start 118.116725 157.71574)
		(end 118.116725 154.55673)
		(width 0.508)
		(layer "F.Cu")
		(net "GND")
	)
	(segment
		(start 125.465195 154.2818)
		(end 125.486995 154.3036)
		(width 0.508)
		(layer "F.Cu")
		(net "GND")
	)
	(segment
		(start 165.672595 82.3976)
		(end 165.672595 81.329)
		(width 0.254)
		(layer "F.Cu")
		(net "GND")
	)
	(segment
		(start 103.302895 55.8147)
		(end 105.380195 55.8147)
		(width 0.254)
		(layer "F.Cu")
		(net "GND")
	)
	(segment
		(start 125.465195 154.2818)
		(end 126.834635 154.2818)
		(width 0.508)
		(layer "F.Cu")
		(net "GND")
	)
	(segment
		(start 117.158595 154.3286)
		(end 117.888595 154.3286)
		(width 0.508)
		(layer "F.Cu")
		(net "GND")
	)
	(segment
		(start 234.989195 107.3386)
		(end 235.014595 107.364)
		(width 0.254)
		(layer "F.Cu")
		(net "GND")
	)
	(segment
		(start 87.877595 137.5646)
		(end 88.791995 136.6502)
		(width 0.254)
		(layer "F.Cu")
		(net "GND")
	)
	(segment
		(start 229.598595 114.3786)
		(end 229.598595 114.3068)
		(width 0.254)
		(layer "F.Cu")
		(net "GND")
	)
	(segment
		(start 145.123995 117.05187)
		(end 146.454705 117.05187)
		(width 0.254)
		(layer "F.Cu")
		(net "GND")
	)
	(segment
		(start 131.867195 53.3616)
		(end 133.287595 53.3616)
		(width 0.254)
		(layer "F.Cu")
		(net "GND")
	)
	(segment
		(start 146.080815 122.29806)
		(end 146.318945 122.05993)
		(width 0.254)
		(layer "F.Cu")
		(net "GND")
	)
	(segment
		(start 225.988595 115.4786)
		(end 227.206595 115.4786)
		(width 0.254)
		(layer "F.Cu")
		(net "GND")
	)
	(segment
		(start 154.388595 82.3786)
		(end 156.988595 82.3786)
		(width 0.3048)
		(layer "F.Cu")
		(net "GND")
	)
	(segment
		(start 103.925195 51.622)
		(end 104.269795 51.9666)
		(width 0.254)
		(layer "F.Cu")
		(net "GND")
	)
	(segment
		(start 129.588595 154.1786)
		(end 130.057215 154.64722)
		(width 0.508)
		(layer "F.Cu")
		(net "GND")
	)
	(segment
		(start 202.678595 70.5104)
		(end 202.680395 70.5086)
		(width 0.254)
		(layer "F.Cu")
		(net "GND")
	)
	(segment
		(start 102.147195 122.5532)
		(end 102.152785 122.55879)
		(width 0.254)
		(layer "F.Cu")
		(net "GND")
	)
	(via
		(at 172.225795 80.948)
		(size 0.4064)
		(drill 0.2032)
		(layers "F.Cu" "B.Cu")
		(net "GND")
	)
	(via
		(at 123.158585 154.35959)
		(size 0.4064)
		(drill 0.2032)
		(layers "F.Cu" "B.Cu")
		(net "GND")
	)
	(via
		(at 124.288595 94.5116)
		(size 0.4064)
		(drill 0.2032)
		(layers "F.Cu" "B.Cu")
		(net "GND")
	)
	(via
		(at 153.607595 75.6902)
		(size 0.4064)
		(drill 0.2032)
		(layers "F.Cu" "B.Cu")
		(net "GND")
	)
	(via
		(at 122.786105 62.69541)
		(size 5.08)
		(drill 3.2)
		(layers "F.Cu" "B.Cu")
		(net "GND")
	)
	(via
		(at 165.037595 61.9234)
		(size 0.4064)
		(drill 0.2032)
		(layers "F.Cu" "B.Cu")
		(net "GND")
	)
	(via
		(at 161.100595 64.4634)
		(size 0.4064)
		(drill 0.2032)
		(layers "F.Cu" "B.Cu")
		(net "GND")
	)
	(via
		(at 235.014595 107.364)
		(size 0.4064)
		(drill 0.2032)
		(layers "F.Cu" "B.Cu")
		(net "GND")
	)
	(via
		(at 222.339995 98.0278)
		(size 0.4064)
		(drill 0.2032)
		(layers "F.Cu" "B.Cu")
		(net "GND")
	)
	(via
		(at 62.286095 62.69541)
		(size 5.08)
		(drill 3.2)
		(layers "F.Cu" "B.Cu")
		(net "GND")
	)
	(via
		(at 152.972595 109.8786)
		(size 0.4064)
		(drill 0.2032)
		(layers "F.Cu" "B.Cu")
		(net "GND")
	)
	(via
		(at 122.786105 88.69541)
		(size 5.08)
		(drill 3.2)
		(layers "F.Cu" "B.Cu")
		(net "GND")
	)
	(via
		(at 132.288595 136.7786)
		(size 0.4064)
		(drill 0.2032)
		(layers "F.Cu" "B.Cu")
		(net "GND")
	)
	(via
		(at 124.988595 102.1786)
		(size 0.4064)
		(drill 0.2032)
		(layers "F.Cu" "B.Cu")
		(net "GND")
	)
	(via
		(at 119.988595 98.8786)
		(size 0.4064)
		(drill 0.2032)
		(layers "F.Cu" "B.Cu")
		(net "GND")
	)
	(via
		(at 127.577595 71.8106)
		(size 0.4064)
		(drill 0.2032)
		(layers "F.Cu" "B.Cu")
		(net "GND")
	)
	(via
		(at 62.286095 88.69541)
		(size 5.08)
		(drill 3.2)
		(layers "F.Cu" "B.Cu")
		(net "GND")
	)
	(via
		(at 119.800195 76.884)
		(size 0.4064)
		(drill 0.2032)
		(layers "F.Cu" "B.Cu")
		(net "GND")
	)
	(via
		(at 127.699595 65.8604)
		(size 0.4064)
		(drill 0.2032)
		(layers "F.Cu" "B.Cu")
		(net "GND")
	)
	(via
		(at 119.088595 94.18857)
		(size 0.4064)
		(drill 0.2032)
		(layers "F.Cu" "B.Cu")
		(net "GND")
	)
	(via
		(at 132.188595 132.4786)
		(size 0.4064)
		(drill 0.2032)
		(layers "F.Cu" "B.Cu")
		(net "GND")
	)
	(via
		(at 122.288595 132.48857)
		(size 0.4064)
		(drill 0.2032)
		(layers "F.Cu" "B.Cu")
		(net "GND")
	)
	(via
		(at 145.022395 123.4676)
		(size 0.4064)
		(drill 0.2032)
		(layers "F.Cu" "B.Cu")
		(net "GND")
	)
	(via
		(at 161.735595 91.4382)
		(size 0.4064)
		(drill 0.2032)
		(layers "F.Cu" "B.Cu")
		(net "GND")
	)
	(via
		(at 154.445795 58.3928)
		(size 0.4064)
		(drill 0.2032)
		(layers "F.Cu" "B.Cu")
		(net "GND")
	)
	(via
		(at 75.096195 121.1816)
		(size 0.4064)
		(drill 0.2032)
		(layers "F.Cu" "B.Cu")
		(net "GND")
	)
	(via
		(at 141.738595 85.3036)
		(size 0.4064)
		(drill 0.2032)
		(layers "F.Cu" "B.Cu")
		(net "GND")
	)
	(via
		(at 225.988595 118.0786)
		(size 0.4064)
		(drill 0.2032)
		(layers "F.Cu" "B.Cu")
		(net "GND")
	)
	(via
		(at 107.158615 154.36162)
		(size 0.4064)
		(drill 0.2032)
		(layers "F.Cu" "B.Cu")
		(net "GND")
	)
	(via
		(at 226.861195 125.7282)
		(size 0.4064)
		(drill 0.2032)
		(layers "F.Cu" "B.Cu")
		(net "GND")
	)
	(via
		(at 227.338595 81.0786)
		(size 0.4064)
		(drill 0.2032)
		(layers "F.Cu" "B.Cu")
		(net "GND")
	)
	(via
		(at 222.492395 84.1484)
		(size 0.4064)
		(drill 0.2032)
		(layers "F.Cu" "B.Cu")
		(net "GND")
	)
	(via
		(at 161.837195 80.948)
		(size 0.4064)
		(drill 0.2032)
		(layers "F.Cu" "B.Cu")
		(net "GND")
	)
	(via
		(at 102.147195 115.0602)
		(size 0.4064)
		(drill 0.2032)
		(layers "F.Cu" "B.Cu")
		(net "GND")
	)
	(via
		(at 171.057395 80.948)
		(size 0.4064)
		(drill 0.2032)
		(layers "F.Cu" "B.Cu")
		(net "GND")
	)
	(via
		(at 148.781595 111.2756)
		(size 0.4064)
		(drill 0.2032)
		(layers "F.Cu" "B.Cu")
		(net "GND")
	)
	(via
		(at 90.056795 123.1882)
		(size 0.4064)
		(drill 0.2032)
		(layers "F.Cu" "B.Cu")
		(net "GND")
	)
	(via
		(at 103.925195 50.6125)
		(size 0.4064)
		(drill 0.2032)
		(layers "F.Cu" "B.Cu")
		(net "GND")
	)
	(via
		(at 122.388595 136.8786)
		(size 0.4064)
		(drill 0.2032)
		(layers "F.Cu" "B.Cu")
		(net "GND")
	)
	(via
		(at 220.088595 85.5786)
		(size 0.4064)
		(drill 0.2032)
		(layers "F.Cu" "B.Cu")
		(net "GND")
	)
	(via
		(at 125.465195 154.2818)
		(size 0.4064)
		(drill 0.2032)
		(layers "F.Cu" "B.Cu")
		(net "GND")
	)
	(via
		(at 126.708995 101.8776)
		(size 0.4064)
		(drill 0.2032)
		(layers "F.Cu" "B.Cu")
		(net "GND")
	)
	(via
		(at 235.751195 114.0786)
		(size 0.4064)
		(drill 0.2032)
		(layers "F.Cu" "B.Cu")
		(net "GND")
	)
	(via
		(at 129.188595 98.7786)
		(size 0.4064)
		(drill 0.2032)
		(layers "F.Cu" "B.Cu")
		(net "GND")
	)
	(via
		(at 163.970795 80.948)
		(size 0.4064)
		(drill 0.2032)
		(layers "F.Cu" "B.Cu")
		(net "GND")
	)
	(via
		(at 217.869595 99.8456)
		(size 0.4064)
		(drill 0.2032)
		(layers "F.Cu" "B.Cu")
		(net "GND")
	)
	(via
		(at 210.988595 98.8514)
		(size 0.4064)
		(drill 0.2032)
		(layers "F.Cu" "B.Cu")
		(net "GND")
	)
	(via
		(at 159.093995 91.3874)
		(size 0.4064)
		(drill 0.2032)
		(layers "F.Cu" "B.Cu")
		(net "GND")
	)
	(via
		(at 75.121595 100.506)
		(size 0.4064)
		(drill 0.2032)
		(layers "F.Cu" "B.Cu")
		(net "GND")
	)
	(via
		(at 225.818675 121.7341)
		(size 0.4064)
		(drill 0.2032)
		(layers "F.Cu" "B.Cu")
		(net "GND")
	)
	(via
		(at 227.388595 84.2786)
		(size 0.4064)
		(drill 0.2032)
		(layers "F.Cu" "B.Cu")
		(net "GND")
	)
	(via
		(at 82.288595 101.7036)
		(size 0.4064)
		(drill 0.2032)
		(layers "F.Cu" "B.Cu")
		(net "GND")
	)
	(via
		(at 129.288595 132.4786)
		(size 0.4064)
		(drill 0.2032)
		(layers "F.Cu" "B.Cu")
		(net "GND")
	)
	(via
		(at 166.053595 91.362)
		(size 0.4064)
		(drill 0.2032)
		(layers "F.Cu" "B.Cu")
		(net "GND")
	)
	(via
		(at 145.225595 91.0786)
		(size 0.4064)
		(drill 0.2032)
		(layers "F.Cu" "B.Cu")
		(net "GND")
	)
	(via
		(at 202.680395 70.5086)
		(size 0.4064)
		(drill 0.2032)
		(layers "F.Cu" "B.Cu")
		(net "GND")
	)
	(via
		(at 183.223995 53.8208)
		(size 0.4064)
		(drill 0.2032)
		(layers "F.Cu" "B.Cu")
		(net "GND")
	)
	(via
		(at 222.339995 96.1786)
		(size 0.4064)
		(drill 0.2032)
		(layers "F.Cu" "B.Cu")
		(net "GND")
	)
	(via
		(at 222.339995 90.9786)
		(size 0.4064)
		(drill 0.2032)
		(layers "F.Cu" "B.Cu")
		(net "GND")
	)
	(via
		(at 101.461395 56.9704)
		(size 0.4064)
		(drill 0.2032)
		(layers "F.Cu" "B.Cu")
		(net "GND")
	)
	(via
		(at 163.437395 117.7526)
		(size 0.4064)
		(drill 0.2032)
		(layers "F.Cu" "B.Cu")
		(net "GND")
	)
	(via
		(at 102.223395 110.0564)
		(size 0.4064)
		(drill 0.2032)
		(layers "F.Cu" "B.Cu")
		(net "GND")
	)
	(via
		(at 149.695995 118.3622)
		(size 0.4064)
		(drill 0.2032)
		(layers "F.Cu" "B.Cu")
		(net "GND")
	)
	(via
		(at 148.781595 113.8156)
		(size 0.4064)
		(drill 0.2032)
		(layers "F.Cu" "B.Cu")
		(net "GND")
	)
	(via
		(at 220.942995 106.9576)
		(size 0.4064)
		(drill 0.2032)
		(layers "F.Cu" "B.Cu")
		(net "GND")
	)
	(via
		(at 152.921795 82.5482)
		(size 0.4064)
		(drill 0.2032)
		(layers "F.Cu" "B.Cu")
		(net "GND")
	)
	(via
		(at 222.388595 94.3786)
		(size 0.4064)
		(drill 0.2032)
		(layers "F.Cu" "B.Cu")
		(net "GND")
	)
	(via
		(at 148.197395 67.613)
		(size 0.4064)
		(drill 0.2032)
		(layers "F.Cu" "B.Cu")
		(net "GND")
	)
	(via
		(at 120.643785 154.41678)
		(size 0.4064)
		(drill 0.2032)
		(layers "F.Cu" "B.Cu")
		(net "GND")
	)
	(via
		(at 152.947195 117.0626)
		(size 0.4064)
		(drill 0.2032)
		(layers "F.Cu" "B.Cu")
		(net "GND")
	)
	(via
		(at 149.797595 122.1214)
		(size 0.4064)
		(drill 0.2032)
		(layers "F.Cu" "B.Cu")
		(net "GND")
	)
	(via
		(at 217.863595 85.6536)
		(size 0.4064)
		(drill 0.2032)
		(layers "F.Cu" "B.Cu")
		(net "GND")
	)
	(via
		(at 226.327795 105.3066)
		(size 0.4064)
		(drill 0.2032)
		(layers "F.Cu" "B.Cu")
		(net "GND")
	)
	(via
		(at 102.223395 117.7616)
		(size 0.4064)
		(drill 0.2032)
		(layers "F.Cu" "B.Cu")
		(net "GND")
	)
	(via
		(at 173.388595 65.6786)
		(size 0.4064)
		(drill 0.2032)
		(layers "F.Cu" "B.Cu")
		(net "GND")
	)
	(via
		(at 102.223395 112.571)
		(size 0.4064)
		(drill 0.2032)
		(layers "F.Cu" "B.Cu")
		(net "GND")
	)
	(via
		(at 102.350395 50.6125)
		(size 0.4064)
		(drill 0.2032)
		(layers "F.Cu" "B.Cu")
		(net "GND")
	)
	(via
		(at 223.000395 78.5096)
		(size 0.4064)
		(drill 0.2032)
		(layers "F.Cu" "B.Cu")
		(net "GND")
	)
	(via
		(at 222.364875 92.6786)
		(size 0.4064)
		(drill 0.2032)
		(layers "F.Cu" "B.Cu")
		(net "GND")
	)
	(via
		(at 163.005595 80.948)
		(size 0.4064)
		(drill 0.2032)
		(layers "F.Cu" "B.Cu")
		(net "GND")
	)
	(via
		(at 141.542595 64.3618)
		(size 0.4064)
		(drill 0.2032)
		(layers "F.Cu" "B.Cu")
		(net "GND")
	)
	(via
		(at 150.026195 143.2542)
		(size 0.4064)
		(drill 0.2032)
		(layers "F.Cu" "B.Cu")
		(net "GND")
	)
	(via
		(at 102.934595 56.183)
		(size 0.4064)
		(drill 0.2032)
		(layers "F.Cu" "B.Cu")
		(net "GND")
	)
	(via
		(at 225.988595 116.8786)
		(size 0.4064)
		(drill 0.2032)
		(layers "F.Cu" "B.Cu")
		(net "GND")
	)
	(via
		(at 129.088595 94.5116)
		(size 0.4064)
		(drill 0.2032)
		(layers "F.Cu" "B.Cu")
		(net "GND")
	)
	(via
		(at 117.158595 154.3286)
		(size 0.4064)
		(drill 0.2032)
		(layers "F.Cu" "B.Cu")
		(net "GND")
	)
	(via
		(at 135.988595 91.1786)
		(size 0.4064)
		(drill 0.2032)
		(layers "F.Cu" "B.Cu")
		(net "GND")
	)
	(via
		(at 100.927995 117.7616)
		(size 0.4064)
		(drill 0.2032)
		(layers "F.Cu" "B.Cu")
		(net "GND")
	)
	(via
		(at 143.091995 76.7316)
		(size 0.4064)
		(drill 0.2032)
		(layers "F.Cu" "B.Cu")
		(net "GND")
	)
	(via
		(at 90.209195 109.777)
		(size 0.4064)
		(drill 0.2032)
		(layers "F.Cu" "B.Cu")
		(net "GND")
	)
	(via
		(at 117.288595 136.8786)
		(size 0.4064)
		(drill 0.2032)
		(layers "F.Cu" "B.Cu")
		(net "GND")
	)
	(via
		(at 127.788595 132.4786)
		(size 0.4064)
		(drill 0.2032)
		(layers "F.Cu" "B.Cu")
		(net "GND")
	)
	(via
		(at 102.147195 122.5532)
		(size 0.4064)
		(drill 0.2032)
		(layers "F.Cu" "B.Cu")
		(net "GND")
	)
	(via
		(at 212.129195 105.4336)
		(size 0.4064)
		(drill 0.2032)
		(layers "F.Cu" "B.Cu")
		(net "GND")
	)
	(via
		(at 144.742995 53.3382)
		(size 0.4064)
		(drill 0.2032)
		(layers "F.Cu" "B.Cu")
		(net "GND")
	)
	(via
		(at 101.054995 112.5456)
		(size 0.4064)
		(drill 0.2032)
		(layers "F.Cu" "B.Cu")
		(net "GND")
	)
	(via
		(at 153.302795 124.5598)
		(size 0.4064)
		(drill 0.2032)
		(layers "F.Cu" "B.Cu")
		(net "GND")
	)
	(via
		(at 116.675995 53.4652)
		(size 0.4064)
		(drill 0.2032)
		(layers "F.Cu" "B.Cu")
		(net "GND")
	)
	(via
		(at 159.297195 118.1336)
		(size 0.4064)
		(drill 0.2032)
		(layers "F.Cu" "B.Cu")
		(net "GND")
	)
	(via
		(at 100.953395 125.0424)
		(size 0.4064)
		(drill 0.2032)
		(layers "F.Cu" "B.Cu")
		(net "GND")
	)
	(via
		(at 131.865195 53.3636)
		(size 0.4064)
		(drill 0.2032)
		(layers "F.Cu" "B.Cu")
		(net "GND")
	)
	(via
		(at 90.539395 97.5342)
		(size 0.4064)
		(drill 0.2032)
		(layers "F.Cu" "B.Cu")
		(net "GND")
	)
	(via
		(at 228.535995 114.0738)
		(size 0.4064)
		(drill 0.2032)
		(layers "F.Cu" "B.Cu")
		(net "GND")
	)
	(via
		(at 148.654595 124.6868)
		(size 0.4064)
		(drill 0.2032)
		(layers "F.Cu" "B.Cu")
		(net "GND")
	)
	(via
		(at 102.045595 120.064)
		(size 0.4064)
		(drill 0.2032)
		(layers "F.Cu" "B.Cu")
		(net "GND")
	)
	(via
		(at 75.121595 127.2014)
		(size 0.4064)
		(drill 0.2032)
		(layers "F.Cu" "B.Cu")
		(net "GND")
	)
	(via
		(at 133.608465 154.1786)
		(size 0.4064)
		(drill 0.2032)
		(layers "F.Cu" "B.Cu")
		(net "GND")
	)
	(via
		(at 155.791995 65.0222)
		(size 0.4064)
		(drill 0.2032)
		(layers "F.Cu" "B.Cu")
		(net "GND")
	)
	(via
		(at 75.121595 140.511)
		(size 0.4064)
		(drill 0.2032)
		(layers "F.Cu" "B.Cu")
		(net "GND")
	)
	(via
		(at 225.988595 119.6786)
		(size 0.4064)
		(drill 0.2032)
		(layers "F.Cu" "B.Cu")
		(net "GND")
	)
	(via
		(at 100.953395 115.0602)
		(size 0.4064)
		(drill 0.2032)
		(layers "F.Cu" "B.Cu")
		(net "GND")
	)
	(via
		(at 131.153995 64.3872)
		(size 0.4064)
		(drill 0.2032)
		(layers "F.Cu" "B.Cu")
		(net "GND")
	)
	(via
		(at 163.054015 69.19477)
		(size 0.4064)
		(drill 0.2032)
		(layers "F.Cu" "B.Cu")
		(net "GND")
	)
	(via
		(at 228.664595 112.7996)
		(size 0.4064)
		(drill 0.2032)
		(layers "F.Cu" "B.Cu")
		(net "GND")
	)
	(via
		(at 101.029595 110.0564)
		(size 0.4064)
		(drill 0.2032)
		(layers "F.Cu" "B.Cu")
		(net "GND")
	)
	(via
		(at 145.216035 114.73)
		(size 0.4064)
		(drill 0.2032)
		(layers "F.Cu" "B.Cu")
		(net "GND")
	)
	(via
		(at 115.863195 65.5556)
		(size 0.4064)
		(drill 0.2032)
		(layers "F.Cu" "B.Cu")
		(net "GND")
	)
	(via
		(at 100.953395 122.5532)
		(size 0.4064)
		(drill 0.2032)
		(layers "F.Cu" "B.Cu")
		(net "GND")
	)
	(via
		(at 117.188625 132.47863)
		(size 0.4064)
		(drill 0.2032)
		(layers "F.Cu" "B.Cu")
		(net "GND")
	)
	(via
		(at 110.173595 154.3286)
		(size 0.4064)
		(drill 0.2032)
		(layers "F.Cu" "B.Cu")
		(net "GND")
	)
	(via
		(at 117.455595 75.2076)
		(size 0.4064)
		(drill 0.2032)
		(layers "F.Cu" "B.Cu")
		(net "GND")
	)
	(via
		(at 100.927995 120.064)
		(size 0.4064)
		(drill 0.2032)
		(layers "F.Cu" "B.Cu")
		(net "GND")
	)
	(via
		(at 225.988595 115.4786)
		(size 0.4064)
		(drill 0.2032)
		(layers "F.Cu" "B.Cu")
		(net "GND")
	)
	(via
		(at 126.429595 71.6516)
		(size 0.4064)
		(drill 0.2032)
		(layers "F.Cu" "B.Cu")
		(net "GND")
	)
	(via
		(at 160.008395 117.1176)
		(size 0.4064)
		(drill 0.2032)
		(layers "F.Cu" "B.Cu")
		(net "GND")
	)
	(via
		(at 124.788595 132.4786)
		(size 0.4064)
		(drill 0.2032)
		(layers "F.Cu" "B.Cu")
		(net "GND")
	)
	(via
		(at 168.568195 80.948)
		(size 0.4064)
		(drill 0.2032)
		(layers "F.Cu" "B.Cu")
		(net "GND")
	)
	(via
		(at 75.121595 107.9228)
		(size 0.4064)
		(drill 0.2032)
		(layers "F.Cu" "B.Cu")
		(net "GND")
	)
	(via
		(at 149.988595 144.2786)
		(size 0.4064)
		(drill 0.2032)
		(layers "F.Cu" "B.Cu")
		(net "GND")
	)
	(via
		(at 131.488595 102.39612)
		(size 0.4064)
		(drill 0.2032)
		(layers "F.Cu" "B.Cu")
		(net "GND")
	)
	(via
		(at 148.781595 110.0056)
		(size 0.4064)
		(drill 0.2032)
		(layers "F.Cu" "B.Cu")
		(net "GND")
	)
	(via
		(at 119.788595 136.8786)
		(size 0.4064)
		(drill 0.2032)
		(layers "F.Cu" "B.Cu")
		(net "GND")
	)
	(via
		(at 168.720595 91.362)
		(size 0.4064)
		(drill 0.2032)
		(layers "F.Cu" "B.Cu")
		(net "GND")
	)
	(via
		(at 126.188605 132.47861)
		(size 0.4064)
		(drill 0.2032)
		(layers "F.Cu" "B.Cu")
		(net "GND")
	)
	(via
		(at 152.972595 111.7836)
		(size 0.4064)
		(drill 0.2032)
		(layers "F.Cu" "B.Cu")
		(net "GND")
	)
	(via
		(at 167.018795 80.948)
		(size 0.4064)
		(drill 0.2032)
		(layers "F.Cu" "B.Cu")
		(net "GND")
	)
	(via
		(at 156.988595 82.3786)
		(size 0.4064)
		(drill 0.2032)
		(layers "F.Cu" "B.Cu")
		(net "GND")
	)
	(via
		(at 137.163595 154.1786)
		(size 0.4064)
		(drill 0.2032)
		(layers "F.Cu" "B.Cu")
		(net "GND")
	)
	(via
		(at 145.123995 117.05187)
		(size 0.4064)
		(drill 0.2032)
		(layers "F.Cu" "B.Cu")
		(net "GND")
	)
	(via
		(at 102.096395 125.0424)
		(size 0.4064)
		(drill 0.2032)
		(layers "F.Cu" "B.Cu")
		(net "GND")
	)
	(via
		(at 227.369195 75.7156)
		(size 0.4064)
		(drill 0.2032)
		(layers "F.Cu" "B.Cu")
		(net "GND")
	)
	(via
		(at 139.338595 80.9286)
		(size 0.4064)
		(drill 0.2032)
		(layers "F.Cu" "B.Cu")
		(net "GND")
	)
	(via
		(at 165.393195 80.948)
		(size 0.4064)
		(drill 0.2032)
		(layers "F.Cu" "B.Cu")
		(net "GND")
	)
	(via
		(at 145.200195 120.6228)
		(size 0.4064)
		(drill 0.2032)
		(layers "F.Cu" "B.Cu")
		(net "GND")
	)
	(via
		(at 116.396595 94.1786)
		(size 0.4064)
		(drill 0.2032)
		(layers "F.Cu" "B.Cu")
		(net "GND")
	)
	(via
		(at 129.608475 154.1786)
		(size 0.4064)
		(drill 0.2032)
		(layers "F.Cu" "B.Cu")
		(net "GND")
	)
	(via
		(at 126.788595 94.5116)
		(size 0.4064)
		(drill 0.2032)
		(layers "F.Cu" "B.Cu")
		(net "GND")
	)
	(via
		(at 162.268995 61.7202)
		(size 0.4064)
		(drill 0.2032)
		(layers "F.Cu" "B.Cu")
		(net "GND")
	)
	(via
		(at 131.687395 95.4006)
		(size 0.4064)
		(drill 0.2032)
		(layers "F.Cu" "B.Cu")
		(net "GND")
	)
	(via
		(at 131.597015 154.23884)
		(size 0.4064)
		(drill 0.2032)
		(layers "F.Cu" "B.Cu")
		(net "GND")
	)
	(via
		(at 119.938205 89.74741)
		(size 0.4064)
		(drill 0.2032)
		(layers "F.Cu" "B.Cu")
		(net "GND")
	)
	(via
		(at 117.488595 98.8786)
		(size 0.4064)
		(drill 0.2032)
		(layers "F.Cu" "B.Cu")
		(net "GND")
	)
	(via
		(at 121.688415 95.17878)
		(size 0.4064)
		(drill 0.2032)
		(layers "F.Cu" "B.Cu")
		(net "GND")
	)
	(via
		(at 124.698335 136.90826)
		(size 0.4064)
		(drill 0.2032)
		(layers "F.Cu" "B.Cu")
		(net "GND")
	)
	(via
		(at 75.099355 94.69379)
		(size 0.4064)
		(drill 0.2032)
		(layers "F.Cu" "B.Cu")
		(net "GND")
	)
	(via
		(at 90.412395 136.6502)
		(size 0.4064)
		(drill 0.2032)
		(layers "F.Cu" "B.Cu")
		(net "GND")
	)
	(via
		(at 119.688595 132.4786)
		(size 0.4064)
		(drill 0.2032)
		(layers "F.Cu" "B.Cu")
		(net "GND")
	)
	(via
		(at 121.324195 84.885)
		(size 0.4064)
		(drill 0.2032)
		(layers "F.Cu" "B.Cu")
		(net "GND")
	)
	(via
		(at 130.888595 132.4786)
		(size 0.4064)
		(drill 0.2032)
		(layers "F.Cu" "B.Cu")
		(net "GND")
	)
	(via
		(at 169.939795 53.7446)
		(size 0.4064)
		(drill 0.2032)
		(layers "F.Cu" "B.Cu")
		(net "GND")
	)
	(via
		(at 204.128195 70.2546)
		(size 0.4064)
		(drill 0.2032)
		(layers "F.Cu" "B.Cu")
		(net "GND")
	)
	(via
		(at 125.380595 86.3786)
		(size 0.4064)
		(drill 0.2032)
		(layers "F.Cu" "B.Cu")
		(net "GND")
	)
	(via
		(at 121.588595 98.8786)
		(size 0.4064)
		(drill 0.2032)
		(layers "F.Cu" "B.Cu")
		(net "GND")
	)
	(via
		(at 75.121595 113.8664)
		(size 0.4064)
		(drill 0.2032)
		(layers "F.Cu" "B.Cu")
		(net "GND")
	)
	(via
		(at 145.225595 87.1218)
		(size 0.4064)
		(drill 0.2032)
		(layers "F.Cu" "B.Cu")
		(net "GND")
	)
	(via
		(at 75.146995 134.4658)
		(size 0.4064)
		(drill 0.2032)
		(layers "F.Cu" "B.Cu")
		(net "GND")
	)
	(arc
		(start 133.919343 154.535981)
		(mid 134.01234 154.691687)
		(end 134.044715 154.870138)
		(width 0.508)
		(layer "F.Cu")
		(net "GND")
	)
	(arc
		(start 120.955918 154.653006)
		(mid 121.105102 154.832121)
		(end 121.158584 155.059007)
		(width 0.508)
		(layer "F.Cu")
		(net "GND")
	)
	(segment
		(start 125.380595 86.3786)
		(end 125.380595 85.117)
		(width 0.254)
		(layer "B.Cu")
		(net "GND")
	)
	(segment
		(start 131.597015 154.23884)
		(end 131.597595 154.23889)
		(width 0.508)
		(layer "B.Cu")
		(net "GND")
	)
	(segment
		(start 119.850995 89.6602)
		(end 119.850995 88.8492)
		(width 0.254)
		(layer "B.Cu")
		(net "GND")
	)
	(segment
		(start 128.138575 157.0786)
		(end 128.138575 154.47618)
		(width 0.508)
		(layer "B.Cu")
		(net "GND")
	)
	(segment
		(start 129.588595 154.1786)
		(end 129.608475 154.1786)
		(width 0.508)
		(layer "B.Cu")
		(net "GND")
	)
	(segment
		(start 136.194945 154.70118)
		(end 136.717525 154.1786)
		(width 0.508)
		(layer "B.Cu")
		(net "GND")
	)
	(segment
		(start 128.138575 154.47618)
		(end 128.436155 154.1786)
		(width 0.508)
		(layer "B.Cu")
		(net "GND")
	)
	(segment
		(start 123.158585 157.7576)
		(end 123.158585 154.35959)
		(width 0.508)
		(layer "B.Cu")
		(net "GND")
	)
	(segment
		(start 126.589195 85.0992)
		(end 127.369395 84.319)
		(width 0.2032)
		(layer "B.Cu")
		(net "GND")
	)
	(segment
		(start 129.138575 157.0786)
		(end 129.169945 157.04722)
		(width 0.508)
		(layer "B.Cu")
		(net "GND")
	)
	(segment
		(start 125.158575 157.7576)
		(end 125.158575 154.58842)
		(width 0.508)
		(layer "B.Cu")
		(net "GND")
	)
	(segment
		(start 119.300195 88.2984)
		(end 119.850995 88.8492)
		(width 0.254)
		(layer "B.Cu")
		(net "GND")
	)
	(segment
		(start 119.852795 85.2014)
		(end 120.002795 85.2014)
		(width 0.254)
		(layer "B.Cu")
		(net "GND")
	)
	(segment
		(start 132.119715 154.58472)
		(end 132.739385 154.58472)
		(width 0.508)
		(layer "B.Cu")
		(net "GND")
	)
	(segment
		(start 119.087195 88.0854)
		(end 119.107195 88.0854)
		(width 0.254)
		(layer "B.Cu")
		(net "GND")
	)
	(segment
		(start 117.158595 157.7576)
		(end 117.158595 154.3286)
		(width 0.508)
		(layer "B.Cu")
		(net "GND")
	)
	(segment
		(start 125.158575 154.58842)
		(end 125.465195 154.2818)
		(width 0.508)
		(layer "B.Cu")
		(net "GND")
	)
	(segment
		(start 131.921035 154.38605)
		(end 131.921435 154.38644)
		(width 0.508)
		(layer "B.Cu")
		(net "GND")
	)
	(segment
		(start 120.158585 157.7576)
		(end 120.158585 155.01902)
		(width 0.508)
		(layer "B.Cu")
		(net "GND")
	)
	(segment
		(start 127.369395 84.319)
		(end 127.369395 84.299)
		(width 0.2032)
		(layer "B.Cu")
		(net "GND")
	)
	(segment
		(start 136.158555 157.7576)
		(end 136.169945 157.74622)
		(width 0.508)
		(layer "B.Cu")
		(net "GND")
	)
	(segment
		(start 132.119715 157.05975)
		(end 132.119715 154.58472)
		(width 0.508)
		(layer "B.Cu")
		(net "GND")
	)
	(segment
		(start 119.300195 88.2984)
		(end 119.300195 88.2784)
		(width 0.254)
		(layer "B.Cu")
		(net "GND")
	)
	(segment
		(start 136.169945 157.04721)
		(end 136.194945 157.02222)
		(width 0.508)
		(layer "B.Cu")
		(net "GND")
	)
	(segment
		(start 129.169945 154.59725)
		(end 129.588595 154.1786)
		(width 0.508)
		(layer "B.Cu")
		(net "GND")
	)
	(segment
		(start 136.169945 157.74622)
		(end 136.169945 157.04721)
		(width 0.508)
		(layer "B.Cu")
		(net "GND")
	)
	(segment
		(start 136.194945 157.02222)
		(end 136.194945 154.70118)
		(width 0.508)
		(layer "B.Cu")
		(net "GND")
	)
	(segment
		(start 129.169945 157.04722)
		(end 129.169945 154.59725)
		(width 0.508)
		(layer "B.Cu")
		(net "GND")
	)
	(segment
		(start 120.002795 85.2014)
		(end 120.319195 84.885)
		(width 0.254)
		(layer "B.Cu")
		(net "GND")
	)
	(segment
		(start 125.362795 85.0992)
		(end 125.380595 85.117)
		(width 0.254)
		(layer "B.Cu")
		(net "GND")
	)
	(segment
		(start 119.404795 85.7994)
		(end 119.404795 85.6494)
		(width 0.254)
		(layer "B.Cu")
		(net "GND")
	)
	(segment
		(start 125.362795 85.0992)
		(end 126.589195 85.0992)
		(width 0.2032)
		(layer "B.Cu")
		(net "GND")
	)
	(segment
		(start 132.119715 157.05975)
		(end 132.138565 157.0786)
		(width 0.508)
		(layer "B.Cu")
		(net "GND")
	)
	(segment
		(start 131.921435 154.38644)
		(end 132.119715 154.58472)
		(width 0.508)
		(layer "B.Cu")
		(net "GND")
	)
	(segment
		(start 120.319195 84.885)
		(end 121.324195 84.885)
		(width 0.254)
		(layer "B.Cu")
		(net "GND")
	)
	(segment
		(start 117.793595 77.2904)
		(end 119.393795 77.2904)
		(width 0.254)
		(layer "B.Cu")
		(net "GND")
	)
	(segment
		(start 119.393795 77.2904)
		(end 119.800195 76.884)
		(width 0.254)
		(layer "B.Cu")
		(net "GND")
	)
	(segment
		(start 119.107195 88.0854)
		(end 119.300195 88.2784)
		(width 0.254)
		(layer "B.Cu")
		(net "GND")
	)
	(segment
		(start 120.377695 154.60117)
		(end 120.643785 154.41678)
		(width 0.508)
		(layer "B.Cu")
		(net "GND")
	)
	(segment
		(start 133.036965 156.977)
		(end 133.138565 157.0786)
		(width 0.508)
		(layer "B.Cu")
		(net "GND")
	)
	(segment
		(start 107.158615 157.7576)
		(end 107.158615 154.36162)
		(width 0.508)
		(layer "B.Cu")
		(net "GND")
	)
	(segment
		(start 128.436155 154.1786)
		(end 129.588595 154.1786)
		(width 0.508)
		(layer "B.Cu")
		(net "GND")
	)
	(segment
		(start 132.739385 154.58472)
		(end 133.036965 154.8823)
		(width 0.508)
		(layer "B.Cu")
		(net "GND")
	)
	(segment
		(start 119.850995 89.6602)
		(end 119.938205 89.74741)
		(width 0.254)
		(layer "B.Cu")
		(net "GND")
	)
	(segment
		(start 133.036965 156.977)
		(end 133.036965 154.8823)
		(width 0.508)
		(layer "B.Cu")
		(net "GND")
	)
	(segment
		(start 136.717525 154.1786)
		(end 137.163595 154.1786)
		(width 0.508)
		(layer "B.Cu")
		(net "GND")
	)
	(segment
		(start 136.138555 157.0786)
		(end 136.169945 157.04721)
		(width 0.508)
		(layer "B.Cu")
		(net "GND")
	)
	(segment
		(start 119.404795 85.6494)
		(end 119.852795 85.2014)
		(width 0.254)
		(layer "B.Cu")
		(net "GND")
	)
	(arc
		(start 120.158585 155.019027)
		(mid 120.216684 154.783119)
		(end 120.377689 154.601169)
		(width 0.508)
		(layer "B.Cu")
		(net "GND")
	)
	(arc
		(start 131.597592 154.238883)
		(mid 131.772599 154.283261)
		(end 131.921033 154.386044)
		(width 0.508)
		(layer "B.Cu")
		(net "GND")
	)
	(segment
		(start 143.113595 82.4536)
		(end 143.113595 80.4786)
		(width 0.2032)
		(layer "In2.Cu")
		(net "GND")
	)
	(segment
		(start 143.617915 87.18292)
		(end 145.083875 87.18292)
		(width 0.2032)
		(layer "In2.Cu")
		(net "GND")
	)
	(segment
		(start 141.738595 85.3036)
		(end 143.617915 87.18292)
		(width 0.2032)
		(layer "In2.Cu")
		(net "GND")
	)
	(segment
		(start 141.705595 85.2706)
		(end 141.738595 85.3036)
		(width 0.2032)
		(layer "In2.Cu")
		(net "GND")
	)
	(segment
		(start 141.688595 84.7786)
		(end 141.688595 83.8786)
		(width 0.2032)
		(layer "In2.Cu")
		(net "GND")
	)
	(segment
		(start 145.186715 87.16068)
		(end 145.225595 87.1218)
		(width 0.2032)
		(layer "In2.Cu")
		(net "GND")
	)
	(segment
		(start 141.363595 79.6036)
		(end 142.238595 79.6036)
		(width 0.2032)
		(layer "In2.Cu")
		(net "GND")
	)
	(segment
		(start 142.238595 79.6036)
		(end 143.113595 80.4786)
		(width 0.2032)
		(layer "In2.Cu")
		(net "GND")
	)
	(segment
		(start 145.106115 87.16068)
		(end 145.186715 87.16068)
		(width 0.2032)
		(layer "In2.Cu")
		(net "GND")
	)
	(segment
		(start 141.688595 83.8786)
		(end 143.113595 82.4536)
		(width 0.2032)
		(layer "In2.Cu")
		(net "GND")
	)
	(segment
		(start 141.705595 85.2706)
		(end 141.705595 84.7956)
		(width 0.2032)
		(layer "In2.Cu")
		(net "GND")
	)
	(segment
		(start 141.688595 84.7786)
		(end 141.705595 84.7956)
		(width 0.2032)
		(layer "In2.Cu")
		(net "GND")
	)
	(segment
		(start 145.083875 87.18292)
		(end 145.106115 87.16068)
		(width 0.2032)
		(layer "In2.Cu")
		(net "GND")
	)
	(segment
		(start 139.338595 80.9286)
		(end 140.038595 80.9286)
		(width 0.2032)
		(layer "In2.Cu")
		(net "GND")
	)
	(segment
		(start 140.038595 80.9286)
		(end 141.363595 79.6036)
		(width 0.2032)
		(layer "In2.Cu")
		(net "GND")
	)
	(segment
		(start 99.563255 107.55882)
		(end 99.563255 106.77294)
		(width 0.2032)
		(layer "F.Cu")
		(net "FPGA_TMS")
	)
	(segment
		(start 140.782595 67.4446)
		(end 140.907595 67.5696)
		(width 0.2032)
		(layer "F.Cu")
		(net "FPGA_TMS")
	)
	(segment
		(start 99.563255 106.77294)
		(end 99.632595 106.7036)
		(width 0.2032)
		(layer "F.Cu")
		(net "FPGA_TMS")
	)
	(segment
		(start 140.780595 69.2386)
		(end 140.844095 69.1751)
		(width 0.2032)
		(layer "F.Cu")
		(net "FPGA_TMS")
	)
	(segment
		(start 140.844095 69.1751)
		(end 140.844095 67.6331)
		(width 0.2032)
		(layer "F.Cu")
		(net "FPGA_TMS")
	)
	(segment
		(start 138.367595 67.4446)
		(end 140.782595 67.4446)
		(width 0.2032)
		(layer "F.Cu")
		(net "FPGA_TMS")
	)
	(segment
		(start 140.844095 67.6331)
		(end 140.907595 67.5696)
		(width 0.2032)
		(layer "F.Cu")
		(net "FPGA_TMS")
	)
	(via
		(at 98.489595 69.2386)
		(size 0.4064)
		(drill 0.2032)
		(layers "F.Cu" "B.Cu")
		(net "FPGA_TMS")
	)
	(via
		(at 140.780595 69.2386)
		(size 0.4064)
		(drill 0.2032)
		(layers "F.Cu" "B.Cu")
		(net "FPGA_TMS")
	)
	(via
		(at 99.632595 106.7036)
		(size 0.4064)
		(drill 0.2032)
		(layers "F.Cu" "B.Cu")
		(net "FPGA_TMS")
	)
	(segment
		(start 125.466485 69.2386)
		(end 140.780595 69.2386)
		(width 0.2032)
		(layer "In2.Cu")
		(net "FPGA_TMS")
	)
	(segment
		(start 124.831485 69.8736)
		(end 125.466485 69.2386)
		(width 0.2032)
		(layer "In2.Cu")
		(net "FPGA_TMS")
	)
	(segment
		(start 98.972195 69.7212)
		(end 112.267355 69.7212)
		(width 0.2032)
		(layer "In2.Cu")
		(net "FPGA_TMS")
	)
	(segment
		(start 112.419755 69.8736)
		(end 124.831485 69.8736)
		(width 0.2032)
		(layer "In2.Cu")
		(net "FPGA_TMS")
	)
	(segment
		(start 112.267355 69.7212)
		(end 112.419755 69.8736)
		(width 0.2032)
		(layer "In2.Cu")
		(net "FPGA_TMS")
	)
	(segment
		(start 98.489595 69.2386)
		(end 98.972195 69.7212)
		(width 0.2032)
		(layer "In2.Cu")
		(net "FPGA_TMS")
	)
	(segment
		(start 98.489595 99.1046)
		(end 98.489595 69.2386)
		(width 0.2032)
		(layer "In3.Cu")
		(net "FPGA_TMS")
	)
	(segment
		(start 99.632595 106.7036)
		(end 99.632595 100.2476)
		(width 0.2032)
		(layer "In3.Cu")
		(net "FPGA_TMS")
	)
	(segment
		(start 98.489595 99.1046)
		(end 99.632595 100.2476)
		(width 0.2032)
		(layer "In3.Cu")
		(net "FPGA_TMS")
	)
	(segment
		(start 218.838595 96.2286)
		(end 218.888595 96.1786)
		(width 0.508)
		(layer "F.Cu")
		(net "+3.3V")
	)
	(segment
		(start 139.503095 62.63868)
		(end 140.257595 63.39318)
		(width 0.508)
		(layer "F.Cu")
		(net "+3.3V")
	)
	(segment
		(start 149.157035 63.88516)
		(end 149.670595 63.3716)
		(width 0.508)
		(layer "F.Cu")
		(net "+3.3V")
	)
	(segment
		(start 168.513595 69.0286)
		(end 168.513595 68.3286)
		(width 0.508)
		(layer "F.Cu")
		(net "+3.3V")
	)
	(segment
		(start 220.088595 88.8786)
		(end 222.588595 88.8786)
		(width 0.508)
		(layer "F.Cu")
		(net "+3.3V")
	)
	(segment
		(start 127.637795 64.4124)
		(end 129.128395 64.4124)
		(width 0.508)
		(layer "F.Cu")
		(net "+3.3V")
	)
	(segment
		(start 217.988595 89.5786)
		(end 217.988595 88.9786)
		(width 0.508)
		(layer "F.Cu")
		(net "+3.3V")
	)
	(segment
		(start 171.538595 62.51239)
		(end 171.572385 62.4786)
		(width 0.2032)
		(layer "F.Cu")
		(net "+3.3V")
	)
	(segment
		(start 218.888595 92.6786)
		(end 218.888595 91.3786)
		(width 0.508)
		(layer "F.Cu")
		(net "+3.3V")
	)
	(segment
		(start 113.018395 92.5262)
		(end 113.018395 90.6508)
		(width 0.2032)
		(layer "F.Cu")
		(net "+3.3V")
	)
	(segment
		(start 225.763595 82.8786)
		(end 225.788595 82.8786)
		(width 0.508)
		(layer "F.Cu")
		(net "+3.3V")
	)
	(segment
		(start 214.008795 97.3776)
		(end 215.705115 97.3776)
		(width 0.508)
		(layer "F.Cu")
		(net "+3.3V")
	)
	(segment
		(start 138.367595 55.2666)
		(end 138.367595 53.3616)
		(width 0.508)
		(layer "F.Cu")
		(net "+3.3V")
	)
	(segment
		(start 171.133595 89.7156)
		(end 172.881595 89.7156)
		(width 0.508)
		(layer "F.Cu")
		(net "+3.3V")
	)
	(segment
		(start 172.188595 62.4786)
		(end 172.588595 62.8786)
		(width 0.2032)
		(layer "F.Cu")
		(net "+3.3V")
	)
	(segment
		(start 224.838595 86.1786)
		(end 227.138595 86.1786)
		(width 0.508)
		(layer "F.Cu")
		(net "+3.3V")
	)
	(segment
		(start 148.413595 63.8916)
		(end 148.420035 63.88516)
		(width 0.508)
		(layer "F.Cu")
		(net "+3.3V")
	)
	(segment
		(start 148.420035 63.88516)
		(end 149.157035 63.88516)
		(width 0.508)
		(layer "F.Cu")
		(net "+3.3V")
	)
	(segment
		(start 175.088595 62.8786)
		(end 177.288595 65.0786)
		(width 0.2032)
		(layer "F.Cu")
		(net "+3.3V")
	)
	(segment
		(start 218.617595 91.1076)
		(end 218.888595 91.3786)
		(width 0.508)
		(layer "F.Cu")
		(net "+3.3V")
	)
	(segment
		(start 138.367595 55.2666)
		(end 139.503095 56.4021)
		(width 0.508)
		(layer "F.Cu")
		(net "+3.3V")
	)
	(segment
		(start 193.104595 70.73511)
		(end 193.104595 53.3128)
		(width 0.508)
		(layer "F.Cu")
		(net "+3.3V")
	)
	(segment
		(start 168.513595 69.0286)
		(end 168.538595 69.0536)
		(width 0.508)
		(layer "F.Cu")
		(net "+3.3V")
	)
	(segment
		(start 129.843595 65.3196)
		(end 129.843595 65.1276)
		(width 0.508)
		(layer "F.Cu")
		(net "+3.3V")
	)
	(segment
		(start 215.806115 97.4786)
		(end 215.888595 97.4786)
		(width 0.508)
		(layer "F.Cu")
		(net "+3.3V")
	)
	(segment
		(start 177.288595 69.0536)
		(end 179.613155 71.37816)
		(width 0.508)
		(layer "F.Cu")
		(net "+3.3V")
	)
	(segment
		(start 112.840595 68.5274)
		(end 112.840595 67.7796)
		(width 0.254)
		(layer "F.Cu")
		(net "+3.3V")
	)
	(segment
		(start 135.827595 53.3616)
		(end 138.367595 53.3616)
		(width 0.508)
		(layer "F.Cu")
		(net "+3.3V")
	)
	(segment
		(start 148.400595 63.9046)
		(end 148.413595 63.8916)
		(width 0.508)
		(layer "F.Cu")
		(net "+3.3V")
	)
	(segment
		(start 74.867595 52.5116)
		(end 79.989925 52.5116)
		(width 0.508)
		(layer "F.Cu")
		(net "+3.3V")
	)
	(segment
		(start 222.588595 88.8786)
		(end 223.388595 89.6786)
		(width 0.508)
		(layer "F.Cu")
		(net "+3.3V")
	)
	(segment
		(start 148.413595 66.21418)
		(end 151.303015 69.1036)
		(width 0.508)
		(layer "F.Cu")
		(net "+3.3V")
	)
	(segment
		(start 218.888595 94.3786)
		(end 218.888595 92.6786)
		(width 0.508)
		(layer "F.Cu")
		(net "+3.3V")
	)
	(segment
		(start 112.840595 68.8576)
		(end 112.840595 67.5296)
		(width 0.508)
		(layer "F.Cu")
		(net "+3.3V")
	)
	(segment
		(start 171.288595 61.3786)
		(end 171.538595 61.6286)
		(width 0.2032)
		(layer "F.Cu")
		(net "+3.3V")
	)
	(segment
		(start 112.840595 67.5096)
		(end 112.903395 67.4468)
		(width 0.508)
		(layer "F.Cu")
		(net "+3.3V")
	)
	(segment
		(start 223.849595 85.1896)
		(end 223.849595 82.5736)
		(width 0.508)
		(layer "F.Cu")
		(net "+3.3V")
	)
	(segment
		(start 223.849595 85.1896)
		(end 224.838595 86.1786)
		(width 0.508)
		(layer "F.Cu")
		(net "+3.3V")
	)
	(segment
		(start 114.661095 68.0221)
		(end 117.624095 68.0221)
		(width 0.508)
		(layer "F.Cu")
		(net "+3.3V")
	)
	(segment
		(start 177.288595 69.0536)
		(end 177.288595 65.0786)
		(width 0.2032)
		(layer "F.Cu")
		(net "+3.3V")
	)
	(segment
		(start 172.588595 62.8786)
		(end 173.388595 62.8786)
		(width 0.2032)
		(layer "F.Cu")
		(net "+3.3V")
	)
	(segment
		(start 218.888595 96.1536)
		(end 218.888595 94.3786)
		(width 0.508)
		(layer "F.Cu")
		(net "+3.3V")
	)
	(segment
		(start 112.840595 67.5296)
		(end 113.290595 67.9796)
		(width 0.508)
		(layer "F.Cu")
		(net "+3.3V")
	)
	(segment
		(start 222.586395 81.1604)
		(end 222.586395 80.5859)
		(width 0.2032)
		(layer "F.Cu")
		(net "+3.3V")
	)
	(segment
		(start 173.388595 62.8786)
		(end 175.088595 62.8786)
		(width 0.2032)
		(layer "F.Cu")
		(net "+3.3V")
	)
	(segment
		(start 192.469595 71.37011)
		(end 193.104595 70.73511)
		(width 0.508)
		(layer "F.Cu")
		(net "+3.3V")
	)
	(segment
		(start 223.388595 89.6786)
		(end 227.885595 89.6786)
		(width 0.508)
		(layer "F.Cu")
		(net "+3.3V")
	)
	(segment
		(start 215.705115 97.3776)
		(end 215.806115 97.4786)
		(width 0.508)
		(layer "F.Cu")
		(net "+3.3V")
	)
	(segment
		(start 192.469595 71.3976)
		(end 192.469595 71.37011)
		(width 0.508)
		(layer "F.Cu")
		(net "+3.3V")
	)
	(segment
		(start 90.234595 52.5116)
		(end 91.340595 52.5116)
		(width 0.508)
		(layer "F.Cu")
		(net "+3.3V")
	)
	(segment
		(start 217.188595 96.1786)
		(end 218.888595 96.1786)
		(width 0.508)
		(layer "F.Cu")
		(net "+3.3V")
	)
	(segment
		(start 179.613155 71.37816)
		(end 192.450155 71.37816)
		(width 0.508)
		(layer "F.Cu")
		(net "+3.3V")
	)
	(segment
		(start 126.922595 65.1276)
		(end 127.637795 64.4124)
		(width 0.508)
		(layer "F.Cu")
		(net "+3.3V")
	)
	(segment
		(start 223.345645 80.0056)
		(end 223.877095 80.0056)
		(width 0.2032)
		(layer "F.Cu")
		(net "+3.3V")
	)
	(segment
		(start 85.112255 52.5116)
		(end 90.234595 52.5116)
		(width 0.508)
		(layer "F.Cu")
		(net "+3.3V")
	)
	(segment
		(start 190.978595 53.6786)
		(end 192.738795 53.6786)
		(width 0.508)
		(layer "F.Cu")
		(net "+3.3V")
	)
	(segment
		(start 222.591995 80.19715)
		(end 222.813345 79.9758)
		(width 0.2032)
		(layer "F.Cu")
		(net "+3.3V")
	)
	(segment
		(start 227.885595 89.6786)
		(end 228.156595 89.4076)
		(width 0.508)
		(layer "F.Cu")
		(net "+3.3V")
	)
	(segment
		(start 145.972595 65.3196)
		(end 145.972595 64.4696)
		(width 0.508)
		(layer "F.Cu")
		(net "+3.3V")
	)
	(segment
		(start 171.572385 62.4786)
		(end 172.188595 62.4786)
		(width 0.2032)
		(layer "F.Cu")
		(net "+3.3V")
	)
	(segment
		(start 145.972595 64.4696)
		(end 146.537595 63.9046)
		(width 0.508)
		(layer "F.Cu")
		(net "+3.3V")
	)
	(segment
		(start 222.568595 80.5681)
		(end 222.586395 80.5859)
		(width 0.2032)
		(layer "F.Cu")
		(net "+3.3V")
	)
	(segment
		(start 149.670595 64.4496)
		(end 149.670595 63.3716)
		(width 0.508)
		(layer "F.Cu")
		(net "+3.3V")
	)
	(segment
		(start 227.138595 86.1786)
		(end 228.156595 87.1966)
		(width 0.508)
		(layer "F.Cu")
		(net "+3.3V")
	)
	(segment
		(start 217.888595 88.8786)
		(end 220.088595 88.8786)
		(width 0.508)
		(layer "F.Cu")
		(net "+3.3V")
	)
	(segment
		(start 177.688595 52.4786)
		(end 178.200595 51.9666)
		(width 0.508)
		(layer "F.Cu")
		(net "+3.3V")
	)
	(segment
		(start 223.849595 82.5736)
		(end 223.849595 82.4236)
		(width 0.2032)
		(layer "F.Cu")
		(net "+3.3V")
	)
	(segment
		(start 177.678595 53.7786)
		(end 177.688595 53.7686)
		(width 0.508)
		(layer "F.Cu")
		(net "+3.3V")
	)
	(segment
		(start 129.128395 64.4124)
		(end 129.843595 65.1276)
		(width 0.508)
		(layer "F.Cu")
		(net "+3.3V")
	)
	(segment
		(start 146.537595 63.9046)
		(end 148.400595 63.9046)
		(width 0.508)
		(layer "F.Cu")
		(net "+3.3V")
	)
	(segment
		(start 91.340595 52.5116)
		(end 91.377595 52.4746)
		(width 0.508)
		(layer "F.Cu")
		(net "+3.3V")
	)
	(segment
		(start 222.586395 81.1604)
		(end 223.849595 82.4236)
		(width 0.2032)
		(layer "F.Cu")
		(net "+3.3V")
	)
	(segment
		(start 218.617595 91.1076)
		(end 218.617595 90.2076)
		(width 0.508)
		(layer "F.Cu")
		(net "+3.3V")
	)
	(segment
		(start 151.303015 69.1036)
		(end 161.538595 69.1036)
		(width 0.508)
		(layer "F.Cu")
		(net "+3.3V")
	)
	(segment
		(start 139.503095 62.63868)
		(end 139.503095 56.4021)
		(width 0.508)
		(layer "F.Cu")
		(net "+3.3V")
	)
	(segment
		(start 117.624095 68.0221)
		(end 117.666595 68.0646)
		(width 0.508)
		(layer "F.Cu")
		(net "+3.3V")
	)
	(segment
		(start 148.413595 66.21418)
		(end 148.413595 63.8916)
		(width 0.508)
		(layer "F.Cu")
		(net "+3.3V")
	)
	(segment
		(start 167.963595 67.7786)
		(end 168.513595 68.3286)
		(width 0.508)
		(layer "F.Cu")
		(net "+3.3V")
	)
	(segment
		(start 224.054595 82.7786)
		(end 225.688595 82.7786)
		(width 0.508)
		(layer "F.Cu")
		(net "+3.3V")
	)
	(segment
		(start 161.538595 69.1036)
		(end 162.863595 67.7786)
		(width 0.508)
		(layer "F.Cu")
		(net "+3.3V")
	)
	(segment
		(start 168.538595 69.0536)
		(end 177.288595 69.0536)
		(width 0.508)
		(layer "F.Cu")
		(net "+3.3V")
	)
	(segment
		(start 171.263595 60.7786)
		(end 171.288595 60.8036)
		(width 0.2032)
		(layer "F.Cu")
		(net "+3.3V")
	)
	(segment
		(start 192.738795 53.6786)
		(end 193.104595 53.3128)
		(width 0.508)
		(layer "F.Cu")
		(net "+3.3V")
	)
	(segment
		(start 191.758395 51.9666)
		(end 193.104595 53.3128)
		(width 0.508)
		(layer "F.Cu")
		(net "+3.3V")
	)
	(segment
		(start 79.989925 52.5116)
		(end 85.112255 52.5116)
		(width 0.508)
		(layer "F.Cu")
		(net "+3.3V")
	)
	(segment
		(start 223.849595 82.5736)
		(end 224.054595 82.7786)
		(width 0.508)
		(layer "F.Cu")
		(net "+3.3V")
	)
	(segment
		(start 114.618595 67.9796)
		(end 114.661095 68.0221)
		(width 0.508)
		(layer "F.Cu")
		(net "+3.3V")
	)
	(segment
		(start 228.156595 89.4076)
		(end 228.156595 87.1966)
		(width 0.508)
		(layer "F.Cu")
		(net "+3.3V")
	)
	(segment
		(start 192.450155 71.37816)
		(end 192.469595 71.3976)
		(width 0.508)
		(layer "F.Cu")
		(net "+3.3V")
	)
	(segment
		(start 222.568595 80.5681)
		(end 222.591995 80.5447)
		(width 0.2032)
		(layer "F.Cu")
		(net "+3.3V")
	)
	(segment
		(start 112.840595 67.7796)
		(end 112.840595 67.5096)
		(width 0.254)
		(layer "F.Cu")
		(net "+3.3V")
	)
	(segment
		(start 162.863595 67.7786)
		(end 167.963595 67.7786)
		(width 0.508)
		(layer "F.Cu")
		(net "+3.3V")
	)
	(segment
		(start 171.538595 62.51239)
		(end 171.538595 61.6286)
		(width 0.2032)
		(layer "F.Cu")
		(net "+3.3V")
	)
	(segment
		(start 217.988595 89.5786)
		(end 218.617595 90.2076)
		(width 0.508)
		(layer "F.Cu")
		(net "+3.3V")
	)
	(segment
		(start 177.688595 53.7686)
		(end 177.688595 52.4786)
		(width 0.508)
		(layer "F.Cu")
		(net "+3.3V")
	)
	(segment
		(start 215.888595 97.4786)
		(end 217.188595 96.1786)
		(width 0.508)
		(layer "F.Cu")
		(net "+3.3V")
	)
	(segment
		(start 223.315845 79.9758)
		(end 223.345645 80.0056)
		(width 0.2032)
		(layer "F.Cu")
		(net "+3.3V")
	)
	(segment
		(start 126.922595 65.3196)
		(end 126.922595 65.1276)
		(width 0.508)
		(layer "F.Cu")
		(net "+3.3V")
	)
	(segment
		(start 222.813345 79.9758)
		(end 223.315845 79.9758)
		(width 0.2032)
		(layer "F.Cu")
		(net "+3.3V")
	)
	(segment
		(start 222.591995 80.5447)
		(end 222.591995 80.19715)
		(width 0.2032)
		(layer "F.Cu")
		(net "+3.3V")
	)
	(segment
		(start 149.670595 63.3716)
		(end 149.670595 62.7246)
		(width 0.508)
		(layer "F.Cu")
		(net "+3.3V")
	)
	(segment
		(start 112.840595 67.5296)
		(end 112.840595 67.5096)
		(width 0.508)
		(layer "F.Cu")
		(net "+3.3V")
	)
	(segment
		(start 113.290595 67.9796)
		(end 114.618595 67.9796)
		(width 0.508)
		(layer "F.Cu")
		(net "+3.3V")
	)
	(segment
		(start 140.257595 65.3196)
		(end 140.257595 63.39318)
		(width 0.508)
		(layer "F.Cu")
		(net "+3.3V")
	)
	(segment
		(start 178.200595 51.9666)
		(end 191.758395 51.9666)
		(width 0.508)
		(layer "F.Cu")
		(net "+3.3V")
	)
	(segment
		(start 217.888595 88.8786)
		(end 217.988595 88.9786)
		(width 0.508)
		(layer "F.Cu")
		(net "+3.3V")
	)
	(segment
		(start 225.688595 82.7786)
		(end 225.788595 82.8786)
		(width 0.508)
		(layer "F.Cu")
		(net "+3.3V")
	)
	(segment
		(start 171.288595 61.3786)
		(end 171.288595 60.8036)
		(width 0.2032)
		(layer "F.Cu")
		(net "+3.3V")
	)
	(via
		(at 148.400595 63.9046)
		(size 0.4064)
		(drill 0.2032)
		(layers "F.Cu" "B.Cu")
		(net "+3.3V")
	)
	(via
		(at 172.881595 89.7156)
		(size 0.4064)
		(drill 0.2032)
		(layers "F.Cu" "B.Cu")
		(net "+3.3V")
	)
	(via
		(at 113.018395 90.6508)
		(size 0.4064)
		(drill 0.2032)
		(layers "F.Cu" "B.Cu")
		(net "+3.3V")
	)
	(via
		(at 112.840595 68.8576)
		(size 0.4064)
		(drill 0.2032)
		(layers "F.Cu" "B.Cu")
		(net "+3.3V")
	)
	(via
		(at 123.787995 51.7888)
		(size 0.4064)
		(drill 0.2032)
		(layers "F.Cu" "B.Cu")
		(net "+3.3V")
	)
	(via
		(at 127.637795 64.4124)
		(size 0.4064)
		(drill 0.2032)
		(layers "F.Cu" "B.Cu")
		(net "+3.3V")
	)
	(via
		(at 91.377595 52.4746)
		(size 0.4064)
		(drill 0.2032)
		(layers "F.Cu" "B.Cu")
		(net "+3.3V")
	)
	(via
		(at 215.888595 97.4786)
		(size 0.8128)
		(drill 0.4064)
		(layers "F.Cu" "B.Cu")
		(net "+3.3V")
	)
	(via
		(at 140.272595 63.9046)
		(size 0.4064)
		(drill 0.2032)
		(layers "F.Cu" "B.Cu")
		(net "+3.3V")
	)
	(via
		(at 192.469595 71.3976)
		(size 0.4064)
		(drill 0.2032)
		(layers "F.Cu" "B.Cu")
		(net "+3.3V")
	)
	(segment
		(start 214.248435 95.83844)
		(end 215.888595 97.4786)
		(width 0.508)
		(layer "B.Cu")
		(net "+3.3V")
	)
	(segment
		(start 173.079995 89.914)
		(end 210.529195 89.914)
		(width 0.508)
		(layer "B.Cu")
		(net "+3.3V")
	)
	(segment
		(start 134.639655 63.7776)
		(end 134.792055 63.93)
		(width 0.508)
		(layer "B.Cu")
		(net "+3.3V")
	)
	(segment
		(start 129.215265 64.4124)
		(end 129.850065 63.7776)
		(width 0.508)
		(layer "B.Cu")
		(net "+3.3V")
	)
	(segment
		(start 127.637795 64.4124)
		(end 129.215265 64.4124)
		(width 0.508)
		(layer "B.Cu")
		(net "+3.3V")
	)
	(segment
		(start 148.273595 63.7776)
		(end 148.400595 63.9046)
		(width 0.508)
		(layer "B.Cu")
		(net "+3.3V")
	)
	(segment
		(start 214.248435 95.83844)
		(end 214.248435 93.17644)
		(width 0.508)
		(layer "B.Cu")
		(net "+3.3V")
	)
	(segment
		(start 127.572595 64.4126)
		(end 127.572795 64.4124)
		(width 0.508)
		(layer "B.Cu")
		(net "+3.3V")
	)
	(segment
		(start 210.529195 89.914)
		(end 210.757595 89.6856)
		(width 0.508)
		(layer "B.Cu")
		(net "+3.3V")
	)
	(segment
		(start 127.572795 64.4124)
		(end 127.637795 64.4124)
		(width 0.508)
		(layer "B.Cu")
		(net "+3.3V")
	)
	(segment
		(start 210.757595 89.6856)
		(end 214.248435 93.17644)
		(width 0.508)
		(layer "B.Cu")
		(net "+3.3V")
	)
	(segment
		(start 140.247195 63.93)
		(end 140.272595 63.9046)
		(width 0.508)
		(layer "B.Cu")
		(net "+3.3V")
	)
	(segment
		(start 192.469595 71.3976)
		(end 210.757595 89.6856)
		(width 0.508)
		(layer "B.Cu")
		(net "+3.3V")
	)
	(segment
		(start 140.272595 63.9046)
		(end 140.399595 63.7776)
		(width 0.508)
		(layer "B.Cu")
		(net "+3.3V")
	)
	(segment
		(start 134.792055 63.93)
		(end 140.247195 63.93)
		(width 0.508)
		(layer "B.Cu")
		(net "+3.3V")
	)
	(segment
		(start 172.881595 89.7156)
		(end 173.079995 89.914)
		(width 0.508)
		(layer "B.Cu")
		(net "+3.3V")
	)
	(segment
		(start 113.163595 50.9286)
		(end 114.023795 51.7888)
		(width 0.508)
		(layer "In2.Cu")
		(net "+3.3V")
	)
	(segment
		(start 93.093215 52.4746)
		(end 94.397215 53.7786)
		(width 0.508)
		(layer "In2.Cu")
		(net "+3.3V")
	)
	(segment
		(start 114.023795 51.7888)
		(end 123.787995 51.7888)
		(width 0.508)
		(layer "In2.Cu")
		(net "+3.3V")
	)
	(segment
		(start 107.813595 50.9286)
		(end 113.163595 50.9286)
		(width 0.508)
		(layer "In2.Cu")
		(net "+3.3V")
	)
	(segment
		(start 98.530645 51.7536)
		(end 106.988595 51.7536)
		(width 0.508)
		(layer "In2.Cu")
		(net "+3.3V")
	)
	(segment
		(start 94.397215 53.7786)
		(end 96.505645 53.7786)
		(width 0.508)
		(layer "In2.Cu")
		(net "+3.3V")
	)
	(segment
		(start 91.377595 52.4746)
		(end 93.093215 52.4746)
		(width 0.508)
		(layer "In2.Cu")
		(net "+3.3V")
	)
	(segment
		(start 96.505645 53.7786)
		(end 98.530645 51.7536)
		(width 0.508)
		(layer "In2.Cu")
		(net "+3.3V")
	)
	(segment
		(start 106.988595 51.7536)
		(end 107.813595 50.9286)
		(width 0.508)
		(layer "In2.Cu")
		(net "+3.3V")
	)
	(segment
		(start 152.508595 62.5076)
		(end 152.540345 62.53935)
		(width 0.2032)
		(layer "F.Cu")
		(net "UART1_RXD")
	)
	(segment
		(start 152.464595 63.1426)
		(end 152.508595 63.0986)
		(width 0.2032)
		(layer "F.Cu")
		(net "UART1_RXD")
	)
	(segment
		(start 154.279845 62.53935)
		(end 154.311595 62.5711)
		(width 0.2032)
		(layer "F.Cu")
		(net "UART1_RXD")
	)
	(segment
		(start 133.698055 101.85626)
		(end 134.328995 102.4872)
		(width 0.2032)
		(layer "F.Cu")
		(net "UART1_RXD")
	)
	(segment
		(start 152.508595 63.0986)
		(end 152.508595 62.5076)
		(width 0.2032)
		(layer "F.Cu")
		(net "UART1_RXD")
	)
	(segment
		(start 133.698055 101.85626)
		(end 133.698055 100.66475)
		(width 0.2032)
		(layer "F.Cu")
		(net "UART1_RXD")
	)
	(segment
		(start 152.540345 62.53935)
		(end 154.279845 62.53935)
		(width 0.2032)
		(layer "F.Cu")
		(net "UART1_RXD")
	)
	(via
		(at 134.328995 102.4872)
		(size 0.4064)
		(drill 0.2032)
		(layers "F.Cu" "B.Cu")
		(net "UART1_RXD")
	)
	(via
		(at 152.464595 63.1426)
		(size 0.4064)
		(drill 0.2032)
		(layers "F.Cu" "B.Cu")
		(net "UART1_RXD")
	)
	(via
		(at 135.065595 63.2696)
		(size 0.4064)
		(drill 0.2032)
		(layers "F.Cu" "B.Cu")
		(net "UART1_RXD")
	)
	(segment
		(start 135.184625 63.1426)
		(end 152.464595 63.1426)
		(width 0.2032)
		(layer "In2.Cu")
		(net "UART1_RXD")
	)
	(segment
		(start 135.065595 63.26163)
		(end 135.184625 63.1426)
		(width 0.2032)
		(layer "In2.Cu")
		(net "UART1_RXD")
	)
	(segment
		(start 135.065595 63.2696)
		(end 135.065595 63.26163)
		(width 0.2032)
		(layer "In2.Cu")
		(net "UART1_RXD")
	)
	(segment
		(start 134.659195 94.07359)
		(end 135.028005 94.44239)
		(width 0.2032)
		(layer "In3.Cu")
		(net "UART1_RXD")
	)
	(segment
		(start 135.243395 84.49934)
		(end 135.243395 63.50239)
		(width 0.2032)
		(layer "In3.Cu")
		(net "UART1_RXD")
	)
	(segment
		(start 134.659195 85.08354)
		(end 135.243395 84.49934)
		(width 0.2032)
		(layer "In3.Cu")
		(net "UART1_RXD")
	)
	(segment
		(start 134.659195 94.07359)
		(end 134.659195 85.08354)
		(width 0.2032)
		(layer "In3.Cu")
		(net "UART1_RXD")
	)
	(segment
		(start 135.028005 101.78819)
		(end 135.028005 94.44239)
		(width 0.2032)
		(layer "In3.Cu")
		(net "UART1_RXD")
	)
	(segment
		(start 135.065595 63.32459)
		(end 135.243395 63.50239)
		(width 0.2032)
		(layer "In3.Cu")
		(net "UART1_RXD")
	)
	(segment
		(start 135.065595 63.32459)
		(end 135.065595 63.2696)
		(width 0.2032)
		(layer "In3.Cu")
		(net "UART1_RXD")
	)
	(segment
		(start 134.328995 102.4872)
		(end 135.028005 101.78819)
		(width 0.2032)
		(layer "In3.Cu")
		(net "UART1_RXD")
	)
	(segment
		(start 132.198185 102.03279)
		(end 132.677995 102.5126)
		(width 0.2032)
		(layer "F.Cu")
		(net "UART1_TXD")
	)
	(segment
		(start 132.198185 102.03279)
		(end 132.198185 100.66475)
		(width 0.2032)
		(layer "F.Cu")
		(net "UART1_TXD")
	)
	(segment
		(start 152.540345 64.44435)
		(end 154.279845 64.44435)
		(width 0.2032)
		(layer "F.Cu")
		(net "UART1_TXD")
	)
	(segment
		(start 152.508595 64.4126)
		(end 152.540345 64.44435)
		(width 0.2032)
		(layer "F.Cu")
		(net "UART1_TXD")
	)
	(segment
		(start 154.279845 64.44435)
		(end 154.311595 64.4761)
		(width 0.2032)
		(layer "F.Cu")
		(net "UART1_TXD")
	)
	(segment
		(start 152.464595 65.3016)
		(end 152.508595 65.2576)
		(width 0.2032)
		(layer "F.Cu")
		(net "UART1_TXD")
	)
	(segment
		(start 152.508595 65.2576)
		(end 152.508595 64.4126)
		(width 0.2032)
		(layer "F.Cu")
		(net "UART1_TXD")
	)
	(segment
		(start 132.677995 102.5126)
		(end 133.236795 102.5126)
		(width 0.2032)
		(layer "F.Cu")
		(net "UART1_TXD")
	)
	(via
		(at 133.236795 102.5126)
		(size 0.4064)
		(drill 0.2032)
		(layers "F.Cu" "B.Cu")
		(net "UART1_TXD")
	)
	(via
		(at 152.464595 65.3016)
		(size 0.4064)
		(drill 0.2032)
		(layers "F.Cu" "B.Cu")
		(net "UART1_TXD")
	)
	(via
		(at 134.520595 65.3016)
		(size 0.4064)
		(drill 0.2032)
		(layers "F.Cu" "B.Cu")
		(net "UART1_TXD")
	)
	(segment
		(start 134.520595 65.3016)
		(end 152.464595 65.3016)
		(width 0.2032)
		(layer "In2.Cu")
		(net "UART1_TXD")
	)
	(segment
		(start 133.236795 102.5126)
		(end 133.559885 102.5126)
		(width 0.2032)
		(layer "In3.Cu")
		(net "UART1_TXD")
	)
	(segment
		(start 133.848115 98.4198)
		(end 134.176595 98.09131)
		(width 0.2032)
		(layer "In3.Cu")
		(net "UART1_TXD")
	)
	(segment
		(start 134.520595 84.75517)
		(end 134.520595 65.3016)
		(width 0.2032)
		(layer "In3.Cu")
		(net "UART1_TXD")
	)
	(segment
		(start 133.559885 102.5126)
		(end 133.729075 102.34341)
		(width 0.2032)
		(layer "In3.Cu")
		(net "UART1_TXD")
	)
	(segment
		(start 134.176595 85.09917)
		(end 134.520595 84.75517)
		(width 0.2032)
		(layer "In3.Cu")
		(net "UART1_TXD")
	)
	(segment
		(start 134.176595 98.09131)
		(end 134.176595 85.09917)
		(width 0.2032)
		(layer "In3.Cu")
		(net "UART1_TXD")
	)
	(segment
		(start 133.788595 102.19972)
		(end 133.788595 98.56348)
		(width 0.2032)
		(layer "In3.Cu")
		(net "UART1_TXD")
	)
	(arc
		(start 133.788595 98.56348)
		(mid 133.804062 98.485719)
		(end 133.84811 98.419797)
		(width 0.2032)
		(layer "In3.Cu")
		(net "UART1_TXD")
	)
	(arc
		(start 133.788595 102.199723)
		(mid 133.773126 102.277486)
		(end 133.729077 102.34341)
		(width 0.2032)
		(layer "In3.Cu")
		(net "UART1_TXD")
	)
	(segment
		(start 126.574595 67.5696)
		(end 127.572595 67.5696)
		(width 0.2032)
		(layer "F.Cu")
		(net "FPGA_TDO")
	)
	(segment
		(start 103.084965 107.55882)
		(end 103.613025 107.55882)
		(width 0.2032)
		(layer "F.Cu")
		(net "FPGA_TDO")
	)
	(segment
		(start 103.061595 107.53545)
		(end 103.061595 106.5766)
		(width 0.2032)
		(layer "F.Cu")
		(net "FPGA_TDO")
	)
	(segment
		(start 129.545595 66.5716)
		(end 134.704595 66.5716)
		(width 0.2032)
		(layer "F.Cu")
		(net "FPGA_TDO")
	)
	(segment
		(start 103.061595 107.53545)
		(end 103.084965 107.55882)
		(width 0.2032)
		(layer "F.Cu")
		(net "FPGA_TDO")
	)
	(segment
		(start 134.704595 66.5716)
		(end 135.577595 67.4446)
		(width 0.2032)
		(layer "F.Cu")
		(net "FPGA_TDO")
	)
	(segment
		(start 126.556595 67.5876)
		(end 126.574595 67.5696)
		(width 0.2032)
		(layer "F.Cu")
		(net "FPGA_TDO")
	)
	(segment
		(start 128.547595 67.5696)
		(end 129.545595 66.5716)
		(width 0.2032)
		(layer "F.Cu")
		(net "FPGA_TDO")
	)
	(segment
		(start 127.572595 67.5696)
		(end 128.547595 67.5696)
		(width 0.2032)
		(layer "F.Cu")
		(net "FPGA_TDO")
	)
	(segment
		(start 135.577595 67.4446)
		(end 135.827595 67.4446)
		(width 0.2032)
		(layer "F.Cu")
		(net "FPGA_TDO")
	)
	(via
		(at 103.061595 67.5876)
		(size 0.4064)
		(drill 0.2032)
		(layers "F.Cu" "B.Cu")
		(net "FPGA_TDO")
	)
	(via
		(at 126.556595 67.5876)
		(size 0.4064)
		(drill 0.2032)
		(layers "F.Cu" "B.Cu")
		(net "FPGA_TDO")
	)
	(via
		(at 103.061595 106.5766)
		(size 0.4064)
		(drill 0.2032)
		(layers "F.Cu" "B.Cu")
		(net "FPGA_TDO")
	)
	(segment
		(start 126.535995 67.567)
		(end 126.556595 67.5876)
		(width 0.2032)
		(layer "In2.Cu")
		(net "FPGA_TDO")
	)
	(segment
		(start 103.061595 67.5876)
		(end 103.082195 67.567)
		(width 0.2032)
		(layer "In2.Cu")
		(net "FPGA_TDO")
	)
	(segment
		(start 103.082195 67.567)
		(end 126.535995 67.567)
		(width 0.2032)
		(layer "In2.Cu")
		(net "FPGA_TDO")
	)
	(segment
		(start 103.061595 106.5766)
		(end 103.061595 67.5876)
		(width 0.2032)
		(layer "In3.Cu")
		(net "FPGA_TDO")
	)
	(segment
		(start 106.278255 108.05894)
		(end 106.363595 107.9736)
		(width 0.2032)
		(layer "F.Cu")
		(net "FPGA_TCK")
	)
	(segment
		(start 130.345195 67.718)
		(end 130.493595 67.5696)
		(width 0.2032)
		(layer "F.Cu")
		(net "FPGA_TCK")
	)
	(segment
		(start 130.618595 67.4446)
		(end 133.287595 67.4446)
		(width 0.2032)
		(layer "F.Cu")
		(net "FPGA_TCK")
	)
	(segment
		(start 130.345195 67.99)
		(end 130.345195 67.718)
		(width 0.2032)
		(layer "F.Cu")
		(net "FPGA_TCK")
	)
	(segment
		(start 130.493595 67.5696)
		(end 130.618595 67.4446)
		(width 0.2032)
		(layer "F.Cu")
		(net "FPGA_TCK")
	)
	(segment
		(start 103.613025 108.05894)
		(end 106.278255 108.05894)
		(width 0.2032)
		(layer "F.Cu")
		(net "FPGA_TCK")
	)
	(segment
		(start 129.604595 68.7306)
		(end 130.345195 67.99)
		(width 0.2032)
		(layer "F.Cu")
		(net "FPGA_TCK")
	)
	(via
		(at 106.363595 107.9736)
		(size 0.4064)
		(drill 0.2032)
		(layers "F.Cu" "B.Cu")
		(net "FPGA_TCK")
	)
	(via
		(at 129.604595 68.7306)
		(size 0.4064)
		(drill 0.2032)
		(layers "F.Cu" "B.Cu")
		(net "FPGA_TCK")
	)
	(via
		(at 106.363595 69.1116)
		(size 0.4064)
		(drill 0.2032)
		(layers "F.Cu" "B.Cu")
		(net "FPGA_TCK")
	)
	(segment
		(start 115.836725 69.4672)
		(end 116.924125 68.3798)
		(width 0.2032)
		(layer "In2.Cu")
		(net "FPGA_TCK")
	)
	(segment
		(start 116.924125 68.3798)
		(end 123.088955 68.3798)
		(width 0.2032)
		(layer "In2.Cu")
		(net "FPGA_TCK")
	)
	(segment
		(start 123.439765 68.7306)
		(end 129.604595 68.7306)
		(width 0.2032)
		(layer "In2.Cu")
		(net "FPGA_TCK")
	)
	(segment
		(start 112.232495 69.1116)
		(end 112.588095 69.4672)
		(width 0.2032)
		(layer "In2.Cu")
		(net "FPGA_TCK")
	)
	(segment
		(start 106.363595 69.1116)
		(end 112.232495 69.1116)
		(width 0.2032)
		(layer "In2.Cu")
		(net "FPGA_TCK")
	)
	(segment
		(start 123.088955 68.3798)
		(end 123.439765 68.7306)
		(width 0.2032)
		(layer "In2.Cu")
		(net "FPGA_TCK")
	)
	(segment
		(start 112.588095 69.4672)
		(end 115.836725 69.4672)
		(width 0.2032)
		(layer "In2.Cu")
		(net "FPGA_TCK")
	)
	(segment
		(start 106.363595 107.9736)
		(end 106.363595 69.1116)
		(width 0.2032)
		(layer "In3.Cu")
		(net "FPGA_TCK")
	)
	(segment
		(start 229.794595 106.1406)
		(end 229.934595 106.1406)
		(width 0.508)
		(layer "F.Cu")
		(net "+12V")
	)
	(segment
		(start 201.288595 76.40602)
		(end 201.586175 76.7036)
		(width 0.508)
		(layer "F.Cu")
		(net "+12V")
	)
	(segment
		(start 228.977395 106.3398)
		(end 229.176595 106.1406)
		(width 0.508)
		(layer "F.Cu")
		(net "+12V")
	)
	(segment
		(start 216.959595 106.3986)
		(end 217.618595 106.3986)
		(width 0.508)
		(layer "F.Cu")
		(net "+12V")
	)
	(segment
		(start 206.113595 76.7036)
		(end 206.113595 75.2036)
		(width 0.508)
		(layer "F.Cu")
		(net "+12V")
	)
	(segment
		(start 216.853595 106.5046)
		(end 216.959595 106.3986)
		(width 0.508)
		(layer "F.Cu")
		(net "+12V")
	)
	(segment
		(start 217.618595 106.3986)
		(end 218.038595 105.9786)
		(width 0.508)
		(layer "F.Cu")
		(net "+12V")
	)
	(segment
		(start 201.586175 76.7036)
		(end 206.113595 76.7036)
		(width 0.508)
		(layer "F.Cu")
		(net "+12V")
	)
	(segment
		(start 227.648595 107.3496)
		(end 227.819015 107.17918)
		(width 0.508)
		(layer "F.Cu")
		(net "+12V")
	)
	(segment
		(start 229.176595 106.1406)
		(end 229.794595 106.1406)
		(width 0.508)
		(layer "F.Cu")
		(net "+12V")
	)
	(segment
		(start 209.988595 73.7286)
		(end 209.988595 70.2786)
		(width 0.508)
		(layer "F.Cu")
		(net "+12V")
	)
	(segment
		(start 221.679595 105.1796)
		(end 224.803935 105.1796)
		(width 0.508)
		(layer "F.Cu")
		(net "+12V")
	)
	(segment
		(start 228.457595 110.2596)
		(end 228.977395 109.7398)
		(width 0.508)
		(layer "F.Cu")
		(net "+12V")
	)
	(segment
		(start 227.819015 107.17918)
		(end 228.679815 107.17918)
		(width 0.508)
		(layer "F.Cu")
		(net "+12V")
	)
	(segment
		(start 210.012595 70.2546)
		(end 211.794795 70.2546)
		(width 0.508)
		(layer "F.Cu")
		(net "+12V")
	)
	(segment
		(start 218.038595 104.8786)
		(end 218.038595 102.8786)
		(width 0.508)
		(layer "F.Cu")
		(net "+12V")
	)
	(segment
		(start 225.804925 104.1786)
		(end 228.938595 104.1786)
		(width 0.508)
		(layer "F.Cu")
		(net "+12V")
	)
	(segment
		(start 209.988595 70.2786)
		(end 210.012595 70.2546)
		(width 0.508)
		(layer "F.Cu")
		(net "+12V")
	)
	(segment
		(start 228.679815 107.17918)
		(end 228.977395 106.8816)
		(width 0.508)
		(layer "F.Cu")
		(net "+12V")
	)
	(segment
		(start 228.938595 104.1786)
		(end 229.938595 105.1786)
		(width 0.508)
		(layer "F.Cu")
		(net "+12V")
	)
	(segment
		(start 228.977395 109.7398)
		(end 228.977395 106.8816)
		(width 0.508)
		(layer "F.Cu")
		(net "+12V")
	)
	(segment
		(start 229.794595 106.1406)
		(end 229.938595 105.9966)
		(width 0.508)
		(layer "F.Cu")
		(net "+12V")
	)
	(segment
		(start 227.078595 110.2596)
		(end 228.457595 110.2596)
		(width 0.508)
		(layer "F.Cu")
		(net "+12V")
	)
	(segment
		(start 218.038595 105.9786)
		(end 218.038595 104.8786)
		(width 0.508)
		(layer "F.Cu")
		(net "+12V")
	)
	(segment
		(start 201.288595 75.2786)
		(end 201.288595 75.2786)
		(width 0.508)
		(layer "F.Cu")
		(net "+12V")
	)
	(segment
		(start 201.288595 76.40602)
		(end 201.288595 75.2786)
		(width 0.508)
		(layer "F.Cu")
		(net "+12V")
	)
	(segment
		(start 221.674095 105.1741)
		(end 221.679595 105.1796)
		(width 0.508)
		(layer "F.Cu")
		(net "+12V")
	)
	(segment
		(start 224.803935 105.1796)
		(end 225.804925 104.1786)
		(width 0.508)
		(layer "F.Cu")
		(net "+12V")
	)
	(segment
		(start 229.938595 105.9966)
		(end 229.938595 105.1786)
		(width 0.508)
		(layer "F.Cu")
		(net "+12V")
	)
	(segment
		(start 206.113595 76.7036)
		(end 207.013595 76.7036)
		(width 0.508)
		(layer "F.Cu")
		(net "+12V")
	)
	(segment
		(start 218.038595 102.8786)
		(end 218.531595 102.3856)
		(width 0.508)
		(layer "F.Cu")
		(net "+12V")
	)
	(segment
		(start 207.013595 76.7036)
		(end 209.988595 73.7286)
		(width 0.508)
		(layer "F.Cu")
		(net "+12V")
	)
	(segment
		(start 218.334095 105.1741)
		(end 221.674095 105.1741)
		(width 0.508)
		(layer "F.Cu")
		(net "+12V")
	)
	(segment
		(start 218.531595 102.3856)
		(end 219.836595 102.3856)
		(width 0.508)
		(layer "F.Cu")
		(net "+12V")
	)
	(segment
		(start 228.977395 106.8816)
		(end 228.977395 106.3398)
		(width 0.508)
		(layer "F.Cu")
		(net "+12V")
	)
	(segment
		(start 218.038595 104.8786)
		(end 218.334095 105.1741)
		(width 0.508)
		(layer "F.Cu")
		(net "+12V")
	)
	(via
		(at 221.679595 105.1796)
		(size 0.4064)
		(drill 0.2032)
		(layers "F.Cu" "B.Cu")
		(net "+12V")
	)
	(via
		(at 209.988595 70.2786)
		(size 0.8128)
		(drill 0.4064)
		(layers "F.Cu" "B.Cu")
		(net "+12V")
	)
	(segment
		(start 221.679595 81.1766)
		(end 236.411595 95.9086)
		(width 0.508)
		(layer "B.Cu")
		(net "+12V")
	)
	(segment
		(start 236.411595 119.6576)
		(end 236.411595 95.9086)
		(width 0.508)
		(layer "B.Cu")
		(net "+12V")
	)
	(segment
		(start 209.988595 70.2786)
		(end 221.679595 81.9696)
		(width 0.508)
		(layer "B.Cu")
		(net "+12V")
	)
	(segment
		(start 229.426595 126.6426)
		(end 236.411595 119.6576)
		(width 0.508)
		(layer "B.Cu")
		(net "+12V")
	)
	(segment
		(start 221.679595 81.9696)
		(end 221.679595 81.1766)
		(width 0.508)
		(layer "B.Cu")
		(net "+12V")
	)
	(segment
		(start 221.679595 105.1796)
		(end 221.679595 81.9696)
		(width 0.508)
		(layer "B.Cu")
		(net "+12V")
	)
	(segment
		(start 191.038595 55.0786)
		(end 191.088595 55.1286)
		(width 0.2032)
		(layer "F.Cu")
		(net "KEY2")
	)
	(segment
		(start 191.088595 56.7786)
		(end 191.088595 55.1286)
		(width 0.2032)
		(layer "F.Cu")
		(net "KEY2")
	)
	(segment
		(start 147.185965 124.05993)
		(end 147.209335 124.03656)
		(width 0.2032)
		(layer "F.Cu")
		(net "KEY2")
	)
	(segment
		(start 148.593635 124.03656)
		(end 148.654595 123.9756)
		(width 0.2032)
		(layer "F.Cu")
		(net "KEY2")
	)
	(segment
		(start 147.209335 124.03656)
		(end 148.593635 124.03656)
		(width 0.2032)
		(layer "F.Cu")
		(net "KEY2")
	)
	(via
		(at 191.088595 56.7786)
		(size 0.4064)
		(drill 0.2032)
		(layers "F.Cu" "B.Cu")
		(net "KEY2")
	)
	(via
		(at 147.511595 56.7926)
		(size 0.4064)
		(drill 0.2032)
		(layers "F.Cu" "B.Cu")
		(net "KEY2")
	)
	(via
		(at 148.654595 123.9756)
		(size 0.4064)
		(drill 0.2032)
		(layers "F.Cu" "B.Cu")
		(net "KEY2")
	)
	(segment
		(start 147.511595 56.7926)
		(end 147.518595 56.7856)
		(width 0.2032)
		(layer "In2.Cu")
		(net "KEY2")
	)
	(segment
		(start 147.518595 56.7856)
		(end 191.081595 56.7856)
		(width 0.2032)
		(layer "In2.Cu")
		(net "KEY2")
	)
	(segment
		(start 191.081595 56.7856)
		(end 191.088595 56.7786)
		(width 0.2032)
		(layer "In2.Cu")
		(net "KEY2")
	)
	(segment
		(start 147.988595 123.3096)
		(end 147.988595 76.50462)
		(width 0.2032)
		(layer "In3.Cu")
		(net "KEY2")
	)
	(segment
		(start 147.892595 64.64481)
		(end 147.892595 57.1736)
		(width 0.2032)
		(layer "In3.Cu")
		(net "KEY2")
	)
	(segment
		(start 147.638595 76.15462)
		(end 147.988595 76.50462)
		(width 0.2032)
		(layer "In3.Cu")
		(net "KEY2")
	)
	(segment
		(start 147.638595 76.15462)
		(end 147.638595 64.89881)
		(width 0.2032)
		(layer "In3.Cu")
		(net "KEY2")
	)
	(segment
		(start 147.988595 123.3096)
		(end 148.654595 123.9756)
		(width 0.2032)
		(layer "In3.Cu")
		(net "KEY2")
	)
	(segment
		(start 147.511595 56.7926)
		(end 147.892595 57.1736)
		(width 0.2032)
		(layer "In3.Cu")
		(net "KEY2")
	)
	(segment
		(start 147.638595 64.89881)
		(end 147.892595 64.64481)
		(width 0.2032)
		(layer "In3.Cu")
		(net "KEY2")
	)
	(segment
		(start 177.678595 55.1786)
		(end 178.988595 55.1786)
		(width 0.2032)
		(layer "F.Cu")
		(net "KEY1")
	)
	(segment
		(start 179.258275 56.03392)
		(end 179.258275 55.44828)
		(width 0.2032)
		(layer "F.Cu")
		(net "KEY1")
	)
	(segment
		(start 102.174505 121.56069)
		(end 103.611125 121.56069)
		(width 0.2032)
		(layer "F.Cu")
		(net "KEY1")
	)
	(segment
		(start 103.611125 121.56069)
		(end 103.613025 121.55879)
		(width 0.2032)
		(layer "F.Cu")
		(net "KEY1")
	)
	(segment
		(start 102.172595 121.5626)
		(end 102.174505 121.56069)
		(width 0.2032)
		(layer "F.Cu")
		(net "KEY1")
	)
	(segment
		(start 178.988595 55.1786)
		(end 179.258275 55.44828)
		(width 0.2032)
		(layer "F.Cu")
		(net "KEY1")
	)
	(via
		(at 179.258275 56.03392)
		(size 0.4064)
		(drill 0.2032)
		(layers "F.Cu" "B.Cu")
		(net "KEY1")
	)
	(via
		(at 103.696595 55.0146)
		(size 0.4064)
		(drill 0.2032)
		(layers "F.Cu" "B.Cu")
		(net "KEY1")
	)
	(via
		(at 102.172595 121.5626)
		(size 0.4064)
		(drill 0.2032)
		(layers "F.Cu" "B.Cu")
		(net "KEY1")
	)
	(segment
		(start 159.329045 55.0146)
		(end 160.348365 56.03392)
		(width 0.2032)
		(layer "In2.Cu")
		(net "KEY1")
	)
	(segment
		(start 111.013525 53.6536)
		(end 112.374525 55.0146)
		(width 0.2032)
		(layer "In2.Cu")
		(net "KEY1")
	)
	(segment
		(start 109.763595 53.6536)
		(end 111.013525 53.6536)
		(width 0.2032)
		(layer "In2.Cu")
		(net "KEY1")
	)
	(segment
		(start 108.402595 55.0146)
		(end 109.763595 53.6536)
		(width 0.2032)
		(layer "In2.Cu")
		(net "KEY1")
	)
	(segment
		(start 160.348365 56.03392)
		(end 179.258275 56.03392)
		(width 0.2032)
		(layer "In2.Cu")
		(net "KEY1")
	)
	(segment
		(start 112.374525 55.0146)
		(end 159.329045 55.0146)
		(width 0.2032)
		(layer "In2.Cu")
		(net "KEY1")
	)
	(segment
		(start 103.696595 55.0146)
		(end 108.402595 55.0146)
		(width 0.2032)
		(layer "In2.Cu")
		(net "KEY1")
	)
	(segment
		(start 102.172595 121.5626)
		(end 103.696595 120.0386)
		(width 0.2032)
		(layer "In3.Cu")
		(net "KEY1")
	)
	(segment
		(start 103.696595 120.0386)
		(end 103.696595 55.0146)
		(width 0.2032)
		(layer "In3.Cu")
		(net "KEY1")
	)
	(segment
		(start 101.359795 53.262)
		(end 105.576195 53.262)
		(width 0.254)
		(layer "F.Cu")
		(net "+5.0V")
	)
	(segment
		(start 149.457235 108.05996)
		(end 151.235745 108.05996)
		(width 0.254)
		(layer "F.Cu")
		(net "+5.0V")
	)
	(segment
		(start 228.348595 119.6576)
		(end 228.488595 119.7976)
		(width 0.508)
		(layer "F.Cu")
		(net "+5.0V")
	)
	(segment
		(start 152.988595 144.1786)
		(end 153.113095 144.0541)
		(width 0.508)
		(layer "F.Cu")
		(net "+5.0V")
	)
	(segment
		(start 232.188595 115.2786)
		(end 232.292595 115.1746)
		(width 0.508)
		(layer "F.Cu")
		(net "+5.0V")
	)
	(segment
		(start 125.690595 68.9736)
		(end 126.033595 69.3166)
		(width 0.508)
		(layer "F.Cu")
		(net "+5.0V")
	)
	(segment
		(start 128.626595 69.3166)
		(end 128.969595 69.6596)
		(width 0.508)
		(layer "F.Cu")
		(net "+5.0V")
	)
	(segment
		(start 149.592365 108.55983)
		(end 151.235745 108.55983)
		(width 0.254)
		(layer "F.Cu")
		(net "+5.0V")
	)
	(segment
		(start 228.348595 116.8636)
		(end 228.348595 115.4666)
		(width 0.508)
		(layer "F.Cu")
		(net "+5.0V")
	)
	(segment
		(start 125.540595 68.9736)
		(end 125.690595 68.9736)
		(width 0.508)
		(layer "F.Cu")
		(net "+5.0V")
	)
	(segment
		(start 232.292595 115.1746)
		(end 232.292595 114.4506)
		(width 0.508)
		(layer "F.Cu")
		(net "+5.0V")
	)
	(segment
		(start 228.348595 118.1336)
		(end 228.348595 116.8636)
		(width 0.508)
		(layer "F.Cu")
		(net "+5.0V")
	)
	(segment
		(start 159.573665 140.04353)
		(end 159.573665 137.95689)
		(width 0.2032)
		(layer "F.Cu")
		(net "+5.0V")
	)
	(segment
		(start 106.951995 55.6962)
		(end 107.608195 55.6962)
		(width 0.254)
		(layer "F.Cu")
		(net "+5.0V")
	)
	(segment
		(start 228.675595 125.9416)
		(end 228.675595 124.4836)
		(width 0.508)
		(layer "F.Cu")
		(net "+5.0V")
	)
	(segment
		(start 100.762995 52.6652)
		(end 101.359795 53.262)
		(width 0.254)
		(layer "F.Cu")
		(net "+5.0V")
	)
	(segment
		(start 147.185965 108.55983)
		(end 148.834425 108.55983)
		(width 0.254)
		(layer "F.Cu")
		(net "+5.0V")
	)
	(segment
		(start 148.781595 108.9388)
		(end 149.213395 108.9388)
		(width 0.254)
		(layer "F.Cu")
		(net "+5.0V")
	)
	(segment
		(start 153.113095 142.2611)
		(end 153.237595 142.1366)
		(width 0.508)
		(layer "F.Cu")
		(net "+5.0V")
	)
	(segment
		(start 128.969595 70.0006)
		(end 128.969595 69.6596)
		(width 0.508)
		(layer "F.Cu")
		(net "+5.0V")
	)
	(segment
		(start 148.834425 108.55983)
		(end 149.213395 108.9388)
		(width 0.254)
		(layer "F.Cu")
		(net "+5.0V")
	)
	(segment
		(start 149.213395 108.9388)
		(end 149.592365 108.55983)
		(width 0.254)
		(layer "F.Cu")
		(net "+5.0V")
	)
	(segment
		(start 147.185965 109.05996)
		(end 148.660435 109.05996)
		(width 0.254)
		(layer "F.Cu")
		(net "+5.0V")
	)
	(segment
		(start 149.918755 109.05996)
		(end 151.235745 109.05996)
		(width 0.254)
		(layer "F.Cu")
		(net "+5.0V")
	)
	(segment
		(start 147.185965 108.05996)
		(end 148.969555 108.05996)
		(width 0.254)
		(layer "F.Cu")
		(net "+5.0V")
	)
	(segment
		(start 106.069795 51.9666)
		(end 106.069795 51.82419)
		(width 0.254)
		(layer "F.Cu")
		(net "+5.0V")
	)
	(segment
		(start 232.148575 115.31862)
		(end 232.148585 115.31861)
		(width 0.508)
		(layer "F.Cu")
		(net "+5.0V")
	)
	(segment
		(start 219.012595 125.6526)
		(end 219.012595 123.4916)
		(width 0.508)
		(layer "F.Cu")
		(net "+5.0V")
	)
	(segment
		(start 232.148585 115.31861)
		(end 232.188595 115.2786)
		(width 0.508)
		(layer "F.Cu")
		(net "+5.0V")
	)
	(segment
		(start 98.057795 53.1604)
		(end 99.175395 52.0428)
		(width 0.254)
		(layer "F.Cu")
		(net "+5.0V")
	)
	(segment
		(start 122.111595 68.0646)
		(end 124.481595 68.0646)
		(width 0.508)
		(layer "F.Cu")
		(net "+5.0V")
	)
	(segment
		(start 148.660435 109.05996)
		(end 148.781595 108.9388)
		(width 0.254)
		(layer "F.Cu")
		(net "+5.0V")
	)
	(segment
		(start 107.608195 52.4492)
		(end 107.608195 52.4492)
		(width 0.254)
		(layer "F.Cu")
		(net "+5.0V")
	)
	(segment
		(start 227.838595 126.7786)
		(end 228.675595 125.9416)
		(width 0.508)
		(layer "F.Cu")
		(net "+5.0V")
	)
	(segment
		(start 149.213395 108.3038)
		(end 149.457235 108.05996)
		(width 0.254)
		(layer "F.Cu")
		(net "+5.0V")
	)
	(segment
		(start 105.576195 53.262)
		(end 106.069795 52.7684)
		(width 0.254)
		(layer "F.Cu")
		(net "+5.0V")
	)
	(segment
		(start 220.138595 126.7786)
		(end 227.838595 126.7786)
		(width 0.508)
		(layer "F.Cu")
		(net "+5.0V")
	)
	(segment
		(start 106.198495 56.4497)
		(end 106.951995 55.6962)
		(width 0.254)
		(layer "F.Cu")
		(net "+5.0V")
	)
	(segment
		(start 106.219795 51.9666)
		(end 107.125595 51.9666)
		(width 0.254)
		(layer "F.Cu")
		(net "+5.0V")
	)
	(segment
		(start 105.380195 56.4497)
		(end 106.198495 56.4497)
		(width 0.254)
		(layer "F.Cu")
		(net "+5.0V")
	)
	(segment
		(start 148.469425 107.55983)
		(end 148.969555 108.05996)
		(width 0.254)
		(layer "F.Cu")
		(net "+5.0V")
	)
	(segment
		(start 153.113095 144.0541)
		(end 153.113095 142.2611)
		(width 0.508)
		(layer "F.Cu")
		(net "+5.0V")
	)
	(segment
		(start 232.188595 118.6786)
		(end 232.188595 115.2786)
		(width 0.508)
		(layer "F.Cu")
		(net "+5.0V")
	)
	(segment
		(start 100.762995 52.6652)
		(end 100.762995 52.0428)
		(width 0.254)
		(layer "F.Cu")
		(net "+5.0V")
	)
	(segment
		(start 157.438595 142.1786)
		(end 159.573665 140.04353)
		(width 0.2032)
		(layer "F.Cu")
		(net "+5.0V")
	)
	(segment
		(start 124.481595 68.0646)
		(end 125.390595 68.9736)
		(width 0.508)
		(layer "F.Cu")
		(net "+5.0V")
	)
	(segment
		(start 107.608195 55.6962)
		(end 107.608195 52.4492)
		(width 0.254)
		(layer "F.Cu")
		(net "+5.0V")
	)
	(segment
		(start 125.390595 68.9736)
		(end 125.540595 68.9736)
		(width 0.508)
		(layer "F.Cu")
		(net "+5.0V")
	)
	(segment
		(start 228.348595 115.4666)
		(end 231.790175 115.4666)
		(width 0.508)
		(layer "F.Cu")
		(net "+5.0V")
	)
	(segment
		(start 149.457235 108.05996)
		(end 149.957365 107.55983)
		(width 0.254)
		(layer "F.Cu")
		(net "+5.0V")
	)
	(segment
		(start 149.957365 107.55983)
		(end 151.235745 107.55983)
		(width 0.254)
		(layer "F.Cu")
		(net "+5.0V")
	)
	(segment
		(start 147.185965 107.55983)
		(end 148.469425 107.55983)
		(width 0.254)
		(layer "F.Cu")
		(net "+5.0V")
	)
	(segment
		(start 126.033595 69.3166)
		(end 128.626595 69.3166)
		(width 0.508)
		(layer "F.Cu")
		(net "+5.0V")
	)
	(segment
		(start 228.488595 121.5026)
		(end 228.675595 121.6896)
		(width 0.508)
		(layer "F.Cu")
		(net "+5.0V")
	)
	(segment
		(start 166.523595 64.7046)
		(end 166.561595 64.6666)
		(width 0.508)
		(layer "F.Cu")
		(net "+5.0V")
	)
	(segment
		(start 219.012595 125.6526)
		(end 220.138595 126.7786)
		(width 0.508)
		(layer "F.Cu")
		(net "+5.0V")
	)
	(segment
		(start 107.125595 51.9666)
		(end 107.608195 52.4492)
		(width 0.254)
		(layer "F.Cu")
		(net "+5.0V")
	)
	(segment
		(start 149.797595 108.9388)
		(end 149.918755 109.05996)
		(width 0.254)
		(layer "F.Cu")
		(net "+5.0V")
	)
	(segment
		(start 106.069795 52.7684)
		(end 106.069795 51.9666)
		(width 0.254)
		(layer "F.Cu")
		(net "+5.0V")
	)
	(segment
		(start 149.213395 108.9388)
		(end 149.797595 108.9388)
		(width 0.254)
		(layer "F.Cu")
		(net "+5.0V")
	)
	(segment
		(start 153.429595 142.1786)
		(end 157.438595 142.1786)
		(width 0.2032)
		(layer "F.Cu")
		(net "+5.0V")
	)
	(segment
		(start 106.069795 51.82419)
		(end 106.517795 51.37619)
		(width 0.254)
		(layer "F.Cu")
		(net "+5.0V")
	)
	(segment
		(start 228.675595 124.4836)
		(end 228.675595 121.6896)
		(width 0.508)
		(layer "F.Cu")
		(net "+5.0V")
	)
	(segment
		(start 228.488595 121.5026)
		(end 228.488595 119.7976)
		(width 0.508)
		(layer "F.Cu")
		(net "+5.0V")
	)
	(segment
		(start 148.969555 108.05996)
		(end 149.213395 108.3038)
		(width 0.254)
		(layer "F.Cu")
		(net "+5.0V")
	)
	(segment
		(start 99.175395 52.0428)
		(end 100.762995 52.0428)
		(width 0.254)
		(layer "F.Cu")
		(net "+5.0V")
	)
	(segment
		(start 228.348595 119.6576)
		(end 228.348595 118.1336)
		(width 0.508)
		(layer "F.Cu")
		(net "+5.0V")
	)
	(via
		(at 166.561595 64.6666)
		(size 0.4064)
		(drill 0.2032)
		(layers "F.Cu" "B.Cu")
		(net "+5.0V")
	)
	(via
		(at 128.969595 70.0006)
		(size 0.4064)
		(drill 0.2032)
		(layers "F.Cu" "B.Cu")
		(net "+5.0V")
	)
	(via
		(at 232.188595 118.6786)
		(size 0.8128)
		(drill 0.4064)
		(layers "F.Cu" "B.Cu")
		(net "+5.0V")
	)
	(via
		(at 98.057795 53.1604)
		(size 0.4064)
		(drill 0.2032)
		(layers "F.Cu" "B.Cu")
		(net "+5.0V")
	)
	(via
		(at 149.213395 108.9388)
		(size 0.4064)
		(drill 0.2032)
		(layers "F.Cu" "B.Cu")
		(net "+5.0V")
	)
	(via
		(at 149.213395 108.3038)
		(size 0.4064)
		(drill 0.2032)
		(layers "F.Cu" "B.Cu")
		(net "+5.0V")
	)
	(arc
		(start 232.148577 115.318617)
		(mid 231.984051 115.428149)
		(end 231.790175 115.4666)
		(width 0.508)
		(layer "F.Cu")
		(net "+5.0V")
	)
	(segment
		(start 138.678195 97.44425)
		(end 138.678195 79.7932)
		(width 0.508)
		(layer "B.Cu")
		(net "+5.0V")
	)
	(segment
		(start 125.353995 83.2904)
		(end 125.362795 83.2992)
		(width 0.508)
		(layer "B.Cu")
		(net "+5.0V")
	)
	(segment
		(start 149.943135 133.64614)
		(end 149.943135 124.18651)
		(width 0.508)
		(layer "B.Cu")
		(net "+5.0V")
	)
	(segment
		(start 148.908595 116.40203)
		(end 150.940595 114.37003)
		(width 0.508)
		(layer "B.Cu")
		(net "+5.0V")
	)
	(segment
		(start 122.238595 83.2904)
		(end 125.353995 83.2904)
		(width 0.508)
		(layer "B.Cu")
		(net "+5.0V")
	)
	(segment
		(start 125.502595 83.439)
		(end 127.369395 83.439)
		(width 0.508)
		(layer "B.Cu")
		(net "+5.0V")
	)
	(segment
		(start 168.717525 129.56667)
		(end 221.300535 129.56667)
		(width 0.508)
		(layer "B.Cu")
		(net "+5.0V")
	)
	(segment
		(start 148.908595 123.15197)
		(end 148.908595 116.40203)
		(width 0.508)
		(layer "B.Cu")
		(net "+5.0V")
	)
	(segment
		(start 148.908595 123.15197)
		(end 149.943135 124.18651)
		(width 0.508)
		(layer "B.Cu")
		(net "+5.0V")
	)
	(segment
		(start 125.362795 83.2992)
		(end 125.502595 83.439)
		(width 0.508)
		(layer "B.Cu")
		(net "+5.0V")
	)
	(segment
		(start 157.290595 140.9936)
		(end 168.717525 129.56667)
		(width 0.508)
		(layer "B.Cu")
		(net "+5.0V")
	)
	(segment
		(start 128.969595 70.0846)
		(end 138.678195 79.7932)
		(width 0.508)
		(layer "B.Cu")
		(net "+5.0V")
	)
	(segment
		(start 149.943135 133.64614)
		(end 157.290595 140.9936)
		(width 0.508)
		(layer "B.Cu")
		(net "+5.0V")
	)
	(segment
		(start 144.057195 103.3762)
		(end 144.057195 102.82325)
		(width 0.508)
		(layer "B.Cu")
		(net "+5.0V")
	)
	(segment
		(start 149.213395 108.9388)
		(end 149.213395 108.3038)
		(width 0.508)
		(layer "B.Cu")
		(net "+5.0V")
	)
	(segment
		(start 149.441995 112.87143)
		(end 149.441995 109.73205)
		(width 0.508)
		(layer "B.Cu")
		(net "+5.0V")
	)
	(segment
		(start 149.213395 109.50345)
		(end 149.213395 108.9388)
		(width 0.508)
		(layer "B.Cu")
		(net "+5.0V")
	)
	(segment
		(start 144.057195 103.3762)
		(end 148.654595 107.9736)
		(width 0.508)
		(layer "B.Cu")
		(net "+5.0V")
	)
	(segment
		(start 149.441995 112.87143)
		(end 150.940595 114.37003)
		(width 0.508)
		(layer "B.Cu")
		(net "+5.0V")
	)
	(segment
		(start 128.969595 70.0846)
		(end 128.969595 70.0006)
		(width 0.508)
		(layer "B.Cu")
		(net "+5.0V")
	)
	(segment
		(start 221.300535 129.56667)
		(end 232.188595 118.6786)
		(width 0.508)
		(layer "B.Cu")
		(net "+5.0V")
	)
	(segment
		(start 149.213395 109.50345)
		(end 149.441995 109.73205)
		(width 0.508)
		(layer "B.Cu")
		(net "+5.0V")
	)
	(segment
		(start 161.227595 70.0006)
		(end 166.561595 64.6666)
		(width 0.508)
		(layer "B.Cu")
		(net "+5.0V")
	)
	(segment
		(start 138.678195 97.44425)
		(end 144.057195 102.82325)
		(width 0.508)
		(layer "B.Cu")
		(net "+5.0V")
	)
	(segment
		(start 128.969595 70.0006)
		(end 161.227595 70.0006)
		(width 0.508)
		(layer "B.Cu")
		(net "+5.0V")
	)
	(segment
		(start 143.574595 67.4446)
		(end 145.488595 67.4446)
		(width 0.2032)
		(layer "F.Cu")
		(net "FPGA_TDI")
	)
	(segment
		(start 145.488595 67.4446)
		(end 146.497595 67.4446)
		(width 0.2032)
		(layer "F.Cu")
		(net "FPGA_TDI")
	)
	(segment
		(start 145.479595 68.2226)
		(end 145.488595 68.2136)
		(width 0.2032)
		(layer "F.Cu")
		(net "FPGA_TDI")
	)
	(segment
		(start 145.488595 68.2136)
		(end 145.488595 67.4446)
		(width 0.2032)
		(layer "F.Cu")
		(net "FPGA_TDI")
	)
	(segment
		(start 146.474195 67.918)
		(end 146.622595 67.7696)
		(width 0.2032)
		(layer "F.Cu")
		(net "FPGA_TDI")
	)
	(segment
		(start 98.320935 108.05894)
		(end 99.563255 108.05894)
		(width 0.2032)
		(layer "F.Cu")
		(net "FPGA_TDI")
	)
	(segment
		(start 146.497595 67.4446)
		(end 146.622595 67.5696)
		(width 0.2032)
		(layer "F.Cu")
		(net "FPGA_TDI")
	)
	(segment
		(start 146.622595 67.7696)
		(end 146.622595 67.5696)
		(width 0.2032)
		(layer "F.Cu")
		(net "FPGA_TDI")
	)
	(via
		(at 145.479595 68.2226)
		(size 0.4064)
		(drill 0.2032)
		(layers "F.Cu" "B.Cu")
		(net "FPGA_TDI")
	)
	(via
		(at 98.320935 108.05894)
		(size 0.4064)
		(drill 0.2032)
		(layers "F.Cu" "B.Cu")
		(net "FPGA_TDI")
	)
	(via
		(at 97.854595 68.6036)
		(size 0.4064)
		(drill 0.2032)
		(layers "F.Cu" "B.Cu")
		(net "FPGA_TDI")
	)
	(segment
		(start 125.853875 67.9734)
		(end 126.103085 68.2226)
		(width 0.2032)
		(layer "In2.Cu")
		(net "FPGA_TDI")
	)
	(segment
		(start 97.854595 68.6036)
		(end 106.009495 68.6036)
		(width 0.2032)
		(layer "In2.Cu")
		(net "FPGA_TDI")
	)
	(segment
		(start 106.009495 68.6036)
		(end 106.639695 67.9734)
		(width 0.2032)
		(layer "In2.Cu")
		(net "FPGA_TDI")
	)
	(segment
		(start 106.639695 67.9734)
		(end 125.853875 67.9734)
		(width 0.2032)
		(layer "In2.Cu")
		(net "FPGA_TDI")
	)
	(segment
		(start 126.103085 68.2226)
		(end 145.479595 68.2226)
		(width 0.2032)
		(layer "In2.Cu")
		(net "FPGA_TDI")
	)
	(segment
		(start 97.854595 97.96052)
		(end 97.854595 97.96052)
		(width 0.2032)
		(layer "In3.Cu")
		(net "FPGA_TDI")
	)
	(segment
		(start 97.854595 99.41955)
		(end 97.854595 97.96052)
		(width 0.2032)
		(layer "In3.Cu")
		(net "FPGA_TDI")
	)
	(segment
		(start 97.854595 99.41955)
		(end 98.320935 99.88589)
		(width 0.2032)
		(layer "In3.Cu")
		(net "FPGA_TDI")
	)
	(segment
		(start 97.854595 97.96052)
		(end 97.854595 68.6036)
		(width 0.2032)
		(layer "In3.Cu")
		(net "FPGA_TDI")
	)
	(segment
		(start 98.320935 108.05894)
		(end 98.320935 99.88589)
		(width 0.2032)
		(layer "In3.Cu")
		(net "FPGA_TDI")
	)
	(segment
		(start 97.854595 68.6036)
		(end 97.854595 68.6036)
		(width 0.2032)
		(layer "In3.Cu")
		(net "FPGA_TDI")
	)
	(zone
		(net "+5.0V")
		(layer "F.Cu")
		(hatch edge 0.5)
		(connect_pads yes
			(clearance 0.5)
		)
		(min_thickness 0.25)
		(fill yes
			(thermal_gap 0.2032)
			(thermal_bridge_width 0.254)
			(island_removal_mode 0)
		)
		(polygon
			(pts
				(xy 234.838595 113.6786) (xy 229.238595 113.6786) (xy 227.738595 115.1786) (xy 227.738595 127.6786)
				(xy 229.338595 127.6786) (xy 234.838595 122.1786)
			)
		)
	)
	(zone
		(net "+3.3V")
		(layer "F.Cu")
		(hatch edge 0.5)
		(priority 2)
		(connect_pads yes
			(clearance 0.5)
		)
		(min_thickness 0.25)
		(fill yes
			(thermal_gap 0.2032)
			(thermal_bridge_width 0.254)
			(island_removal_mode 0)
		)
		(polygon
			(pts
				(xy 231.338595 85.1786) (xy 222.588595 85.1786) (xy 222.588595 89.9286) (xy 222.338595 90.1786)
				(xy 213.588595 90.1786) (xy 213.588595 97.6786) (xy 213.838595 97.4286) (xy 219.338595 97.4286)
				(xy 219.338595 92.4286) (xy 219.838595 91.9286) (xy 231.338595 91.9286)
			)
		)
	)
	(zone
		(net "NetD2_2")
		(layer "F.Cu")
		(hatch edge 0.5)
		(priority 6)
		(connect_pads yes
			(clearance 0.5)
		)
		(min_thickness 0.25)
		(fill yes
			(thermal_gap 0.2032)
			(thermal_bridge_width 0.254)
			(island_removal_mode 0)
		)
		(polygon
			(pts
				(xy 236.338595 61.6786) (xy 222.838595 61.6786) (xy 222.838595 71.6786) (xy 236.338595 71.6786)
			)
		)
	)
	(zone
		(net "+3.3V_CLEAN")
		(layer "F.Cu")
		(hatch edge 0.5)
		(priority 18)
		(connect_pads yes
			(clearance 0.5)
		)
		(min_thickness 0.25)
		(fill yes
			(thermal_gap 0.2032)
			(thermal_bridge_width 0.254)
			(island_removal_mode 0)
		)
		(polygon
			(pts
				(xy 175.857995 78.1286) (xy 175.857995 88.7966) (xy 172.860795 91.7938) (xy 130.315795 91.7938)
				(xy 126.378805 87.85679) (xy 126.378795 76.122) (xy 132.119195 70.3816) (xy 168.110985 70.3816)
			)
		)
	)
	(zone
		(layer "F.Cu")
		(hatch edge 0.5)
		(connect_pads
			(clearance 0)
		)
		(min_thickness 0.25)
		(keepout
			(tracks not_allowed)
			(vias not_allowed)
			(pads not_allowed)
			(copperpour not_allowed)
			(footprints allowed)
		)
		(placement
			(enabled no)
			(sheetname "")
		)
		(fill
			(thermal_gap 0.5)
			(thermal_bridge_width 0.5)
			(island_removal_mode 0)
		)
		(polygon
			(pts
				(arc
					(start 58.438215 156.0786)
					(mid 58.452971 156.114224)
					(end 58.488595 156.12898)
				)
				(arc
					(start 73.488595 156.12898)
					(mid 73.524219 156.114224)
					(end 73.538975 156.0786)
				)
				(xy 73.538975 147.87898) (xy 91.788215 147.87898)
				(arc
					(start 91.788215 152.6286)
					(mid 91.802971 152.664224)
					(end 91.838595 152.67898)
				)
				(arc
					(start 99.838595 152.67898)
					(mid 99.874219 152.664224)
					(end 99.888975 152.6286)
				)
				(xy 99.888972 152.628094) (xy 99.888975 152.62809)
				(arc
					(start 99.888975 149.6536)
					(mid 101.663595 147.87898)
					(end 103.438215 149.6536)
				)
				(arc
					(start 103.438215 149.6536)
					(mid 103.488595 149.70398)
					(end 103.538975 149.6536)
				)
				(arc
					(start 103.538975 146.8286)
					(mid 103.524219 146.792976)
					(end 103.488595 146.77822)
				)
				(arc
					(start 58.488595 146.77822)
					(mid 58.452971 146.792976)
					(end 58.438215 146.8286)
				)
			)
		)
	)
	(zone
		(layers "F.Cu" "B.Cu" "In1.Cu" "In2.Cu" "In3.Cu" "In4.Cu")
		(hatch edge 0.5)
		(connect_pads
			(clearance 0)
		)
		(min_thickness 0.25)
		(keepout
			(tracks not_allowed)
			(vias not_allowed)
			(pads not_allowed)
			(copperpour not_allowed)
			(footprints allowed)
		)
		(placement
			(enabled no)
			(sheetname "")
		)
		(fill
			(thermal_gap 0.5)
			(thermal_bridge_width 0.5)
			(island_removal_mode 0)
		)
		(polygon
			(pts
				(xy 91.838595 156.0786) (xy 99.838595 156.0786) (xy 99.838595 152.6286) (xy 91.838595 152.6286)
			)
		)
	)
	(zone
		(net "+12V")
		(layer "B.Cu")
		(hatch edge 0.5)
		(priority 16)
		(connect_pads yes
			(clearance 0.5)
		)
		(min_thickness 0.25)
		(fill yes
			(thermal_gap 0.2032)
			(thermal_bridge_width 0.254)
			(island_removal_mode 0)
		)
		(polygon
			(pts
				(xy 210.630595 66.3176) (xy 207.836595 69.1116) (xy 207.836595 72.9216) (xy 219.393595 84.4786)
				(xy 219.393595 105.8146) (xy 221.298595 107.7196) (xy 231.712595 107.7196) (xy 233.998595 110.0056)
				(xy 233.998595 118.7686) (xy 225.870595 126.8966) (xy 225.870595 129.0556) (xy 227.394595 130.5796)
				(xy 230.696595 130.5796) (xy 238.513595 122.7626) (xy 238.513595 68.0386) (xy 236.919595 66.4446)
			)
		)
	)
	(zone
		(net "+5.0V")
		(layer "B.Cu")
		(hatch edge 0.5)
		(priority 14)
		(connect_pads yes
			(clearance 0.5)
		)
		(min_thickness 0.25)
		(fill yes
			(thermal_gap 0.2032)
			(thermal_bridge_width 0.254)
			(island_removal_mode 0)
		)
		(polygon
			(pts
				(xy 234.633595 113.0536) (xy 164.021595 113.0536) (xy 155.639595 104.6716) (xy 155.639595 80.6686)
				(xy 168.974595 67.3336) (xy 168.974595 63.0156) (xy 168.974595 50.3156) (xy 92.927005 50.3156) (xy 92.927005 83.36099)
				(xy 154.623595 145.0576) (xy 219.266595 145.0576) (xy 234.633595 129.6906)
			)
		)
	)
	(zone
		(layer "B.Cu")
		(hatch edge 0.5)
		(connect_pads
			(clearance 0)
		)
		(min_thickness 0.25)
		(keepout
			(tracks not_allowed)
			(vias not_allowed)
			(pads not_allowed)
			(copperpour not_allowed)
			(footprints allowed)
		)
		(placement
			(enabled no)
			(sheetname "")
		)
		(fill
			(thermal_gap 0.5)
			(thermal_bridge_width 0.5)
			(island_removal_mode 0)
		)
		(polygon
			(pts
				(arc
					(start 58.438215 156.0786)
					(mid 58.452971 156.114224)
					(end 58.488595 156.12898)
				)
				(arc
					(start 73.488595 156.12898)
					(mid 73.524219 156.114224)
					(end 73.538975 156.0786)
				)
				(xy 73.538975 147.87898) (xy 91.788215 147.87898)
				(arc
					(start 91.788215 152.6286)
					(mid 91.802971 152.664224)
					(end 91.838595 152.67898)
				)
				(arc
					(start 99.838595 152.67898)
					(mid 99.874219 152.664224)
					(end 99.888975 152.6286)
				)
				(xy 99.888972 152.628094) (xy 99.888975 152.62809)
				(arc
					(start 99.888975 149.6536)
					(mid 101.663595 147.87898)
					(end 103.438215 149.6536)
				)
				(arc
					(start 103.438215 149.6536)
					(mid 103.488595 149.70398)
					(end 103.538975 149.6536)
				)
				(arc
					(start 103.538975 146.8286)
					(mid 103.524219 146.792976)
					(end 103.488595 146.77822)
				)
				(arc
					(start 58.488595 146.77822)
					(mid 58.452971 146.792976)
					(end 58.438215 146.8286)
				)
			)
		)
	)
	(zone
		(net "+3.3V")
		(layer "B.Cu")
		(hatch edge 0.5)
		(priority 15)
		(connect_pads yes
			(clearance 0.5)
		)
		(min_thickness 0.25)
		(fill yes
			(thermal_gap 0.2032)
			(thermal_bridge_width 0.254)
			(island_removal_mode 0)
		)
		(polygon
			(pts
				(xy 223.711595 95.1466) (xy 218.631595 100.2266) (xy 176.340595 100.2266) (xy 168.974595 92.8606)
				(xy 168.974595 64.5396) (xy 164.783595 60.3486) (xy 161.735595 60.3486) (xy 155.131595 66.9526)
				(xy 127.318595 66.9526) (xy 118.174595 76.0966) (xy 118.174595 91.5398) (xy 109.665595 91.5398)
				(xy 109.665595 56.0306) (xy 109.665595 50.6966) (xy 219.266595 50.6966) (xy 223.711595 55.1416)
			)
		)
	)
	(zone
		(net "GND")
		(layer "In1.Cu")
		(hatch edge 0.5)
		(priority 10)
		(connect_pads yes
			(clearance 0.5)
		)
		(min_thickness 0.25)
		(fill yes
			(thermal_gap 0.2032)
			(thermal_bridge_width 0.254)
			(island_removal_mode 0)
		)
		(polygon
			(pts
				(xy 73.267395 155.8018) (xy 73.267395 147.5722) (xy 92.063395 147.5722) (xy 92.063395 155.8018)
				(xy 99.607195 155.8018) (xy 99.607195 148.639) (xy 100.750195 147.496) (xy 102.578995 147.496) (xy 103.747395 148.6644)
				(xy 103.747395 160.0436) (xy 104.026795 160.323) (xy 114.135995 160.323) (xy 114.440795 160.0182)
				(xy 114.440795 152.6014) (xy 115.253595 151.7886) (xy 115.964795 151.7886) (xy 116.777595 152.6014)
				(xy 116.777595 160.0436) (xy 117.107795 160.3738) (xy 137.249995 160.3738) (xy 137.605595 160.0182)
				(xy 137.605595 147.6484) (xy 238.288585 147.6484) (xy 238.288595 49.6786) (xy 58.994585 49.67861)
				(xy 58.687795 49.9854) (xy 58.687795 155.8018)
			)
		)
	)
	(zone
		(layer "In1.Cu")
		(hatch edge 0.5)
		(connect_pads
			(clearance 0)
		)
		(min_thickness 0.25)
		(keepout
			(tracks allowed)
			(vias allowed)
			(pads allowed)
			(copperpour not_allowed)
			(footprints allowed)
		)
		(placement
			(enabled no)
			(sheetname "")
		)
		(fill
			(thermal_gap 0.5)
			(thermal_bridge_width 0.5)
			(island_removal_mode 0)
		)
		(polygon
			(pts
				(xy 103.338595 160.9286) (xy 103.338595 154.8536) (xy 138.088595 154.8536) (xy 138.088595 161.1786)
			)
		)
	)
	(zone
		(layer "In4.Cu")
		(hatch edge 0.5)
		(connect_pads
			(clearance 0)
		)
		(min_thickness 0.25)
		(keepout
			(tracks allowed)
			(vias allowed)
			(pads allowed)
			(copperpour not_allowed)
			(footprints allowed)
		)
		(placement
			(enabled no)
			(sheetname "")
		)
		(fill
			(thermal_gap 0.5)
			(thermal_bridge_width 0.5)
			(island_removal_mode 0)
		)
		(polygon
			(pts
				(xy 103.338595 160.9286) (xy 103.338595 154.8536) (xy 138.088595 154.8536) (xy 138.088595 161.1786)
			)
		)
	)
	(zone
		(net "GND")
		(layer "In4.Cu")
		(hatch edge 0.5)
		(priority 8)
		(connect_pads yes
			(clearance 0.5)
		)
		(min_thickness 0.25)
		(fill yes
			(thermal_gap 0.2032)
			(thermal_bridge_width 0.254)
			(island_removal_mode 0)
		)
		(polygon
			(pts
				(xy 73.142395 155.9016) (xy 73.142395 147.672) (xy 91.938395 147.672) (xy 91.938395 155.9016) (xy 99.482195 155.9016)
				(xy 99.482195 148.7388) (xy 100.625195 147.5958) (xy 102.453995 147.5958) (xy 103.622395 148.7642)
				(xy 103.622395 160.1434) (xy 103.901795 160.4228) (xy 114.010995 160.4228) (xy 114.315795 160.118)
				(xy 114.315795 152.7012) (xy 115.128595 151.8884) (xy 115.839795 151.8884) (xy 116.652595 152.7012)
				(xy 116.652595 160.1434) (xy 116.982795 160.4736) (xy 137.124995 160.4736) (xy 137.480595 160.118)
				(xy 137.480595 147.7482) (xy 238.388595 147.7482) (xy 238.388595 50.009) (xy 58.638995 50.009) (xy 58.562795 50.0852)
				(xy 58.562795 155.9016)
			)
		)
	)
)
